A!FUNC_LOGICAL_PATH!COMP_DEVICE_TYPE!REFDES!FUNC_PRIM_FILE!COMP_PARENT_PPT!COMP_PARENT_PPT_PART!COMP_PARENT_PART_TYPE!FUNC_SCH_SIZE!FUNC_HAS_FIXED_SIZE!FUNC_DES!FUNC_GROUP!FUNC_ROOM!FUNC_TERM_IDENT!
J!K:/<user>/emsd/Crescent_City/baseboard_fab2/worklib/baseboard_fab2/physical/crescent_city_fab2_2v290_20151002_C_gridout2.brd!Fri Oct 02 10:47:59 2015!-30224.80!-14061.09!740148.33!322724.71!0.01!mils!BASEBOARD_FAB2!89.440157 mil!14!UP TO DATE!
S!@baseboard_fab2_lib.baseboard_fab2(sch_1):page113_i127@mstr_ttl.\74cbtlv1g125\(chips)!74CBTLV1G125_SMLF-IC,C88177-00A!U1M6!//jf4cfls225.pdx.intel.com/apd_proj/ppg_lib/epg_masterlib/logical/mstr_ttl/74cbtlv1g125/chips/chips.prt!74CBTLV1G125!74CBTLV1G125_SMLF-IC,C88177-001!74CBTLV1G125!!!F4206!!DEBUG!!
S!@baseboard_fab2_lib.baseboard_fab2(sch_1):page113_i206@mstr_ttl.\74cbtlv1g125\(chips)!74CBTLV1G125_SMLF-IC,C88177-00A!U4R1!//jf4cfls225.pdx.intel.com/apd_proj/ppg_lib/epg_masterlib/logical/mstr_ttl/74cbtlv1g125/chips/chips.prt!74CBTLV1G125!74CBTLV1G125_SMLF-IC,C88177-001!74CBTLV1G125!!!F4205!!DEBUG!!
S!@baseboard_fab2_lib.baseboard_fab2(sch_1):page113_i190@mstr_ttl.\74cbtlv1g125\(chips)!74CBTLV1G125_SMLF-IC,C88177-00A!U6M1!//jf4cfls225.pdx.intel.com/apd_proj/ppg_lib/epg_masterlib/logical/mstr_ttl/74cbtlv1g125/chips/chips.prt!74CBTLV1G125!74CBTLV1G125_SMLF-IC,C88177-001!74CBTLV1G125!!!F4204!!DEBUG!!
S!@baseboard_fab2_lib.baseboard_fab2(sch_1):page118_i142@mstr_ttl.\74cbtlv1g125\(chips)!74CBTLV1G125_SMLF-IC,C88177-00A!U7D1!//jf4cfls225.pdx.intel.com/apd_proj/ppg_lib/epg_masterlib/logical/mstr_ttl/74cbtlv1g125/chips/chips.prt!74CBTLV1G125!74CBTLV1G125_SMLF-IC,C88177-001!74CBTLV1G125!!!F4203!!DEBUG!!
S!@baseboard_fab2_lib.baseboard_fab2(sch_1):page113_i196@mstr_ttl.\74cbtlv1g125\(chips)!74CBTLV1G125_SMLF-IC,C88177-00A!U1M5!//jf4cfls225.pdx.intel.com/apd_proj/ppg_lib/epg_masterlib/logical/mstr_ttl/74cbtlv1g125/chips/chips.prt!74CBTLV1G125!74CBTLV1G125_SMLF-IC,C88177-001!74CBTLV1G125!!!F4202!!DEBUG!!
S!@baseboard_fab2_lib.baseboard_fab2(sch_1):page113_i185@mstr_ttl.\74cbtlv1g125\(chips)!74CBTLV1G125_SMLF-IC,C88177-00A!U9A5!//jf4cfls225.pdx.intel.com/apd_proj/ppg_lib/epg_masterlib/logical/mstr_ttl/74cbtlv1g125/chips/chips.prt!74CBTLV1G125!74CBTLV1G125_SMLF-IC,C88177-001!74CBTLV1G125!!!F4201!!DEBUG!!
S!@baseboard_fab2_lib.baseboard_fab2(sch_1):page112_i127@mstr_ttl.\74cbtlv1g125\(chips)!74CBTLV1G125_SMLF-IC,C88177-00A!U1M4!//jf4cfls225.pdx.intel.com/apd_proj/ppg_lib/epg_masterlib/logical/mstr_ttl/74cbtlv1g125/chips/chips.prt!74CBTLV1G125!74CBTLV1G125_SMLF-IC,C88177-001!74CBTLV1G125!!!F4200!!DEBUG!!
S!@baseboard_fab2_lib.baseboard_fab2(sch_1):page113_i107@mstr_analog.nc7sb3157(chips)!NC7SB3157_SMLF-IC,C99406-001!U1M2!//jf4cfls225.pdx.intel.com/apd_proj/ppg_lib/epg_masterlib/logical/mstr_analog/nc7sb3157/chips/chips.prt!NC7SB3157!NC7SB3157_SMLF-IC,C99406-001!NC7SB3157!!!F2005!!DEBUG!!
S!@baseboard_fab2_lib.baseboard_fab2(sch_1):page112_i40@mstr_analog.nc7sb3157(chips)!NC7SB3157_SMLF-IC,C99406-001!U1M7!//jf4cfls225.pdx.intel.com/apd_proj/ppg_lib/epg_masterlib/logical/mstr_analog/nc7sb3157/chips/chips.prt!NC7SB3157!NC7SB3157_SMLF-IC,C99406-001!NC7SB3157!!!F2004!!DEBUG!!
S!@baseboard_fab2_lib.baseboard_fab2(sch_1):page113_i255@mstr_analog.nc7sb3157(chips)!NC7SB3157_SMLF-IC,C99406-001!U2M1!//jf4cfls225.pdx.intel.com/apd_proj/ppg_lib/epg_masterlib/logical/mstr_analog/nc7sb3157/chips/chips.prt!NC7SB3157!NC7SB3157_SMLF-IC,C99406-001!NC7SB3157!!!F2003!!DEBUG!!
S!@baseboard_fab2_lib.baseboard_fab2(sch_1):page199_i58@mstr_discrete.npn(chips)!NPN_SM-MMBT3904,IC,C52245-001!Q1D3!//jf4cfls225.pdx.intel.com/apd_proj/ppg_lib/epg_masterlib/logical/mstr_discrete/npn/chips/chips.prt!NPN!NPN_SM-MMBT3904,IC,C52245-001!NPN_SM!!!F1994!!HOT_SWAP!!
S!@baseboard_fab2_lib.baseboard_fab2(sch_1):page168_i9@mstr_discrete.npn(chips)!NPN_SM-MMBT3904,IC,C52245-001!Q1L1!//jf4cfls225.pdx.intel.com/apd_proj/ppg_lib/epg_masterlib/logical/mstr_discrete/npn/chips/chips.prt!NPN!NPN_SM-MMBT3904,IC,C52245-001!NPN_SM!!!F1993!!UART_MUX!!
S!@baseboard_fab2_lib.baseboard_fab2(sch_1):page168_i8@mstr_discrete.npn(chips)!NPN_SM-MMBT3904,IC,C52245-001!Q1L3!//jf4cfls225.pdx.intel.com/apd_proj/ppg_lib/epg_masterlib/logical/mstr_discrete/npn/chips/chips.prt!NPN!NPN_SM-MMBT3904,IC,C52245-001!NPN_SM!!!F1992!!UART_MUX!!
S!@baseboard_fab2_lib.baseboard_fab2(sch_1):page157_i330@mstr_discrete.npn(chips)!NPN_SM-MMBT3904,IC,C52245-001!Q2T1!//jf4cfls225.pdx.intel.com/apd_proj/ppg_lib/epg_masterlib/logical/mstr_discrete/npn/chips/chips.prt!NPN!NPN_SM-MMBT3904,IC,C52245-001!NPN_SM!!!F1991!!PROC_SIDEBAND!!
S!@baseboard_fab2_lib.baseboard_fab2(sch_1):page181_i181@mstr_discrete.npn(chips)!NPN_SM-MMBT3904,IC,C52245-001!Q9T1!//jf4cfls225.pdx.intel.com/apd_proj/ppg_lib/epg_masterlib/logical/mstr_discrete/npn/chips/chips.prt!NPN!NPN_SM-MMBT3904,IC,C52245-001!NPN_SM!!!F1990!!SB!!
S!@baseboard_fab2_lib.baseboard_fab2(sch_1):page154_i100@mstr_ttl.ttl1g32_a(chips)!TTL1G32_A_SOT-74LVC1G32,IC,E60B!U2T2!//jf4cfls225.pdx.intel.com/apd_proj/ppg_lib/epg_masterlib/logical/mstr_ttl/ttl1g32_a/chips/chips.prt!TTL1G32_A!TTL1G32_A_SOT-74LVC1G32,IC,E60229-001!TTL1G32_A!!!F23!!SB_BMC_SPI_MUX!!
S!@baseboard_fab2_lib.baseboard_fab2(sch_1):page154_i99@mstr_ttl.ttl1g32_a(chips)!TTL1G32_A_SOT-74LVC1G32,IC,E60B!U2T3!//jf4cfls225.pdx.intel.com/apd_proj/ppg_lib/epg_masterlib/logical/mstr_ttl/ttl1g32_a/chips/chips.prt!TTL1G32_A!TTL1G32_A_SOT-74LVC1G32,IC,E60229-001!TTL1G32_A!!!F22!!SB_BMC_SPI_MUX!!
S!@baseboard_fab2_lib.baseboard_fab2(sch_1):page112_i108(3)@mstr_ttl.ttl3126(chips)!TTL3126_QFNLF-74CBTLV3126,IC,DB!U1L1!//jf4cfls225.pdx.intel.com/apd_proj/ppg_lib/epg_masterlib/logical/mstr_ttl/ttl3126/chips/chips.prt!TTL3126!TTL3126_QFNLF-74CBTLV3126,IC,D18317-001!TTL3126_QFNLF!4!4!F12!!DEBUG!!
S!@baseboard_fab2_lib.baseboard_fab2(sch_1):page112_i108(2)@mstr_ttl.ttl3126(chips)!TTL3126_QFNLF-74CBTLV3126,IC,DB!U1L1!//jf4cfls225.pdx.intel.com/apd_proj/ppg_lib/epg_masterlib/logical/mstr_ttl/ttl3126/chips/chips.prt!TTL3126!TTL3126_QFNLF-74CBTLV3126,IC,D18317-001!TTL3126_QFNLF!4!4!F11!!DEBUG!!
S!@baseboard_fab2_lib.baseboard_fab2(sch_1):page112_i108(1)@mstr_ttl.ttl3126(chips)!TTL3126_QFNLF-74CBTLV3126,IC,DB!U1L1!//jf4cfls225.pdx.intel.com/apd_proj/ppg_lib/epg_masterlib/logical/mstr_ttl/ttl3126/chips/chips.prt!TTL3126!TTL3126_QFNLF-74CBTLV3126,IC,D18317-001!TTL3126_QFNLF!4!4!F10!!DEBUG!!
S!@baseboard_fab2_lib.baseboard_fab2(sch_1):page112_i108(0)@mstr_ttl.ttl3126(chips)!TTL3126_QFNLF-74CBTLV3126,IC,DB!U1L1!//jf4cfls225.pdx.intel.com/apd_proj/ppg_lib/epg_masterlib/logical/mstr_ttl/ttl3126/chips/chips.prt!TTL3126!TTL3126_QFNLF-74CBTLV3126,IC,D18317-001!TTL3126_QFNLF!4!4!F9!!DEBUG!!
S!@baseboard_fab2_lib.baseboard_fab2(sch_1):page112_i109(3)@mstr_ttl.ttl3126(chips)!TTL3126_QFNLF-74CBTLV3126,IC,DB!U1L5!//jf4cfls225.pdx.intel.com/apd_proj/ppg_lib/epg_masterlib/logical/mstr_ttl/ttl3126/chips/chips.prt!TTL3126!TTL3126_QFNLF-74CBTLV3126,IC,D18317-001!TTL3126_QFNLF!4!4!F8!!DEBUG!!
S!@baseboard_fab2_lib.baseboard_fab2(sch_1):page112_i109(2)@mstr_ttl.ttl3126(chips)!TTL3126_QFNLF-74CBTLV3126,IC,DB!U1L5!//jf4cfls225.pdx.intel.com/apd_proj/ppg_lib/epg_masterlib/logical/mstr_ttl/ttl3126/chips/chips.prt!TTL3126!TTL3126_QFNLF-74CBTLV3126,IC,D18317-001!TTL3126_QFNLF!4!4!F7!!DEBUG!!
S!@baseboard_fab2_lib.baseboard_fab2(sch_1):page112_i109(1)@mstr_ttl.ttl3126(chips)!TTL3126_QFNLF-74CBTLV3126,IC,DB!U1L5!//jf4cfls225.pdx.intel.com/apd_proj/ppg_lib/epg_masterlib/logical/mstr_ttl/ttl3126/chips/chips.prt!TTL3126!TTL3126_QFNLF-74CBTLV3126,IC,D18317-001!TTL3126_QFNLF!4!4!F6!!DEBUG!!
S!@baseboard_fab2_lib.baseboard_fab2(sch_1):page112_i109(0)@mstr_ttl.ttl3126(chips)!TTL3126_QFNLF-74CBTLV3126,IC,DB!U1L5!//jf4cfls225.pdx.intel.com/apd_proj/ppg_lib/epg_masterlib/logical/mstr_ttl/ttl3126/chips/chips.prt!TTL3126!TTL3126_QFNLF-74CBTLV3126,IC,D18317-001!TTL3126_QFNLF!4!4!F5!!DEBUG!!
S!@baseboard_fab2_lib.baseboard_fab2(sch_1):page237_i81@mstr_discrete.res(chips)!RES_0402-63.4K,1.0%,1/16W,CHIPA!R2L20!//jf4cfls225.pdx.intel.com/apd_proj/ppg_lib/epg_masterlib/logical/mstr_discrete/res/chips/chips.prt!RES!RES_0402-63.4K,1.0%,1/16W,CHIP,G21796-327!RES!!!F364!!P1V8_PCH_STBY_VR!!
S!@baseboard_fab2_lib.baseboard_fab2(sch_1):page199_i124@mstr_sconn.sconn3_d53458001(chips)!SCONN3_D53458001_SM-EMPTY,D534A!J1B4!//jf4cfls225.pdx.intel.com/apd_proj/ppg_lib/epg_masterlib/logical/mstr_sconn/sconn3_d53458001/chips/chips.prt!SCONN3_D53458001!SCONN3_D53458001_SM-EMPTY,D53458-001!SCONN3_D53458001_SM!!!F136!!!!
S!@baseboard_fab2_lib.baseboard_fab2(sch_1):page234_i184@mstr_vreg.ncp3232l(chips)!NCP3232L_SM-IC,H86355-001!EU4A3!//jf4cfls225.pdx.intel.com/apd_proj/ppg_lib/epg_masterlib/logical/mstr_vreg/ncp3232l/chips/chips.prt!NCP3232L!NCP3232L_SM-IC,H86355-001!NCP3232L_SM!!!F2002!!!!
S!@baseboard_fab2_lib.baseboard_fab2(sch_1):page233_i225@mstr_vreg.ncp3232l(chips)!NCP3232L_SM-IC,H86355-001!EU4G1!//jf4cfls225.pdx.intel.com/apd_proj/ppg_lib/epg_masterlib/logical/mstr_vreg/ncp3232l/chips/chips.prt!NCP3232L!NCP3232L_SM-IC,H86355-001!NCP3232L_SM!!!F2001!!!!
S!@baseboard_fab2_lib.baseboard_fab2(sch_1):page232_i214@mstr_vreg.ncp3232l(chips)!NCP3232L_SM-IC,H86355-001!EU7B1!//jf4cfls225.pdx.intel.com/apd_proj/ppg_lib/epg_masterlib/logical/mstr_vreg/ncp3232l/chips/chips.prt!NCP3232L!NCP3232L_SM-IC,H86355-001!NCP3232L_SM!!!F2000!!!!
S!@baseboard_fab2_lib.baseboard_fab2(sch_1):page231_i193@mstr_vreg.ncp3232l(chips)!NCP3232L_SM-IC,H86355-001!EU7F1!//jf4cfls225.pdx.intel.com/apd_proj/ppg_lib/epg_masterlib/logical/mstr_vreg/ncp3232l/chips/chips.prt!NCP3232L!NCP3232L_SM-IC,H86355-001!NCP3232L_SM!!!F1999!!!!
S!@baseboard_fab2_lib.baseboard_fab2(sch_1):page193_i46@mstr_sconn.sconn120_h61426002(chips)!SCONN120_H61426002_SM-CONN,H61A!J4B2!//jf4cfls225.pdx.intel.com/apd_proj/ppg_lib/epg_masterlib/logical/mstr_sconn/sconn120_h61426002/chips/chips.prt!SCONN120_H61426002!SCONN120_H61426002_SM-CONN,H61426-002!SCONN120_H61426002_SM!!!F239!!MCP VRM CPU1!!
S!@baseboard_fab2_lib.baseboard_fab2(sch_1):page193_i45@mstr_sconn.sconn120_h61426002(chips)!SCONN120_H61426002_SM-CONN,H61A!J4E1!//jf4cfls225.pdx.intel.com/apd_proj/ppg_lib/epg_masterlib/logical/mstr_sconn/sconn120_h61426002/chips/chips.prt!SCONN120_H61426002!SCONN120_H61426002_SM-CONN,H61426-002!SCONN120_H61426002_SM!!!F238!!MCP VRM CPU1!!
S!@baseboard_fab2_lib.baseboard_fab2(sch_1):page194_i56@mstr_sconn.sconn120_h61426002(chips)!SCONN120_H61426002_SM-CONN,H61A!J6B1!//jf4cfls225.pdx.intel.com/apd_proj/ppg_lib/epg_masterlib/logical/mstr_sconn/sconn120_h61426002/chips/chips.prt!SCONN120_H61426002!SCONN120_H61426002_SM-CONN,H61426-002!SCONN120_H61426002_SM!!!F237!!MCP VRM CPU0!!
S!@baseboard_fab2_lib.baseboard_fab2(sch_1):page194_i55@mstr_sconn.sconn120_h61426002(chips)!SCONN120_H61426002_SM-CONN,H61A!J6E1!//jf4cfls225.pdx.intel.com/apd_proj/ppg_lib/epg_masterlib/logical/mstr_sconn/sconn120_h61426002/chips/chips.prt!SCONN120_H61426002!SCONN120_H61426002_SM-CONN,H61426-002!SCONN120_H61426002_SM!!!F236!!MCP VRM CPU0!!
S!@baseboard_fab2_lib.baseboard_fab2(sch_1):page209_i52@mstr_analog.adm4073(chips)!ADM4073_SM-EMPTY,G12194-001!U1B3!//jf4cfls225.pdx.intel.com/apd_proj/ppg_lib/epg_masterlib/logical/mstr_analog/adm4073/chips/chips.prt!ADM4073!ADM4073_SM-EMPTY,G12194-001!ADM4073_SM!!!F4196!!PVCCIN_CPU1_FILTER_VR!!
S!@baseboard_fab2_lib.baseboard_fab2(sch_1):page204_i53@mstr_analog.adm4073(chips)!ADM4073_SM-EMPTY,G12194-001!U4C1!//jf4cfls225.pdx.intel.com/apd_proj/ppg_lib/epg_masterlib/logical/mstr_analog/adm4073/chips/chips.prt!ADM4073!ADM4073_SM-EMPTY,G12194-001!ADM4073_SM!!!F4195!!PVCCIN_CPU0_FILTER_VR!!
S!@baseboard_fab2_lib.baseboard_fab2(sch_1):page149_i152@mstr_discrete.cap(chips)!CAP_0402-1.0UF,6.3V,10%,EMPTY,A!C1T18!//jf4cfls225.pdx.intel.com/apd_proj/ppg_lib/epg_masterlib/logical/mstr_discrete/cap/chips/chips.prt!CAP!CAP_0402-1.0UF,6.3V,10%,EMPTY,D97712-004!CAP_0402!!!F3757!!BMC!!
S!@baseboard_fab2_lib.baseboard_fab2(sch_1):page149_i161@mstr_discrete.cap(chips)!CAP_0402-1.0UF,6.3V,10%,EMPTY,A!C8F9!//jf4cfls225.pdx.intel.com/apd_proj/ppg_lib/epg_masterlib/logical/mstr_discrete/cap/chips/chips.prt!CAP!CAP_0402-1.0UF,6.3V,10%,EMPTY,D97712-004!CAP_0402!!!F3756!!BMC!!
S!@baseboard_fab2_lib.baseboard_fab2(sch_1):page149_i150@mstr_discrete.cap(chips)!CAP_0603-10UF,6.3V,20%,EMPTY,EA!C1T16!//jf4cfls225.pdx.intel.com/apd_proj/ppg_lib/epg_masterlib/logical/mstr_discrete/cap/chips/chips.prt!CAP!CAP_0603-10UF,6.3V,20%,EMPTY,E15431-002!CAP!!!F3092!!BMC!!
S!@baseboard_fab2_lib.baseboard_fab2(sch_1):page149_i159@mstr_discrete.cap(chips)!CAP_0603-10UF,6.3V,20%,EMPTY,EA!C8F10!//jf4cfls225.pdx.intel.com/apd_proj/ppg_lib/epg_masterlib/logical/mstr_discrete/cap/chips/chips.prt!CAP!CAP_0603-10UF,6.3V,20%,EMPTY,E15431-002!CAP!!!F3091!!BMC!!
S!@baseboard_fab2_lib.baseboard_fab2(sch_1):page139_i163@mstr_discrete.cap(chips)!CAP_0603-22.0UF,4V,20%,EMPTY,EA!C9E1!//jf4cfls225.pdx.intel.com/apd_proj/ppg_lib/epg_masterlib/logical/mstr_discrete/cap/chips/chips.prt!CAP!CAP_0603-22.0UF,4V,20%,EMPTY,E15431-004!CAP!!!F3068!!NIC_SPRV!!
S!@baseboard_fab2_lib.baseboard_fab2(sch_1):page139_i241@mstr_discrete.cap(chips)!CAP_0603-22.0UF,4V,20%,EMPTY,EA!C9E12!//jf4cfls225.pdx.intel.com/apd_proj/ppg_lib/epg_masterlib/logical/mstr_discrete/cap/chips/chips.prt!CAP!CAP_0603-22.0UF,4V,20%,EMPTY,E15431-004!CAP!!!F3067!!NIC_SPRV!!
S!@baseboard_fab2_lib.baseboard_fab2(sch_1):page149_i153@mstr_discrete.ferrite(chips)!FERRITE_SMLF-300,EMPTY,693286-A!FB1T1!//jf4cfls225.pdx.intel.com/apd_proj/ppg_lib/epg_masterlib/logical/mstr_discrete/ferrite/chips/chips.prt!FERRITE!FERRITE_SMLF-300,EMPTY,693286-046!FERRITE!!!F2190!!BMC!!
S!@baseboard_fab2_lib.baseboard_fab2(sch_1):page149_i163@mstr_discrete.ferrite(chips)!FERRITE_SMLF-300,EMPTY,693286-A!FB2T1!//jf4cfls225.pdx.intel.com/apd_proj/ppg_lib/epg_masterlib/logical/mstr_discrete/ferrite/chips/chips.prt!FERRITE!FERRITE_SMLF-300,EMPTY,693286-046!FERRITE!!!F2189!!BMC!!
S!@baseboard_fab2_lib.baseboard_fab2(sch_1):page145_i250@mstr_discrete.osc_c(chips)!OSC_C_SM4-24MHZ,OSC,D34520-021!Y9F2!//jf4cfls225.pdx.intel.com/apd_proj/ppg_lib/epg_masterlib/logical/mstr_discrete/osc_c/chips/chips.prt!OSC_C!OSC_C_SM4-24MHZ,OSC,D34520-021!OSC_C_SM4!!!F1987!!BMC!!
S!@baseboard_fab2_lib.baseboard_fab2(sch_1):page188_i27@mstr_sconn.sconn64_h87568002_a(chips)!SCONN64_H87568002_A_SMT-CONN,HA!J8E4!//jf4cfls225.pdx.intel.com/apd_proj/ppg_lib/epg_masterlib/logical/mstr_sconn/sconn64_h87568002_a/chips/chips.prt!SCONN64_H87568002_A!SCONN64_H87568002_A_SMT-CONN,H87568-002!SCONN64_H87568002_A_SMT!!!F134!!IO_MODULE!!
S!@baseboard_fab2_lib.baseboard_fab2(sch_1):page176_i113@mstr_discrete.capp(chips)!CAPP_7343HLF-330UF,10V,20%,POSA!C9B8!//jf4cfls225.pdx.intel.com/apd_proj/ppg_lib/epg_masterlib/logical/mstr_discrete/capp/chips/chips.prt!CAPP!CAPP_7343HLF-330UF,10V,20%,POSCAP,724613-043!CAPP!!!F4103!!!!
S!@baseboard_fab2_lib.baseboard_fab2(sch_1):page198_i86@mstr_discrete.mosfet_n(chips)!MOSFET_N_LCC3-BSZ019N03LS,NFETA!Q1B1!//jf4cfls225.pdx.intel.com/apd_proj/ppg_lib/epg_masterlib/logical/mstr_discrete/mosfet_n/chips/chips.prt!MOSFET_N!MOSFET_N_LCC3-BSZ019N03LS,NFET,G26762-001!MOSFET_N_LCC3!!!F2017!!!!
S!@baseboard_fab2_lib.baseboard_fab2(sch_1):page198_i88@mstr_discrete.mosfet_n(chips)!MOSFET_N_LCC3-BSZ019N03LS,NFETA!Q7E7!//jf4cfls225.pdx.intel.com/apd_proj/ppg_lib/epg_masterlib/logical/mstr_discrete/mosfet_n/chips/chips.prt!MOSFET_N!MOSFET_N_LCC3-BSZ019N03LS,NFET,G26762-001!MOSFET_N_LCC3!!!F2016!!!!
S!@baseboard_fab2_lib.baseboard_fab2(sch_1):page198_i87@mstr_discrete.mosfet_n(chips)!MOSFET_N_LCC3-BSZ019N03LS,NFETA!Q8B1!//jf4cfls225.pdx.intel.com/apd_proj/ppg_lib/epg_masterlib/logical/mstr_discrete/mosfet_n/chips/chips.prt!MOSFET_N!MOSFET_N_LCC3-BSZ019N03LS,NFET,G26762-001!MOSFET_N_LCC3!!!F2015!!!!
S!@baseboard_fab2_lib.baseboard_fab2(sch_1):page198_i85@mstr_discrete.mosfet_n(chips)!MOSFET_N_LCC3-BSZ019N03LS,NFETA!Q8G1!//jf4cfls225.pdx.intel.com/apd_proj/ppg_lib/epg_masterlib/logical/mstr_discrete/mosfet_n/chips/chips.prt!MOSFET_N!MOSFET_N_LCC3-BSZ019N03LS,NFET,G26762-001!MOSFET_N_LCC3!!!F2014!!!!
S!@baseboard_fab2_lib.baseboard_fab2(sch_1):page166_i32@mstr_discrete.res(chips)!RES_0402-348,1%,1/16W,CHIP,G21A!R7D15!//jf4cfls225.pdx.intel.com/apd_proj/ppg_lib/epg_masterlib/logical/mstr_discrete/res/chips/chips.prt!RES!RES_0402-348,1%,1/16W,CHIP,G21796-340!RES!!!F660!!PECI!!
S!@baseboard_fab2_lib.baseboard_fab2(sch_1):page107_i417@mstr_discrete.cap(chips)!CAP_0402-0.22UF,16V,10%,EMPTY,A!C3P10!//jf4cfls225.pdx.intel.com/apd_proj/ppg_lib/epg_masterlib/logical/mstr_discrete/cap/chips/chips.prt!CAP!CAP_0402-0.22UF,16V,10%,EMPTY,A36096-155!CAP_0402!!!F4052!!!!
S!@baseboard_fab2_lib.baseboard_fab2(sch_1):page107_i415@mstr_discrete.cap(chips)!CAP_0402-0.22UF,16V,10%,EMPTY,A!C3P12!//jf4cfls225.pdx.intel.com/apd_proj/ppg_lib/epg_masterlib/logical/mstr_discrete/cap/chips/chips.prt!CAP!CAP_0402-0.22UF,16V,10%,EMPTY,A36096-155!CAP_0402!!!F4051!!!!
S!@baseboard_fab2_lib.baseboard_fab2(sch_1):page107_i431@mstr_discrete.cap(chips)!CAP_0402-0.22UF,16V,10%,EMPTY,A!C3P14!//jf4cfls225.pdx.intel.com/apd_proj/ppg_lib/epg_masterlib/logical/mstr_discrete/cap/chips/chips.prt!CAP!CAP_0402-0.22UF,16V,10%,EMPTY,A36096-155!CAP_0402!!!F4050!!!!
S!@baseboard_fab2_lib.baseboard_fab2(sch_1):page107_i422@mstr_discrete.cap(chips)!CAP_0402-0.22UF,16V,10%,EMPTY,A!C3P16!//jf4cfls225.pdx.intel.com/apd_proj/ppg_lib/epg_masterlib/logical/mstr_discrete/cap/chips/chips.prt!CAP!CAP_0402-0.22UF,16V,10%,EMPTY,A36096-155!CAP_0402!!!F4049!!!!
S!@baseboard_fab2_lib.baseboard_fab2(sch_1):page107_i427@mstr_discrete.cap(chips)!CAP_0402-0.22UF,16V,10%,EMPTY,A!C3P19!//jf4cfls225.pdx.intel.com/apd_proj/ppg_lib/epg_masterlib/logical/mstr_discrete/cap/chips/chips.prt!CAP!CAP_0402-0.22UF,16V,10%,EMPTY,A36096-155!CAP_0402!!!F4048!!!!
S!@baseboard_fab2_lib.baseboard_fab2(sch_1):page107_i423@mstr_discrete.cap(chips)!CAP_0402-0.22UF,16V,10%,EMPTY,A!C3P21!//jf4cfls225.pdx.intel.com/apd_proj/ppg_lib/epg_masterlib/logical/mstr_discrete/cap/chips/chips.prt!CAP!CAP_0402-0.22UF,16V,10%,EMPTY,A36096-155!CAP_0402!!!F4047!!!!
S!@baseboard_fab2_lib.baseboard_fab2(sch_1):page107_i435@mstr_discrete.cap(chips)!CAP_0402-0.22UF,16V,10%,EMPTY,A!C3P22!//jf4cfls225.pdx.intel.com/apd_proj/ppg_lib/epg_masterlib/logical/mstr_discrete/cap/chips/chips.prt!CAP!CAP_0402-0.22UF,16V,10%,EMPTY,A36096-155!CAP_0402!!!F4046!!!!
S!@baseboard_fab2_lib.baseboard_fab2(sch_1):page107_i424@mstr_discrete.cap(chips)!CAP_0402-0.22UF,16V,10%,EMPTY,A!C3P24!//jf4cfls225.pdx.intel.com/apd_proj/ppg_lib/epg_masterlib/logical/mstr_discrete/cap/chips/chips.prt!CAP!CAP_0402-0.22UF,16V,10%,EMPTY,A36096-155!CAP_0402!!!F4045!!!!
S!@baseboard_fab2_lib.baseboard_fab2(sch_1):page107_i444@mstr_discrete.cap(chips)!CAP_0402-0.22UF,16V,10%,EMPTY,A!C3P26!//jf4cfls225.pdx.intel.com/apd_proj/ppg_lib/epg_masterlib/logical/mstr_discrete/cap/chips/chips.prt!CAP!CAP_0402-0.22UF,16V,10%,EMPTY,A36096-155!CAP_0402!!!F4044!!!!
S!@baseboard_fab2_lib.baseboard_fab2(sch_1):page107_i437@mstr_discrete.cap(chips)!CAP_0402-0.22UF,16V,10%,EMPTY,A!C3P29!//jf4cfls225.pdx.intel.com/apd_proj/ppg_lib/epg_masterlib/logical/mstr_discrete/cap/chips/chips.prt!CAP!CAP_0402-0.22UF,16V,10%,EMPTY,A36096-155!CAP_0402!!!F4043!!!!
S!@baseboard_fab2_lib.baseboard_fab2(sch_1):page107_i452@mstr_discrete.cap(chips)!CAP_0402-0.22UF,16V,10%,EMPTY,A!C3P31!//jf4cfls225.pdx.intel.com/apd_proj/ppg_lib/epg_masterlib/logical/mstr_discrete/cap/chips/chips.prt!CAP!CAP_0402-0.22UF,16V,10%,EMPTY,A36096-155!CAP_0402!!!F4042!!!!
S!@baseboard_fab2_lib.baseboard_fab2(sch_1):page107_i439@mstr_discrete.cap(chips)!CAP_0402-0.22UF,16V,10%,EMPTY,A!C3P33!//jf4cfls225.pdx.intel.com/apd_proj/ppg_lib/epg_masterlib/logical/mstr_discrete/cap/chips/chips.prt!CAP!CAP_0402-0.22UF,16V,10%,EMPTY,A36096-155!CAP_0402!!!F4041!!!!
S!@baseboard_fab2_lib.baseboard_fab2(sch_1):page107_i447@mstr_discrete.cap(chips)!CAP_0402-0.22UF,16V,10%,EMPTY,A!C3P34!//jf4cfls225.pdx.intel.com/apd_proj/ppg_lib/epg_masterlib/logical/mstr_discrete/cap/chips/chips.prt!CAP!CAP_0402-0.22UF,16V,10%,EMPTY,A36096-155!CAP_0402!!!F4040!!!!
S!@baseboard_fab2_lib.baseboard_fab2(sch_1):page107_i438@mstr_discrete.cap(chips)!CAP_0402-0.22UF,16V,10%,EMPTY,A!C3P36!//jf4cfls225.pdx.intel.com/apd_proj/ppg_lib/epg_masterlib/logical/mstr_discrete/cap/chips/chips.prt!CAP!CAP_0402-0.22UF,16V,10%,EMPTY,A36096-155!CAP_0402!!!F4039!!!!
S!@baseboard_fab2_lib.baseboard_fab2(sch_1):page107_i455@mstr_discrete.cap(chips)!CAP_0402-0.22UF,16V,10%,EMPTY,A!C3P38!//jf4cfls225.pdx.intel.com/apd_proj/ppg_lib/epg_masterlib/logical/mstr_discrete/cap/chips/chips.prt!CAP!CAP_0402-0.22UF,16V,10%,EMPTY,A36096-155!CAP_0402!!!F4038!!!!
S!@baseboard_fab2_lib.baseboard_fab2(sch_1):page107_i448@mstr_discrete.cap(chips)!CAP_0402-0.22UF,16V,10%,EMPTY,A!C3P41!//jf4cfls225.pdx.intel.com/apd_proj/ppg_lib/epg_masterlib/logical/mstr_discrete/cap/chips/chips.prt!CAP!CAP_0402-0.22UF,16V,10%,EMPTY,A36096-155!CAP_0402!!!F4037!!!!
S!@baseboard_fab2_lib.baseboard_fab2(sch_1):page161_i32@mstr_conn.conn6_c74770005(chips)!CONN6_C74770005_PIP-HDR,C74770A!J1B2!//jf4cfls225.pdx.intel.com/apd_proj/ppg_lib/epg_masterlib/logical/mstr_conn/conn6_c74770005/chips/chips.prt!CONN6_C74770005!CONN6_C74770005_PIP-HDR,C74770-005!CONN6_C74770005!!!F2242!!CPU_FANS!!
S!@baseboard_fab2_lib.baseboard_fab2(sch_1):page161_i1@mstr_conn.conn6_c74770005(chips)!CONN6_C74770005_PIP-HDR,C74770A!J1F2!//jf4cfls225.pdx.intel.com/apd_proj/ppg_lib/epg_masterlib/logical/mstr_conn/conn6_c74770005/chips/chips.prt!CONN6_C74770005!CONN6_C74770005_PIP-HDR,C74770-005!CONN6_C74770005!!!F2241!!CPU_FANS!!
S!@baseboard_fab2_lib.baseboard_fab2(sch_1):page114_i40@chpset_lib.lbg_core_qat_ext_c(chips)!LBG_CORE_QAT_EXT_C_BGA1-IC,TBD!U7C1!//jf4cfls225.pdx.intel.com/apd_proj/ppg_lib/chpset_lib/logical/lbg_core_qat_ext_c/chips/chips.prt!LBG_CORE_QAT_EXT_C!LBG_CORE_QAT_EXT_C_BGA1-IC,TBD!LBG_CORE_QAT_EXT_C_BGA1!!!F2055!!SB!!
S!@baseboard_fab2_lib.baseboard_fab2(sch_1):page115_i74@chpset_lib.lbg_core_qat_ext_c(chips)!LBG_CORE_QAT_EXT_C_BGA1-IC,TBD!U7C1!//jf4cfls225.pdx.intel.com/apd_proj/ppg_lib/chpset_lib/logical/lbg_core_qat_ext_c/chips/chips.prt!LBG_CORE_QAT_EXT_C!LBG_CORE_QAT_EXT_C_BGA1-IC,TBD!LBG_CORE_QAT_EXT_C_BGA1!!!F2054!!SB!!
S!@baseboard_fab2_lib.baseboard_fab2(sch_1):page116_i220@chpset_lib.lbg_core_qat_ext_c(chips)!LBG_CORE_QAT_EXT_C_BGA1-IC,TBD!U7C1!//jf4cfls225.pdx.intel.com/apd_proj/ppg_lib/chpset_lib/logical/lbg_core_qat_ext_c/chips/chips.prt!LBG_CORE_QAT_EXT_C!LBG_CORE_QAT_EXT_C_BGA1-IC,TBD!LBG_CORE_QAT_EXT_C_BGA1!!!F2053!!SB!!
S!@baseboard_fab2_lib.baseboard_fab2(sch_1):page117_i9@chpset_lib.lbg_core_qat_ext_c(chips)!LBG_CORE_QAT_EXT_C_BGA1-IC,TBD!U7C1!//jf4cfls225.pdx.intel.com/apd_proj/ppg_lib/chpset_lib/logical/lbg_core_qat_ext_c/chips/chips.prt!LBG_CORE_QAT_EXT_C!LBG_CORE_QAT_EXT_C_BGA1-IC,TBD!LBG_CORE_QAT_EXT_C_BGA1!!!F2052!!SB!!
S!@baseboard_fab2_lib.baseboard_fab2(sch_1):page118_i73@chpset_lib.lbg_core_qat_ext_c(chips)!LBG_CORE_QAT_EXT_C_BGA1-IC,TBD!U7C1!//jf4cfls225.pdx.intel.com/apd_proj/ppg_lib/chpset_lib/logical/lbg_core_qat_ext_c/chips/chips.prt!LBG_CORE_QAT_EXT_C!LBG_CORE_QAT_EXT_C_BGA1-IC,TBD!LBG_CORE_QAT_EXT_C_BGA1!!!F2051!!SB!!
S!@baseboard_fab2_lib.baseboard_fab2(sch_1):page119_i115@chpset_lib.lbg_core_qat_ext_c(chips)!LBG_CORE_QAT_EXT_C_BGA1-IC,TBD!U7C1!//jf4cfls225.pdx.intel.com/apd_proj/ppg_lib/chpset_lib/logical/lbg_core_qat_ext_c/chips/chips.prt!LBG_CORE_QAT_EXT_C!LBG_CORE_QAT_EXT_C_BGA1-IC,TBD!LBG_CORE_QAT_EXT_C_BGA1!!!F2050!!SB!!
S!@baseboard_fab2_lib.baseboard_fab2(sch_1):page120_i147@chpset_lib.lbg_core_qat_ext_c(chips)!LBG_CORE_QAT_EXT_C_BGA1-IC,TBD!U7C1!//jf4cfls225.pdx.intel.com/apd_proj/ppg_lib/chpset_lib/logical/lbg_core_qat_ext_c/chips/chips.prt!LBG_CORE_QAT_EXT_C!LBG_CORE_QAT_EXT_C_BGA1-IC,TBD!LBG_CORE_QAT_EXT_C_BGA1!!!F2049!!SB!!
S!@baseboard_fab2_lib.baseboard_fab2(sch_1):page121_i34@chpset_lib.lbg_core_qat_ext_c(chips)!LBG_CORE_QAT_EXT_C_BGA1-IC,TBD!U7C1!//jf4cfls225.pdx.intel.com/apd_proj/ppg_lib/chpset_lib/logical/lbg_core_qat_ext_c/chips/chips.prt!LBG_CORE_QAT_EXT_C!LBG_CORE_QAT_EXT_C_BGA1-IC,TBD!LBG_CORE_QAT_EXT_C_BGA1!!!F2048!!SB!!
S!@baseboard_fab2_lib.baseboard_fab2(sch_1):page122_i63@chpset_lib.lbg_core_qat_ext_c(chips)!LBG_CORE_QAT_EXT_C_BGA1-IC,TBD!U7C1!//jf4cfls225.pdx.intel.com/apd_proj/ppg_lib/chpset_lib/logical/lbg_core_qat_ext_c/chips/chips.prt!LBG_CORE_QAT_EXT_C!LBG_CORE_QAT_EXT_C_BGA1-IC,TBD!LBG_CORE_QAT_EXT_C_BGA1!!!F2047!!SB!!
S!@baseboard_fab2_lib.baseboard_fab2(sch_1):page123_i21@chpset_lib.lbg_core_qat_ext_c(chips)!LBG_CORE_QAT_EXT_C_BGA1-IC,TBD!U7C1!//jf4cfls225.pdx.intel.com/apd_proj/ppg_lib/chpset_lib/logical/lbg_core_qat_ext_c/chips/chips.prt!LBG_CORE_QAT_EXT_C!LBG_CORE_QAT_EXT_C_BGA1-IC,TBD!LBG_CORE_QAT_EXT_C_BGA1!!!F2046!!SB!!
S!@baseboard_fab2_lib.baseboard_fab2(sch_1):page123_i13@chpset_lib.lbg_core_qat_ext_c(chips)!LBG_CORE_QAT_EXT_C_BGA1-IC,TBD!U7C1!//jf4cfls225.pdx.intel.com/apd_proj/ppg_lib/chpset_lib/logical/lbg_core_qat_ext_c/chips/chips.prt!LBG_CORE_QAT_EXT_C!LBG_CORE_QAT_EXT_C_BGA1-IC,TBD!LBG_CORE_QAT_EXT_C_BGA1!!!F2045!!SB!!
S!@baseboard_fab2_lib.baseboard_fab2(sch_1):page124_i17@chpset_lib.lbg_core_qat_ext_c(chips)!LBG_CORE_QAT_EXT_C_BGA1-IC,TBD!U7C1!//jf4cfls225.pdx.intel.com/apd_proj/ppg_lib/chpset_lib/logical/lbg_core_qat_ext_c/chips/chips.prt!LBG_CORE_QAT_EXT_C!LBG_CORE_QAT_EXT_C_BGA1-IC,TBD!LBG_CORE_QAT_EXT_C_BGA1!!!F2044!!SB!!
S!@baseboard_fab2_lib.baseboard_fab2(sch_1):page124_i16@chpset_lib.lbg_core_qat_ext_c(chips)!LBG_CORE_QAT_EXT_C_BGA1-IC,TBD!U7C1!//jf4cfls225.pdx.intel.com/apd_proj/ppg_lib/chpset_lib/logical/lbg_core_qat_ext_c/chips/chips.prt!LBG_CORE_QAT_EXT_C!LBG_CORE_QAT_EXT_C_BGA1-IC,TBD!LBG_CORE_QAT_EXT_C_BGA1!!!F2043!!SB!!
S!@baseboard_fab2_lib.baseboard_fab2(sch_1):page124_i15@chpset_lib.lbg_core_qat_ext_c(chips)!LBG_CORE_QAT_EXT_C_BGA1-IC,TBD!U7C1!//jf4cfls225.pdx.intel.com/apd_proj/ppg_lib/chpset_lib/logical/lbg_core_qat_ext_c/chips/chips.prt!LBG_CORE_QAT_EXT_C!LBG_CORE_QAT_EXT_C_BGA1-IC,TBD!LBG_CORE_QAT_EXT_C_BGA1!!!F2042!!SB!!
S!@baseboard_fab2_lib.baseboard_fab2(sch_1):page134_i5@mstr_conn.conn12_d59987001(chips)!CONN12_D59987001_THLF-CONN,D59A!J8G2!//jf4cfls225.pdx.intel.com/apd_proj/ppg_lib/epg_masterlib/logical/mstr_conn/conn12_d59987001/chips/chips.prt!CONN12_D59987001!CONN12_D59987001_THLF-CONN,D59987-001!CONN12_D59987001!!!F2258!!SB!!
S!@baseboard_fab2_lib.baseboard_fab2(sch_1):page136_i167@mstr_conn.conn12_d59987001(chips)!CONN12_D59987001_THLF-CONN,D59A!J7G3!//jf4cfls225.pdx.intel.com/apd_proj/ppg_lib/epg_masterlib/logical/mstr_conn/conn12_d59987001/chips/chips.prt!CONN12_D59987001!CONN12_D59987001_THLF-CONN,D59987-001!CONN12_D59987001!!!F2257!!SB!!
S!@baseboard_fab2_lib.baseboard_fab2(sch_1):page137_i100@mstr_conn.conn12_d59987001(chips)!CONN12_D59987001_THLF-CONN,D59A!J9G1!//jf4cfls225.pdx.intel.com/apd_proj/ppg_lib/epg_masterlib/logical/mstr_conn/conn12_d59987001/chips/chips.prt!CONN12_D59987001!CONN12_D59987001_THLF-CONN,D59987-001!CONN12_D59987001!!!F2256!!SB!!
S!@baseboard_fab2_lib.baseboard_fab2(sch_1):page177_i71@mstr_discrete.led(chips)!LED_A1-RED,IC,D14725-005!DS9F1!//jf4cfls225.pdx.intel.com/apd_proj/ppg_lib/epg_masterlib/logical/mstr_discrete/led/chips/chips.prt!LED!LED_A1-RED,IC,D14725-005!LED_A1!!!F2035!!BMC!!
S!@baseboard_fab2_lib.baseboard_fab2(sch_1):page199_i88@mstr_discrete.res(chips)!RES_0402-100.0K,1%,1/16W,CHIP,A!R1D11!//jf4cfls225.pdx.intel.com/apd_proj/ppg_lib/epg_masterlib/logical/mstr_discrete/res/chips/chips.prt!RES!RES_0402-100.0K,1%,1/16W,CHIP,G21796-010!RES!!!F1157!!HOT_SWAP!!
S!@baseboard_fab2_lib.baseboard_fab2(sch_1):page199_i92@mstr_discrete.res(chips)!RES_0402-100.0K,1%,1/16W,CHIP,A!R1D15!//jf4cfls225.pdx.intel.com/apd_proj/ppg_lib/epg_masterlib/logical/mstr_discrete/res/chips/chips.prt!RES!RES_0402-100.0K,1%,1/16W,CHIP,G21796-010!RES!!!F1156!!HOT_SWAP!!
S!@baseboard_fab2_lib.baseboard_fab2(sch_1):page199_i87@mstr_discrete.res(chips)!RES_0402-100.0K,1%,1/16W,CHIP,A!R1D18!//jf4cfls225.pdx.intel.com/apd_proj/ppg_lib/epg_masterlib/logical/mstr_discrete/res/chips/chips.prt!RES!RES_0402-100.0K,1%,1/16W,CHIP,G21796-010!RES!!!F1155!!HOT_SWAP!!
S!@baseboard_fab2_lib.baseboard_fab2(sch_1):page199_i17@mstr_discrete.res(chips)!RES_0402-100.0K,1%,1/16W,CHIP,A!R1D32!//jf4cfls225.pdx.intel.com/apd_proj/ppg_lib/epg_masterlib/logical/mstr_discrete/res/chips/chips.prt!RES!RES_0402-100.0K,1%,1/16W,CHIP,G21796-010!RES!!!F1154!!HOT_SWAP!!
S!@baseboard_fab2_lib.baseboard_fab2(sch_1):page199_i15@mstr_discrete.res(chips)!RES_0402-100.0K,1%,1/16W,CHIP,A!R1D37!//jf4cfls225.pdx.intel.com/apd_proj/ppg_lib/epg_masterlib/logical/mstr_discrete/res/chips/chips.prt!RES!RES_0402-100.0K,1%,1/16W,CHIP,G21796-010!RES!!!F1153!!HOT_SWAP!!
S!@baseboard_fab2_lib.baseboard_fab2(sch_1):page199_i16@mstr_discrete.res(chips)!RES_0402-100.0K,1%,1/16W,CHIP,A!R1D39!//jf4cfls225.pdx.intel.com/apd_proj/ppg_lib/epg_masterlib/logical/mstr_discrete/res/chips/chips.prt!RES!RES_0402-100.0K,1%,1/16W,CHIP,G21796-010!RES!!!F1152!!HOT_SWAP!!
S!@baseboard_fab2_lib.baseboard_fab2(sch_1):page155_i130@mstr_discrete.res(chips)!RES_0402-100.0K,1%,1/16W,CHIP,A!R1L9!//jf4cfls225.pdx.intel.com/apd_proj/ppg_lib/epg_masterlib/logical/mstr_discrete/res/chips/chips.prt!RES!RES_0402-100.0K,1%,1/16W,CHIP,G21796-010!RES!!!F1151!!BMC_DEBUG_HEADER!!
S!@baseboard_fab2_lib.baseboard_fab2(sch_1):page147_i144@mstr_discrete.res(chips)!RES_0402-100.0K,1%,1/16W,CHIP,A!R1U1!//jf4cfls225.pdx.intel.com/apd_proj/ppg_lib/epg_masterlib/logical/mstr_discrete/res/chips/chips.prt!RES!RES_0402-100.0K,1%,1/16W,CHIP,G21796-010!RES!!!F1150!!!!
S!@baseboard_fab2_lib.baseboard_fab2(sch_1):page147_i145@mstr_discrete.res(chips)!RES_0402-100.0K,1%,1/16W,CHIP,A!R1U2!//jf4cfls225.pdx.intel.com/apd_proj/ppg_lib/epg_masterlib/logical/mstr_discrete/res/chips/chips.prt!RES!RES_0402-100.0K,1%,1/16W,CHIP,G21796-010!RES!!!F1149!!!!
S!@baseboard_fab2_lib.baseboard_fab2(sch_1):page147_i149@mstr_discrete.res(chips)!RES_0402-100.0K,1%,1/16W,CHIP,A!R1U4!//jf4cfls225.pdx.intel.com/apd_proj/ppg_lib/epg_masterlib/logical/mstr_discrete/res/chips/chips.prt!RES!RES_0402-100.0K,1%,1/16W,CHIP,G21796-010!RES!!!F1148!!!!
S!@baseboard_fab2_lib.baseboard_fab2(sch_1):page147_i148@mstr_discrete.res(chips)!RES_0402-100.0K,1%,1/16W,CHIP,A!R1U5!//jf4cfls225.pdx.intel.com/apd_proj/ppg_lib/epg_masterlib/logical/mstr_discrete/res/chips/chips.prt!RES!RES_0402-100.0K,1%,1/16W,CHIP,G21796-010!RES!!!F1147!!!!
S!@baseboard_fab2_lib.baseboard_fab2(sch_1):page144_i532@mstr_discrete.res(chips)!RES_0402-100.0K,1%,1/16W,CHIP,A!R2T15!//jf4cfls225.pdx.intel.com/apd_proj/ppg_lib/epg_masterlib/logical/mstr_discrete/res/chips/chips.prt!RES!RES_0402-100.0K,1%,1/16W,CHIP,G21796-010!RES!!!F1146!!BMC!!
S!@baseboard_fab2_lib.baseboard_fab2(sch_1):page116_i235@mstr_discrete.res(chips)!RES_0402-100.0K,1%,1/16W,CHIP,A!R3M8!//jf4cfls225.pdx.intel.com/apd_proj/ppg_lib/epg_masterlib/logical/mstr_discrete/res/chips/chips.prt!RES!RES_0402-100.0K,1%,1/16W,CHIP,G21796-010!RES!!!F1145!!SB!!
S!@baseboard_fab2_lib.baseboard_fab2(sch_1):page116_i234@mstr_discrete.res(chips)!RES_0402-100.0K,1%,1/16W,CHIP,A!R3M9!//jf4cfls225.pdx.intel.com/apd_proj/ppg_lib/epg_masterlib/logical/mstr_discrete/res/chips/chips.prt!RES!RES_0402-100.0K,1%,1/16W,CHIP,G21796-010!RES!!!F1144!!SB!!
S!@baseboard_fab2_lib.baseboard_fab2(sch_1):page198_i83@mstr_discrete.res(chips)!RES_0402-100.0K,1%,1/16W,CHIP,A!R8B4!//jf4cfls225.pdx.intel.com/apd_proj/ppg_lib/epg_masterlib/logical/mstr_discrete/res/chips/chips.prt!RES!RES_0402-100.0K,1%,1/16W,CHIP,G21796-010!RES!!!F1143!!HOT_SWAP!!
S!@baseboard_fab2_lib.baseboard_fab2(sch_1):page145_i208@mstr_discrete.res(chips)!RES_0402-100.0K,1%,1/16W,CHIP,A!R9F4!//jf4cfls225.pdx.intel.com/apd_proj/ppg_lib/epg_masterlib/logical/mstr_discrete/res/chips/chips.prt!RES!RES_0402-100.0K,1%,1/16W,CHIP,G21796-010!RES!!!F1142!!BMC!!
S!@baseboard_fab2_lib.baseboard_fab2(sch_1):page145_i214@mstr_discrete.res(chips)!RES_0402-100.0K,1%,1/16W,CHIP,A!R9F42!//jf4cfls225.pdx.intel.com/apd_proj/ppg_lib/epg_masterlib/logical/mstr_discrete/res/chips/chips.prt!RES!RES_0402-100.0K,1%,1/16W,CHIP,G21796-010!RES!!!F1141!!BMC!!
S!@baseboard_fab2_lib.baseboard_fab2(sch_1):page145_i216@mstr_discrete.res(chips)!RES_0402-100.0K,1%,1/16W,CHIP,A!R9F43!//jf4cfls225.pdx.intel.com/apd_proj/ppg_lib/epg_masterlib/logical/mstr_discrete/res/chips/chips.prt!RES!RES_0402-100.0K,1%,1/16W,CHIP,G21796-010!RES!!!F1140!!BMC!!
S!@baseboard_fab2_lib.baseboard_fab2(sch_1):page145_i211@mstr_discrete.res(chips)!RES_0402-100.0K,1%,1/16W,CHIP,A!R9F44!//jf4cfls225.pdx.intel.com/apd_proj/ppg_lib/epg_masterlib/logical/mstr_discrete/res/chips/chips.prt!RES!RES_0402-100.0K,1%,1/16W,CHIP,G21796-010!RES!!!F1139!!BMC!!
S!@baseboard_fab2_lib.baseboard_fab2(sch_1):page145_i210@mstr_discrete.res(chips)!RES_0402-100.0K,1%,1/16W,CHIP,A!R9F45!//jf4cfls225.pdx.intel.com/apd_proj/ppg_lib/epg_masterlib/logical/mstr_discrete/res/chips/chips.prt!RES!RES_0402-100.0K,1%,1/16W,CHIP,G21796-010!RES!!!F1138!!BMC!!
S!@baseboard_fab2_lib.baseboard_fab2(sch_1):page145_i218@mstr_discrete.res(chips)!RES_0402-100.0K,1%,1/16W,CHIP,A!R9F46!//jf4cfls225.pdx.intel.com/apd_proj/ppg_lib/epg_masterlib/logical/mstr_discrete/res/chips/chips.prt!RES!RES_0402-100.0K,1%,1/16W,CHIP,G21796-010!RES!!!F1137!!BMC!!
S!@baseboard_fab2_lib.baseboard_fab2(sch_1):page169_i106@mstr_discrete.res(chips)!RES_0402-100.0K,1%,1/16W,CHIP,A!R9G26!//jf4cfls225.pdx.intel.com/apd_proj/ppg_lib/epg_masterlib/logical/mstr_discrete/res/chips/chips.prt!RES!RES_0402-100.0K,1%,1/16W,CHIP,G21796-010!RES!!!F1136!!BMC_VOLT_MONITOR!!
S!@baseboard_fab2_lib.baseboard_fab2(sch_1):page199_i54@mstr_discrete.res(chips)!RES_0402-100.0K,1%,1/16W,CHIP,A!R9P23!//jf4cfls225.pdx.intel.com/apd_proj/ppg_lib/epg_masterlib/logical/mstr_discrete/res/chips/chips.prt!RES!RES_0402-100.0K,1%,1/16W,CHIP,G21796-010!RES!!!F1135!!HOT_SWAP!!
S!@baseboard_fab2_lib.baseboard_fab2(sch_1):page199_i6@mstr_discrete.res(chips)!RES_0402-100.0K,1%,1/16W,CHIP,A!R9P28!//jf4cfls225.pdx.intel.com/apd_proj/ppg_lib/epg_masterlib/logical/mstr_discrete/res/chips/chips.prt!RES!RES_0402-100.0K,1%,1/16W,CHIP,G21796-010!RES!!!F1134!!HOT_SWAP!!
S!@baseboard_fab2_lib.baseboard_fab2(sch_1):page199_i12@mstr_discrete.res(chips)!RES_0402-100.0K,1%,1/16W,CHIP,A!R9P29!//jf4cfls225.pdx.intel.com/apd_proj/ppg_lib/epg_masterlib/logical/mstr_discrete/res/chips/chips.prt!RES!RES_0402-100.0K,1%,1/16W,CHIP,G21796-010!RES!!!F1133!!HOT_SWAP!!
S!@baseboard_fab2_lib.baseboard_fab2(sch_1):page196_i112@mstr_discrete.res(chips)!RES_0402-100.0K,1%,1/16W,CHIP,A!R8D38!//jf4cfls225.pdx.intel.com/apd_proj/ppg_lib/epg_masterlib/logical/mstr_discrete/res/chips/chips.prt!RES!RES_0402-100.0K,1%,1/16W,CHIP,G21796-010!RES!!!F1132!!V_SUPER!!
S!@baseboard_fab2_lib.baseboard_fab2(sch_1):page200_i222@mstr_discrete.res(chips)!RES_0402-100.0K,1%,1/16W,CHIP,A!R9P33!//jf4cfls225.pdx.intel.com/apd_proj/ppg_lib/epg_masterlib/logical/mstr_discrete/res/chips/chips.prt!RES!RES_0402-100.0K,1%,1/16W,CHIP,G21796-010!RES!!!F1131!!HOT_SWAP!!
S!@baseboard_fab2_lib.baseboard_fab2(sch_1):page200_i220@mstr_discrete.diode(chips)!DIODE_SM-MBRS340T3G,EMPTY,C819A!CR1F5!//jf4cfls225.pdx.intel.com/apd_proj/ppg_lib/epg_masterlib/logical/mstr_discrete/diode/chips/chips.prt!DIODE!DIODE_SM-MBRS340T3G,EMPTY,C81983-002!DIODE_SM!!!F2218!!!!
S!@baseboard_fab2_lib.baseboard_fab2(sch_1):page211_i93@mstr_controller.pxe1110b(chips)!PXE1110B_QFN-IC,H89187-001!EU3P1!//jf4cfls225.pdx.intel.com/apd_proj/ppg_lib/epg_masterlib/logical/mstr_controller/pxe1110b/chips/chips.prt!PXE1110B!PXE1110B_QFN-IC,H89187-001!PXE1110B_QFN!!!F1976!!!!
S!@baseboard_fab2_lib.baseboard_fab2(sch_1):page213_i96@mstr_controller.pxe1110b(chips)!PXE1110B_QFN-IC,H89187-001!EU4D5!//jf4cfls225.pdx.intel.com/apd_proj/ppg_lib/epg_masterlib/logical/mstr_controller/pxe1110b/chips/chips.prt!PXE1110B!PXE1110B_QFN-IC,H89187-001!PXE1110B_QFN!!!F1975!!!!
S!@baseboard_fab2_lib.baseboard_fab2(sch_1):page235_i229@mstr_controller.pxe1110b(chips)!PXE1110B_QFN-IC,H89187-001!EU8A1!//jf4cfls225.pdx.intel.com/apd_proj/ppg_lib/epg_masterlib/logical/mstr_controller/pxe1110b/chips/chips.prt!PXE1110B!PXE1110B_QFN-IC,H89187-001!PXE1110B_QFN!!!F1974!!!!
S!@baseboard_fab2_lib.baseboard_fab2(sch_1):page226_i90@mstr_controller.pxm1310b(chips)!PXM1310B_QFN-IC,H89186-001!EU1B1!//jf4cfls225.pdx.intel.com/apd_proj/ppg_lib/epg_masterlib/logical/mstr_controller/pxm1310b/chips/chips.prt!PXM1310B!PXM1310B_QFN-IC,H89186-001!PXM1310B_QFN!!!F1971!!!!
S!@baseboard_fab2_lib.baseboard_fab2(sch_1):page223_i90@mstr_controller.pxm1310b(chips)!PXM1310B_QFN-IC,H89186-001!EU1G2!//jf4cfls225.pdx.intel.com/apd_proj/ppg_lib/epg_masterlib/logical/mstr_controller/pxm1310b/chips/chips.prt!PXM1310B!PXM1310B_QFN-IC,H89186-001!PXM1310B_QFN!!!F1970!!!!
S!@baseboard_fab2_lib.baseboard_fab2(sch_1):page218_i75@mstr_controller.pxm1310b(chips)!PXM1310B_QFN-IC,H89186-001!EU7A5!//jf4cfls225.pdx.intel.com/apd_proj/ppg_lib/epg_masterlib/logical/mstr_controller/pxm1310b/chips/chips.prt!PXM1310B!PXM1310B_QFN-IC,H89186-001!PXM1310B_QFN!!!F1969!!!!
S!@baseboard_fab2_lib.baseboard_fab2(sch_1):page215_i358@mstr_controller.pxm1310b(chips)!PXM1310B_QFN-IC,H89186-001!EU7G1!//jf4cfls225.pdx.intel.com/apd_proj/ppg_lib/epg_masterlib/logical/mstr_controller/pxm1310b/chips/chips.prt!PXM1310B!PXM1310B_QFN-IC,H89186-001!PXM1310B_QFN!!!F1968!!!!
S!@baseboard_fab2_lib.baseboard_fab2(sch_1):page206_i49@mstr_discrete.res(chips)!RES_0402-100.0K,1%,1/16W,CHIP,B!R1C13!//jf4cfls225.pdx.intel.com/apd_proj/ppg_lib/epg_masterlib/logical/mstr_discrete/res/chips/chips.prt!RES!RES_0402-100.0K,1%,1/16W,CHIP,G21796-160!RES!!!F1130!!PVCCIN_CPU1_VR!!
S!@baseboard_fab2_lib.baseboard_fab2(sch_1):page218_i53@mstr_discrete.res(chips)!RES_0402-100.0K,1%,1/16W,CHIP,B!R3L12!//jf4cfls225.pdx.intel.com/apd_proj/ppg_lib/epg_masterlib/logical/mstr_discrete/res/chips/chips.prt!RES!RES_0402-100.0K,1%,1/16W,CHIP,G21796-160!RES!!!F1129!!VDDQ_DEF_PWR_VR!!
S!@baseboard_fab2_lib.baseboard_fab2(sch_1):page211_i31@mstr_discrete.res(chips)!RES_0402-100.0K,1%,1/16W,CHIP,B!R3P12!//jf4cfls225.pdx.intel.com/apd_proj/ppg_lib/epg_masterlib/logical/mstr_discrete/res/chips/chips.prt!RES!RES_0402-100.0K,1%,1/16W,CHIP,G21796-160!RES!!!F1128!!PVCCIO_CPU0!!
S!@baseboard_fab2_lib.baseboard_fab2(sch_1):page201_i54@mstr_discrete.res(chips)!RES_0402-100.0K,1%,1/16W,CHIP,B!R4D27!//jf4cfls225.pdx.intel.com/apd_proj/ppg_lib/epg_masterlib/logical/mstr_discrete/res/chips/chips.prt!RES!RES_0402-100.0K,1%,1/16W,CHIP,G21796-160!RES!!!F1127!!PVCCIN_CPU0_VR!!
S!@baseboard_fab2_lib.baseboard_fab2(sch_1):page213_i31@mstr_discrete.res(chips)!RES_0402-100.0K,1%,1/16W,CHIP,B!R4D60!//jf4cfls225.pdx.intel.com/apd_proj/ppg_lib/epg_masterlib/logical/mstr_discrete/res/chips/chips.prt!RES!RES_0402-100.0K,1%,1/16W,CHIP,G21796-160!RES!!!F1126!!PVCCIO_CPU1!!
S!@baseboard_fab2_lib.baseboard_fab2(sch_1):page215_i336@mstr_discrete.res(chips)!RES_0402-100.0K,1%,1/16W,CHIP,B!R7F34!//jf4cfls225.pdx.intel.com/apd_proj/ppg_lib/epg_masterlib/logical/mstr_discrete/res/chips/chips.prt!RES!RES_0402-100.0K,1%,1/16W,CHIP,G21796-160!RES!!!F1125!!VDDQ_ABC_PWR_VR!!
S!@baseboard_fab2_lib.baseboard_fab2(sch_1):page235_i165@mstr_discrete.res(chips)!RES_0402-100.0K,1%,1/16W,CHIP,B!R8A4!//jf4cfls225.pdx.intel.com/apd_proj/ppg_lib/epg_masterlib/logical/mstr_discrete/res/chips/chips.prt!RES!RES_0402-100.0K,1%,1/16W,CHIP,G21796-160!RES!!!F1124!!PVNN_PCH_STBY!!
S!@baseboard_fab2_lib.baseboard_fab2(sch_1):page226_i57@mstr_discrete.res(chips)!RES_0402-100.0K,1%,1/16W,CHIP,B!R9M8!//jf4cfls225.pdx.intel.com/apd_proj/ppg_lib/epg_masterlib/logical/mstr_discrete/res/chips/chips.prt!RES!RES_0402-100.0K,1%,1/16W,CHIP,G21796-160!RES!!!F1123!!VDDQ_KLM_PWR_VR!!
S!@baseboard_fab2_lib.baseboard_fab2(sch_1):page223_i57@mstr_discrete.res(chips)!RES_0402-100.0K,1%,1/16W,CHIP,B!R9U11!//jf4cfls225.pdx.intel.com/apd_proj/ppg_lib/epg_masterlib/logical/mstr_discrete/res/chips/chips.prt!RES!RES_0402-100.0K,1%,1/16W,CHIP,G21796-160!RES!!!F1122!!VDDQ_GHJ_PWR_VR!!
S!@baseboard_fab2_lib.baseboard_fab2(sch_1):page226_i78@mstr_discrete.res(chips)!RES_0402-3.16K,1%,1/16W,CHIP,GA!R1B12!//jf4cfls225.pdx.intel.com/apd_proj/ppg_lib/epg_masterlib/logical/mstr_discrete/res/chips/chips.prt!RES!RES_0402-3.16K,1%,1/16W,CHIP,G21796-043!RES!!!F780!!VDDQ_KLM_PWR_VR!!
S!@baseboard_fab2_lib.baseboard_fab2(sch_1):page211_i52@mstr_discrete.res(chips)!RES_0402-3.16K,1%,1/16W,CHIP,GA!R3N31!//jf4cfls225.pdx.intel.com/apd_proj/ppg_lib/epg_masterlib/logical/mstr_discrete/res/chips/chips.prt!RES!RES_0402-3.16K,1%,1/16W,CHIP,G21796-043!RES!!!F779!!PVCCIO_CPU0!!
S!@baseboard_fab2_lib.baseboard_fab2(sch_1):page213_i42@mstr_discrete.res(chips)!RES_0402-3.16K,1%,1/16W,CHIP,GA!R4D64!//jf4cfls225.pdx.intel.com/apd_proj/ppg_lib/epg_masterlib/logical/mstr_discrete/res/chips/chips.prt!RES!RES_0402-3.16K,1%,1/16W,CHIP,G21796-043!RES!!!F778!!PVCCIO_CPU1!!
S!@baseboard_fab2_lib.baseboard_fab2(sch_1):page213_i65@mstr_discrete.res(chips)!RES_0402-3.16K,1%,1/16W,CHIP,GA!R4E2!//jf4cfls225.pdx.intel.com/apd_proj/ppg_lib/epg_masterlib/logical/mstr_discrete/res/chips/chips.prt!RES!RES_0402-3.16K,1%,1/16W,CHIP,G21796-043!RES!!!F777!!!!
S!@baseboard_fab2_lib.baseboard_fab2(sch_1):page218_i40@mstr_discrete.res(chips)!RES_0402-3.16K,1%,1/16W,CHIP,GA!R7A10!//jf4cfls225.pdx.intel.com/apd_proj/ppg_lib/epg_masterlib/logical/mstr_discrete/res/chips/chips.prt!RES!RES_0402-3.16K,1%,1/16W,CHIP,G21796-043!RES!!!F776!!VDDQ_DEF_PWR_VR!!
S!@baseboard_fab2_lib.baseboard_fab2(sch_1):page206_i111@mstr_discrete.res(chips)!RES_0402-3.16K,1%,1/16W,CHIP,GA!R9N7!//jf4cfls225.pdx.intel.com/apd_proj/ppg_lib/epg_masterlib/logical/mstr_discrete/res/chips/chips.prt!RES!RES_0402-3.16K,1%,1/16W,CHIP,G21796-043!RES!!!F775!!PVCCIN_CPU1_VR!!
S!@baseboard_fab2_lib.baseboard_fab2(sch_1):page193_i170@mstr_discrete.res(chips)!RES_0402-3.16K,1%,1/16W,CHIP,GA!R4C11!//jf4cfls225.pdx.intel.com/apd_proj/ppg_lib/epg_masterlib/logical/mstr_discrete/res/chips/chips.prt!RES!RES_0402-3.16K,1%,1/16W,CHIP,G21796-043!RES!!!F774!!PVCCIN_CPU0_VR!!
S!@baseboard_fab2_lib.baseboard_fab2(sch_1):page111_i26@mstr_sconn.sconn60_c21100002(chips)!SCONN60_C21100002_SMLF-CONN,C2A!J9A3!//jf4cfls225.pdx.intel.com/apd_proj/ppg_lib/epg_masterlib/logical/mstr_sconn/sconn60_c21100002/chips/chips.prt!SCONN60_C21100002!SCONN60_C21100002_SMLF-CONN,C21100-002!SCONN60_C21100002!!!F135!!DEBUG!!
S!@baseboard_fab2_lib.baseboard_fab2(sch_1):page162_i32@mstr_memory.w25q128(chips)!W25Q128_SKT16-IC,H12709-001!U8F2!//jf4cfls225.pdx.intel.com/apd_proj/ppg_lib/epg_masterlib/logical/mstr_memory/w25q128/chips/chips.prt!W25Q128!W25Q128_SKT16-IC,H12709-001!W25Q128_SKT16!!!F3!!BMC_BOOT_SPI!!
S!@baseboard_fab2_lib.baseboard_fab2(sch_1):page206_i130@mstr_controller.pxe1610b(chips)!PXE1610B_QFN-IC,H79206-001!EU1C2!//jf4cfls225.pdx.intel.com/apd_proj/ppg_lib/epg_masterlib/logical/mstr_controller/pxe1610b/chips/chips.prt!PXE1610B!PXE1610B_QFN-IC,H79206-001!PXE1610B_QFN!!!F1973!!!!
S!@baseboard_fab2_lib.baseboard_fab2(sch_1):page201_i155@mstr_controller.pxe1610b(chips)!PXE1610B_QFN-IC,H79206-001!EU4D4!//jf4cfls225.pdx.intel.com/apd_proj/ppg_lib/epg_masterlib/logical/mstr_controller/pxe1610b/chips/chips.prt!PXE1610B!PXE1610B_QFN-IC,H79206-001!PXE1610B_QFN!!!F1972!!!!
S!@baseboard_fab2_lib.baseboard_fab2(sch_1):page196_i113@mstr_discrete.res(chips)!RES_0402-3.74K,1%,1/16W,CHIP,GA!R8D40!//jf4cfls225.pdx.intel.com/apd_proj/ppg_lib/epg_masterlib/logical/mstr_discrete/res/chips/chips.prt!RES!RES_0402-3.74K,1%,1/16W,CHIP,G21796-059!RES!!!F760!!V_SUPER!!
S!@baseboard_fab2_lib.baseboard_fab2(sch_1):page113_i175@mstr_sconn.sconn10_c12536004(chips)!SCONN10_C12536004_SMLF-CONN,C1A!J9B4!//jf4cfls225.pdx.intel.com/apd_proj/ppg_lib/epg_masterlib/logical/mstr_sconn/sconn10_c12536004/chips/chips.prt!SCONN10_C12536004!SCONN10_C12536004_SMLF-CONN,C12536-004!SCONN10_C12536004!!!F242!!DEBUG!!
S!@baseboard_fab2_lib.baseboard_fab2(sch_1):page227_i75@mstr_discrete.cap(chips)!CAP_0402-0.220UF,16V,10%,X7R,AA!C1A8!//jf4cfls225.pdx.intel.com/apd_proj/ppg_lib/epg_masterlib/logical/mstr_discrete/cap/chips/chips.prt!CAP!CAP_0402-0.220UF,16V,10%,X7R,A36096-104!CAP_0402!!!F4076!!VDDQ_KLM_PWR_VR!!
S!@baseboard_fab2_lib.baseboard_fab2(sch_1):page227_i44@mstr_discrete.cap(chips)!CAP_0402-0.220UF,16V,10%,X7R,AA!C1A18!//jf4cfls225.pdx.intel.com/apd_proj/ppg_lib/epg_masterlib/logical/mstr_discrete/cap/chips/chips.prt!CAP!CAP_0402-0.220UF,16V,10%,X7R,A36096-104!CAP_0402!!!F4075!!VDDQ_KLM_PWR_VR!!
S!@baseboard_fab2_lib.baseboard_fab2(sch_1):page210_i24@mstr_discrete.cap(chips)!CAP_0402-0.220UF,16V,10%,X7R,AA!C1C12!//jf4cfls225.pdx.intel.com/apd_proj/ppg_lib/epg_masterlib/logical/mstr_discrete/cap/chips/chips.prt!CAP!CAP_0402-0.220UF,16V,10%,X7R,A36096-104!CAP_0402!!!F4074!!PVSA_CPU1_PWR_VR!!
S!@baseboard_fab2_lib.baseboard_fab2(sch_1):page209_i20@mstr_discrete.cap(chips)!CAP_0402-0.220UF,16V,10%,X7R,AA!C1C24!//jf4cfls225.pdx.intel.com/apd_proj/ppg_lib/epg_masterlib/logical/mstr_discrete/cap/chips/chips.prt!CAP!CAP_0402-0.220UF,16V,10%,X7R,A36096-104!CAP_0402!!!F4073!!PVCCIN_CPU1_PWR_VR!!
S!@baseboard_fab2_lib.baseboard_fab2(sch_1):page208_i48@mstr_discrete.cap(chips)!CAP_0402-0.220UF,16V,10%,X7R,AA!C1D10!//jf4cfls225.pdx.intel.com/apd_proj/ppg_lib/epg_masterlib/logical/mstr_discrete/cap/chips/chips.prt!CAP!CAP_0402-0.220UF,16V,10%,X7R,A36096-104!CAP_0402!!!F4072!!PVCCIN_CPU1_PWR_VR!!
S!@baseboard_fab2_lib.baseboard_fab2(sch_1):page208_i40@mstr_discrete.cap(chips)!CAP_0402-0.220UF,16V,10%,X7R,AA!C1D20!//jf4cfls225.pdx.intel.com/apd_proj/ppg_lib/epg_masterlib/logical/mstr_discrete/cap/chips/chips.prt!CAP!CAP_0402-0.220UF,16V,10%,X7R,A36096-104!CAP_0402!!!F4071!!PVCCIN_CPU1_PWR_VR!!
S!@baseboard_fab2_lib.baseboard_fab2(sch_1):page224_i75@mstr_discrete.cap(chips)!CAP_0402-0.220UF,16V,10%,X7R,AA!C1F26!//jf4cfls225.pdx.intel.com/apd_proj/ppg_lib/epg_masterlib/logical/mstr_discrete/cap/chips/chips.prt!CAP!CAP_0402-0.220UF,16V,10%,X7R,A36096-104!CAP_0402!!!F4068!!VDDQ_GHJ_PWR_VR!!
S!@baseboard_fab2_lib.baseboard_fab2(sch_1):page224_i44@mstr_discrete.cap(chips)!CAP_0402-0.220UF,16V,10%,X7R,AA!C1G11!//jf4cfls225.pdx.intel.com/apd_proj/ppg_lib/epg_masterlib/logical/mstr_discrete/cap/chips/chips.prt!CAP!CAP_0402-0.220UF,16V,10%,X7R,A36096-104!CAP_0402!!!F4067!!VDDQ_GHJ_PWR_VR!!
S!@baseboard_fab2_lib.baseboard_fab2(sch_1):page205_i25@mstr_discrete.cap(chips)!CAP_0402-0.220UF,16V,10%,X7R,AA!C4C8!//jf4cfls225.pdx.intel.com/apd_proj/ppg_lib/epg_masterlib/logical/mstr_discrete/cap/chips/chips.prt!CAP!CAP_0402-0.220UF,16V,10%,X7R,A36096-104!CAP_0402!!!F4066!!PVSA_CPU0_PWR_VR!!
S!@baseboard_fab2_lib.baseboard_fab2(sch_1):page204_i22@mstr_discrete.cap(chips)!CAP_0402-0.220UF,16V,10%,X7R,AA!C4C17!//jf4cfls225.pdx.intel.com/apd_proj/ppg_lib/epg_masterlib/logical/mstr_discrete/cap/chips/chips.prt!CAP!CAP_0402-0.220UF,16V,10%,X7R,A36096-104!CAP_0402!!!F4065!!PVCCIN_CPU0_PWR_VR!!
S!@baseboard_fab2_lib.baseboard_fab2(sch_1):page203_i3@mstr_discrete.cap(chips)!CAP_0402-0.220UF,16V,10%,X7R,AA!C4D9!//jf4cfls225.pdx.intel.com/apd_proj/ppg_lib/epg_masterlib/logical/mstr_discrete/cap/chips/chips.prt!CAP!CAP_0402-0.220UF,16V,10%,X7R,A36096-104!CAP_0402!!!F4064!!PVCCIN_CPU0_PWR_VR!!
S!@baseboard_fab2_lib.baseboard_fab2(sch_1):page203_i42@mstr_discrete.cap(chips)!CAP_0402-0.220UF,16V,10%,X7R,AA!C4D28!//jf4cfls225.pdx.intel.com/apd_proj/ppg_lib/epg_masterlib/logical/mstr_discrete/cap/chips/chips.prt!CAP!CAP_0402-0.220UF,16V,10%,X7R,A36096-104!CAP_0402!!!F4063!!PVCCIN_CPU0_PWR_VR!!
S!@baseboard_fab2_lib.baseboard_fab2(sch_1):page202_i32@mstr_discrete.cap(chips)!CAP_0402-0.220UF,16V,10%,X7R,AA!C4D50!//jf4cfls225.pdx.intel.com/apd_proj/ppg_lib/epg_masterlib/logical/mstr_discrete/cap/chips/chips.prt!CAP!CAP_0402-0.220UF,16V,10%,X7R,A36096-104!CAP_0402!!!F4062!!PVCCIN_CPU0_PWR_VR!!
S!@baseboard_fab2_lib.baseboard_fab2(sch_1):page202_i22@mstr_discrete.cap(chips)!CAP_0402-0.220UF,16V,10%,X7R,AA!C4E17!//jf4cfls225.pdx.intel.com/apd_proj/ppg_lib/epg_masterlib/logical/mstr_discrete/cap/chips/chips.prt!CAP!CAP_0402-0.220UF,16V,10%,X7R,A36096-104!CAP_0402!!!F4061!!PVCCIN_CPU0_PWR_VR!!
S!@baseboard_fab2_lib.baseboard_fab2(sch_1):page214_i78@mstr_discrete.cap(chips)!CAP_0402-0.220UF,16V,10%,X7R,AA!C4E18!//jf4cfls225.pdx.intel.com/apd_proj/ppg_lib/epg_masterlib/logical/mstr_discrete/cap/chips/chips.prt!CAP!CAP_0402-0.220UF,16V,10%,X7R,A36096-104!CAP_0402!!!F4060!!PVCCIO_CPU1!!
S!@baseboard_fab2_lib.baseboard_fab2(sch_1):page236_i21@mstr_discrete.cap(chips)!CAP_0402-0.220UF,16V,10%,X7R,AA!C3L30!//jf4cfls225.pdx.intel.com/apd_proj/ppg_lib/epg_masterlib/logical/mstr_discrete/cap/chips/chips.prt!CAP!CAP_0402-0.220UF,16V,10%,X7R,A36096-104!CAP_0402!!!F4059!!PVNN_PCH_STBY!!
S!@baseboard_fab2_lib.baseboard_fab2(sch_1):page236_i34@mstr_discrete.cap(chips)!CAP_0402-0.220UF,16V,10%,X7R,AA!C3L28!//jf4cfls225.pdx.intel.com/apd_proj/ppg_lib/epg_masterlib/logical/mstr_discrete/cap/chips/chips.prt!CAP!CAP_0402-0.220UF,16V,10%,X7R,A36096-104!CAP_0402!!!F4058!!P1V05_PCH_STBY_VR!!
S!@baseboard_fab2_lib.baseboard_fab2(sch_1):page219_i44@mstr_discrete.cap(chips)!CAP_0402-0.220UF,16V,10%,X7R,AA!C7A12!//jf4cfls225.pdx.intel.com/apd_proj/ppg_lib/epg_masterlib/logical/mstr_discrete/cap/chips/chips.prt!CAP!CAP_0402-0.220UF,16V,10%,X7R,A36096-104!CAP_0402!!!F4057!!VDDQ_DEF_PWR_VR!!
S!@baseboard_fab2_lib.baseboard_fab2(sch_1):page219_i75@mstr_discrete.cap(chips)!CAP_0402-0.220UF,16V,10%,X7R,AA!C7A22!//jf4cfls225.pdx.intel.com/apd_proj/ppg_lib/epg_masterlib/logical/mstr_discrete/cap/chips/chips.prt!CAP!CAP_0402-0.220UF,16V,10%,X7R,A36096-104!CAP_0402!!!F4056!!VDDQ_DEF_PWR_VR!!
S!@baseboard_fab2_lib.baseboard_fab2(sch_1):page212_i37@mstr_discrete.cap(chips)!CAP_0402-0.220UF,16V,10%,X7R,AA!C7C14!//jf4cfls225.pdx.intel.com/apd_proj/ppg_lib/epg_masterlib/logical/mstr_discrete/cap/chips/chips.prt!CAP!CAP_0402-0.220UF,16V,10%,X7R,A36096-104!CAP_0402!!!F4055!!PVCCIO_CPU0!!
S!@baseboard_fab2_lib.baseboard_fab2(sch_1):page216_i44@mstr_discrete.cap(chips)!CAP_0402-0.220UF,16V,10%,X7R,AA!C7G31!//jf4cfls225.pdx.intel.com/apd_proj/ppg_lib/epg_masterlib/logical/mstr_discrete/cap/chips/chips.prt!CAP!CAP_0402-0.220UF,16V,10%,X7R,A36096-104!CAP_0402!!!F4054!!VDDQ_ABC_PWR_VR!!
S!@baseboard_fab2_lib.baseboard_fab2(sch_1):page216_i75@mstr_discrete.cap(chips)!CAP_0402-0.220UF,16V,10%,X7R,AA!C7G38!//jf4cfls225.pdx.intel.com/apd_proj/ppg_lib/epg_masterlib/logical/mstr_discrete/cap/chips/chips.prt!CAP!CAP_0402-0.220UF,16V,10%,X7R,A36096-104!CAP_0402!!!F4053!!VDDQ_ABC_PWR_VR!!
S!@baseboard_fab2_lib.baseboard_fab2(sch_1):page207_i38@mstr_discrete.cap(chips)!CAP_0402-0.220UF,16V,10%,X7R,AA!C1D36!//jf4cfls225.pdx.intel.com/apd_proj/ppg_lib/epg_masterlib/logical/mstr_discrete/cap/chips/chips.prt!CAP!CAP_0402-0.220UF,16V,10%,X7R,A36096-104!CAP_0402!!!F4070!!PVCCIN_CPU1_PWR_VR!!
S!@baseboard_fab2_lib.baseboard_fab2(sch_1):page207_i30@mstr_discrete.cap(chips)!CAP_0402-0.220UF,16V,10%,X7R,AA!C1E11!//jf4cfls225.pdx.intel.com/apd_proj/ppg_lib/epg_masterlib/logical/mstr_discrete/cap/chips/chips.prt!CAP!CAP_0402-0.220UF,16V,10%,X7R,A36096-104!CAP_0402!!!F4069!!PVCCIN_CPU1_PWR_VR!!
S!@baseboard_fab2_lib.baseboard_fab2(sch_1):page172_i17@mstr_conn.conn7_e82125014(chips)!CONN7_E82125014_PIP_TH-CONN,E8A!J8A3!//jf4cfls225.pdx.intel.com/apd_proj/ppg_lib/epg_masterlib/logical/mstr_conn/conn7_e82125014/chips/chips.prt!CONN7_E82125014!CONN7_E82125014_PIP_TH-CONN,E82125-014!CONN7_E82125014_PIP_TH!!!F2237!!ST_SATA!!
S!@baseboard_fab2_lib.baseboard_fab2(sch_1):page172_i52@mstr_conn.conn7_e82125014(chips)!CONN7_E82125014_PIP_TH-EMPTY,EA!J2M1!//jf4cfls225.pdx.intel.com/apd_proj/ppg_lib/epg_masterlib/logical/mstr_conn/conn7_e82125014/chips/chips.prt!CONN7_E82125014!CONN7_E82125014_PIP_TH-EMPTY,E82125-014!CONN7_E82125014_PIP_TH!!!F2236!!ST_SATA!!
S!@baseboard_fab2_lib.baseboard_fab2(sch_1):page214_i126@mstr_discrete.ir354xx(chips)!IR354XX_SM-IR35412,IC,H73684-0A!EU4E2!//jf4cfls225.pdx.intel.com/apd_proj/ppg_lib/epg_masterlib/logical/mstr_discrete/ir354xx/chips/chips.prt!IR354XX!IR354XX_SM-IR35412,IC,H73684-001!IR354XX_SM!!!F2060!!!!
S!@baseboard_fab2_lib.baseboard_fab2(sch_1):page236_i117@mstr_discrete.ir354xx(chips)!IR354XX_SM-IR35412,IC,H73684-0A!EU7A2!//jf4cfls225.pdx.intel.com/apd_proj/ppg_lib/epg_masterlib/logical/mstr_discrete/ir354xx/chips/chips.prt!IR354XX!IR354XX_SM-IR35412,IC,H73684-001!IR354XX_SM!!!F2059!!!!
S!@baseboard_fab2_lib.baseboard_fab2(sch_1):page236_i116@mstr_discrete.ir354xx(chips)!IR354XX_SM-IR35412,IC,H73684-0A!EU7A3!//jf4cfls225.pdx.intel.com/apd_proj/ppg_lib/epg_masterlib/logical/mstr_discrete/ir354xx/chips/chips.prt!IR354XX!IR354XX_SM-IR35412,IC,H73684-001!IR354XX_SM!!!F2058!!!!
S!@baseboard_fab2_lib.baseboard_fab2(sch_1):page212_i101@mstr_discrete.ir354xx(chips)!IR354XX_SM-IR35412,IC,H73684-0A!EU7C1!//jf4cfls225.pdx.intel.com/apd_proj/ppg_lib/epg_masterlib/logical/mstr_discrete/ir354xx/chips/chips.prt!IR354XX!IR354XX_SM-IR35412,IC,H73684-001!IR354XX_SM!!!F2057!!!!
S!@baseboard_fab2_lib.baseboard_fab2(sch_1):page210_i51@mstr_discrete.ir354xx(chips)!IR354XX_SM-IR35412,IC,H73684-0A!EU1C1!//jf4cfls225.pdx.intel.com/apd_proj/ppg_lib/epg_masterlib/logical/mstr_discrete/ir354xx/chips/chips.prt!IR354XX!IR354XX_SM-IR35412,IC,H73684-001!IR354XX_SM!!!F2062!!!!
S!@baseboard_fab2_lib.baseboard_fab2(sch_1):page205_i46@mstr_discrete.ir354xx(chips)!IR354XX_SM-IR35412,IC,H73684-0A!EU4C1!//jf4cfls225.pdx.intel.com/apd_proj/ppg_lib/epg_masterlib/logical/mstr_discrete/ir354xx/chips/chips.prt!IR354XX!IR354XX_SM-IR35412,IC,H73684-001!IR354XX_SM!!!F2061!!!!
S!@baseboard_fab2_lib.baseboard_fab2(sch_1):page37_i312@mstr_discrete.res(chips)!RES_0402-10.0,1%,1/16W,EMPTY,GA!R5D6!//jf4cfls225.pdx.intel.com/apd_proj/ppg_lib/epg_masterlib/logical/mstr_discrete/res/chips/chips.prt!RES!RES_0402-10.0,1%,1/16W,EMPTY,G21796-066!RES!!!F1334!!CPU0!!
S!@baseboard_fab2_lib.baseboard_fab2(sch_1):page71_i53@mstr_discrete.res(chips)!RES_0402-10.0,1%,1/16W,EMPTY,GA!R3D32!//jf4cfls225.pdx.intel.com/apd_proj/ppg_lib/epg_masterlib/logical/mstr_discrete/res/chips/chips.prt!RES!RES_0402-10.0,1%,1/16W,EMPTY,G21796-066!RES!!!F1333!!CPU1!!
S!@baseboard_fab2_lib.baseboard_fab2(sch_1):page205_i62@mstr_discrete.res(chips)!RES_0402-68.1K,1%,1/16W,EMPTY,A!R4C13!//jf4cfls225.pdx.intel.com/apd_proj/ppg_lib/epg_masterlib/logical/mstr_discrete/res/chips/chips.prt!RES!RES_0402-68.1K,1%,1/16W,EMPTY,G21796-187!RES!!!F333!!!!
S!@baseboard_fab2_lib.baseboard_fab2(sch_1):page202_i67@mstr_discrete.res(chips)!RES_0402-68.1K,1%,1/16W,EMPTY,A!R4E19!//jf4cfls225.pdx.intel.com/apd_proj/ppg_lib/epg_masterlib/logical/mstr_discrete/res/chips/chips.prt!RES!RES_0402-68.1K,1%,1/16W,EMPTY,G21796-187!RES!!!F332!!!!
S!@baseboard_fab2_lib.baseboard_fab2(sch_1):page202_i65@mstr_discrete.res(chips)!RES_0402-68.1K,1%,1/16W,EMPTY,A!R4E22!//jf4cfls225.pdx.intel.com/apd_proj/ppg_lib/epg_masterlib/logical/mstr_discrete/res/chips/chips.prt!RES!RES_0402-68.1K,1%,1/16W,EMPTY,G21796-187!RES!!!F331!!!!
S!@baseboard_fab2_lib.baseboard_fab2(sch_1):page203_i89@mstr_discrete.res(chips)!RES_0402-68.1K,1%,1/16W,EMPTY,A!R4D72!//jf4cfls225.pdx.intel.com/apd_proj/ppg_lib/epg_masterlib/logical/mstr_discrete/res/chips/chips.prt!RES!RES_0402-68.1K,1%,1/16W,EMPTY,G21796-187!RES!!!F330!!!!
S!@baseboard_fab2_lib.baseboard_fab2(sch_1):page203_i91@mstr_discrete.res(chips)!RES_0402-68.1K,1%,1/16W,EMPTY,A!R4D71!//jf4cfls225.pdx.intel.com/apd_proj/ppg_lib/epg_masterlib/logical/mstr_discrete/res/chips/chips.prt!RES!RES_0402-68.1K,1%,1/16W,EMPTY,G21796-187!RES!!!F329!!!!
S!@baseboard_fab2_lib.baseboard_fab2(sch_1):page204_i83@mstr_discrete.res(chips)!RES_0402-68.1K,1%,1/16W,EMPTY,A!R4D68!//jf4cfls225.pdx.intel.com/apd_proj/ppg_lib/epg_masterlib/logical/mstr_discrete/res/chips/chips.prt!RES!RES_0402-68.1K,1%,1/16W,EMPTY,G21796-187!RES!!!F328!!!!
S!@baseboard_fab2_lib.baseboard_fab2(sch_1):page212_i103@mstr_discrete.res(chips)!RES_0402-68.1K,1%,1/16W,EMPTY,A!R7C25!//jf4cfls225.pdx.intel.com/apd_proj/ppg_lib/epg_masterlib/logical/mstr_discrete/res/chips/chips.prt!RES!RES_0402-68.1K,1%,1/16W,EMPTY,G21796-187!RES!!!F327!!!!
S!@baseboard_fab2_lib.baseboard_fab2(sch_1):page214_i127@mstr_discrete.res(chips)!RES_0402-68.1K,1%,1/16W,EMPTY,A!R4E21!//jf4cfls225.pdx.intel.com/apd_proj/ppg_lib/epg_masterlib/logical/mstr_discrete/res/chips/chips.prt!RES!RES_0402-68.1K,1%,1/16W,EMPTY,G21796-187!RES!!!F326!!!!
S!@baseboard_fab2_lib.baseboard_fab2(sch_1):page216_i104@mstr_discrete.res(chips)!RES_0402-68.1K,1%,1/16W,EMPTY,A!R7G25!//jf4cfls225.pdx.intel.com/apd_proj/ppg_lib/epg_masterlib/logical/mstr_discrete/res/chips/chips.prt!RES!RES_0402-68.1K,1%,1/16W,EMPTY,G21796-187!RES!!!F325!!!!
S!@baseboard_fab2_lib.baseboard_fab2(sch_1):page216_i106@mstr_discrete.res(chips)!RES_0402-68.1K,1%,1/16W,EMPTY,A!R7G30!//jf4cfls225.pdx.intel.com/apd_proj/ppg_lib/epg_masterlib/logical/mstr_discrete/res/chips/chips.prt!RES!RES_0402-68.1K,1%,1/16W,EMPTY,G21796-187!RES!!!F324!!!!
S!@baseboard_fab2_lib.baseboard_fab2(sch_1):page219_i108@mstr_discrete.res(chips)!RES_0402-68.1K,1%,1/16W,EMPTY,A!R7A20!//jf4cfls225.pdx.intel.com/apd_proj/ppg_lib/epg_masterlib/logical/mstr_discrete/res/chips/chips.prt!RES!RES_0402-68.1K,1%,1/16W,EMPTY,G21796-187!RES!!!F323!!!!
S!@baseboard_fab2_lib.baseboard_fab2(sch_1):page219_i110@mstr_discrete.res(chips)!RES_0402-68.1K,1%,1/16W,EMPTY,A!R7A21!//jf4cfls225.pdx.intel.com/apd_proj/ppg_lib/epg_masterlib/logical/mstr_discrete/res/chips/chips.prt!RES!RES_0402-68.1K,1%,1/16W,EMPTY,G21796-187!RES!!!F322!!!!
S!@baseboard_fab2_lib.baseboard_fab2(sch_1):page224_i112@mstr_discrete.res(chips)!RES_0402-68.1K,1%,1/16W,EMPTY,A!R1G26!//jf4cfls225.pdx.intel.com/apd_proj/ppg_lib/epg_masterlib/logical/mstr_discrete/res/chips/chips.prt!RES!RES_0402-68.1K,1%,1/16W,EMPTY,G21796-187!RES!!!F321!!!!
S!@baseboard_fab2_lib.baseboard_fab2(sch_1):page224_i114@mstr_discrete.res(chips)!RES_0402-68.1K,1%,1/16W,EMPTY,A!R1G25!//jf4cfls225.pdx.intel.com/apd_proj/ppg_lib/epg_masterlib/logical/mstr_discrete/res/chips/chips.prt!RES!RES_0402-68.1K,1%,1/16W,EMPTY,G21796-187!RES!!!F320!!!!
S!@baseboard_fab2_lib.baseboard_fab2(sch_1):page227_i105@mstr_discrete.res(chips)!RES_0402-68.1K,1%,1/16W,EMPTY,A!R1A2!//jf4cfls225.pdx.intel.com/apd_proj/ppg_lib/epg_masterlib/logical/mstr_discrete/res/chips/chips.prt!RES!RES_0402-68.1K,1%,1/16W,EMPTY,G21796-187!RES!!!F319!!!!
S!@baseboard_fab2_lib.baseboard_fab2(sch_1):page227_i103@mstr_discrete.res(chips)!RES_0402-68.1K,1%,1/16W,EMPTY,A!R1A3!//jf4cfls225.pdx.intel.com/apd_proj/ppg_lib/epg_masterlib/logical/mstr_discrete/res/chips/chips.prt!RES!RES_0402-68.1K,1%,1/16W,EMPTY,G21796-187!RES!!!F318!!!!
S!@baseboard_fab2_lib.baseboard_fab2(sch_1):page236_i118@mstr_discrete.res(chips)!RES_0402-68.1K,1%,1/16W,EMPTY,A!R3L15!//jf4cfls225.pdx.intel.com/apd_proj/ppg_lib/epg_masterlib/logical/mstr_discrete/res/chips/chips.prt!RES!RES_0402-68.1K,1%,1/16W,EMPTY,G21796-187!RES!!!F317!!!!
S!@baseboard_fab2_lib.baseboard_fab2(sch_1):page236_i120@mstr_discrete.res(chips)!RES_0402-68.1K,1%,1/16W,EMPTY,A!R3L14!//jf4cfls225.pdx.intel.com/apd_proj/ppg_lib/epg_masterlib/logical/mstr_discrete/res/chips/chips.prt!RES!RES_0402-68.1K,1%,1/16W,EMPTY,G21796-187!RES!!!F316!!!!
S!@baseboard_fab2_lib.baseboard_fab2(sch_1):page207_i67@mstr_discrete.res(chips)!RES_0402-68.1K,1%,1/16W,EMPTY,A!R1E13!//jf4cfls225.pdx.intel.com/apd_proj/ppg_lib/epg_masterlib/logical/mstr_discrete/res/chips/chips.prt!RES!RES_0402-68.1K,1%,1/16W,EMPTY,G21796-187!RES!!!F339!!!!
S!@baseboard_fab2_lib.baseboard_fab2(sch_1):page207_i68@mstr_discrete.res(chips)!RES_0402-68.1K,1%,1/16W,EMPTY,A!R1E14!//jf4cfls225.pdx.intel.com/apd_proj/ppg_lib/epg_masterlib/logical/mstr_discrete/res/chips/chips.prt!RES!RES_0402-68.1K,1%,1/16W,EMPTY,G21796-187!RES!!!F338!!!!
S!@baseboard_fab2_lib.baseboard_fab2(sch_1):page208_i76@mstr_discrete.res(chips)!RES_0402-68.1K,1%,1/16W,EMPTY,A!R1D55!//jf4cfls225.pdx.intel.com/apd_proj/ppg_lib/epg_masterlib/logical/mstr_discrete/res/chips/chips.prt!RES!RES_0402-68.1K,1%,1/16W,EMPTY,G21796-187!RES!!!F337!!!!
S!@baseboard_fab2_lib.baseboard_fab2(sch_1):page208_i75@mstr_discrete.res(chips)!RES_0402-68.1K,1%,1/16W,EMPTY,A!R1D54!//jf4cfls225.pdx.intel.com/apd_proj/ppg_lib/epg_masterlib/logical/mstr_discrete/res/chips/chips.prt!RES!RES_0402-68.1K,1%,1/16W,EMPTY,G21796-187!RES!!!F336!!!!
S!@baseboard_fab2_lib.baseboard_fab2(sch_1):page209_i59@mstr_discrete.res(chips)!RES_0402-68.1K,1%,1/16W,EMPTY,A!R1D52!//jf4cfls225.pdx.intel.com/apd_proj/ppg_lib/epg_masterlib/logical/mstr_discrete/res/chips/chips.prt!RES!RES_0402-68.1K,1%,1/16W,EMPTY,G21796-187!RES!!!F335!!!!
S!@baseboard_fab2_lib.baseboard_fab2(sch_1):page210_i52@mstr_discrete.res(chips)!RES_0402-68.1K,1%,1/16W,EMPTY,A!R1C37!//jf4cfls225.pdx.intel.com/apd_proj/ppg_lib/epg_masterlib/logical/mstr_discrete/res/chips/chips.prt!RES!RES_0402-68.1K,1%,1/16W,EMPTY,G21796-187!RES!!!F334!!!!
S!@baseboard_fab2_lib.baseboard_fab2(sch_1):page37_i309@mstr_discrete.res(chips)!RES_0603-100.0K,1%,1/10W,CHIP,A!R5P1!//jf4cfls225.pdx.intel.com/apd_proj/ppg_lib/epg_masterlib/logical/mstr_discrete/res/chips/chips.prt!RES!RES_0603-100.0K,1%,1/10W,CHIP,G22026-050!RES!!!F273!!CPU0!!
S!@baseboard_fab2_lib.baseboard_fab2(sch_1):page71_i49@mstr_discrete.res(chips)!RES_0603-100.0K,1%,1/10W,CHIP,A!RT8P1!//jf4cfls225.pdx.intel.com/apd_proj/ppg_lib/epg_masterlib/logical/mstr_discrete/res/chips/chips.prt!RES!RES_0603-100.0K,1%,1/10W,CHIP,G22026-050!RES!!!F272!!CPU1!!
S!@baseboard_fab2_lib.baseboard_fab2(sch_1):page227_i102@mstr_discrete.ir354xx(chips)!IR354XX_SM-IR35411,IC,H73688-0A!EU1A1!//jf4cfls225.pdx.intel.com/apd_proj/ppg_lib/epg_masterlib/logical/mstr_discrete/ir354xx/chips/chips.prt!IR354XX!IR354XX_SM-IR35411,IC,H73688-001!IR354XX_SM!!!F2080!!!!
S!@baseboard_fab2_lib.baseboard_fab2(sch_1):page227_i101@mstr_discrete.ir354xx(chips)!IR354XX_SM-IR35411,IC,H73688-0A!EU1A2!//jf4cfls225.pdx.intel.com/apd_proj/ppg_lib/epg_masterlib/logical/mstr_discrete/ir354xx/chips/chips.prt!IR354XX!IR354XX_SM-IR35411,IC,H73688-001!IR354XX_SM!!!F2079!!!!
S!@baseboard_fab2_lib.baseboard_fab2(sch_1):page224_i111@mstr_discrete.ir354xx(chips)!IR354XX_SM-IR35411,IC,H73688-0A!EU1F1!//jf4cfls225.pdx.intel.com/apd_proj/ppg_lib/epg_masterlib/logical/mstr_discrete/ir354xx/chips/chips.prt!IR354XX!IR354XX_SM-IR35411,IC,H73688-001!IR354XX_SM!!!F2073!!!!
S!@baseboard_fab2_lib.baseboard_fab2(sch_1):page224_i110@mstr_discrete.ir354xx(chips)!IR354XX_SM-IR35411,IC,H73688-0A!EU1G1!//jf4cfls225.pdx.intel.com/apd_proj/ppg_lib/epg_masterlib/logical/mstr_discrete/ir354xx/chips/chips.prt!IR354XX!IR354XX_SM-IR35411,IC,H73688-001!IR354XX_SM!!!F2072!!!!
S!@baseboard_fab2_lib.baseboard_fab2(sch_1):page219_i106@mstr_discrete.ir354xx(chips)!IR354XX_SM-IR35411,IC,H73688-0A!EU7A1!//jf4cfls225.pdx.intel.com/apd_proj/ppg_lib/epg_masterlib/logical/mstr_discrete/ir354xx/chips/chips.prt!IR354XX!IR354XX_SM-IR35411,IC,H73688-001!IR354XX_SM!!!F2066!!!!
S!@baseboard_fab2_lib.baseboard_fab2(sch_1):page219_i107@mstr_discrete.ir354xx(chips)!IR354XX_SM-IR35411,IC,H73688-0A!EU7A4!//jf4cfls225.pdx.intel.com/apd_proj/ppg_lib/epg_masterlib/logical/mstr_discrete/ir354xx/chips/chips.prt!IR354XX!IR354XX_SM-IR35411,IC,H73688-001!IR354XX_SM!!!F2065!!!!
S!@baseboard_fab2_lib.baseboard_fab2(sch_1):page216_i102@mstr_discrete.ir354xx(chips)!IR354XX_SM-IR35411,IC,H73688-0A!EU7G2!//jf4cfls225.pdx.intel.com/apd_proj/ppg_lib/epg_masterlib/logical/mstr_discrete/ir354xx/chips/chips.prt!IR354XX!IR354XX_SM-IR35411,IC,H73688-001!IR354XX_SM!!!F2064!!!!
S!@baseboard_fab2_lib.baseboard_fab2(sch_1):page216_i103@mstr_discrete.ir354xx(chips)!IR354XX_SM-IR35411,IC,H73688-0A!EU7G3!//jf4cfls225.pdx.intel.com/apd_proj/ppg_lib/epg_masterlib/logical/mstr_discrete/ir354xx/chips/chips.prt!IR354XX!IR354XX_SM-IR35411,IC,H73688-001!IR354XX_SM!!!F2063!!!!
S!@baseboard_fab2_lib.baseboard_fab2(sch_1):page202_i64@mstr_discrete.ir354xx(chips)!IR354XX_SM-IR35411,IC,H73688-0A!EU4D6!//jf4cfls225.pdx.intel.com/apd_proj/ppg_lib/epg_masterlib/logical/mstr_discrete/ir354xx/chips/chips.prt!IR354XX!IR354XX_SM-IR35411,IC,H73688-001!IR354XX_SM!!!F2068!!!!
S!@baseboard_fab2_lib.baseboard_fab2(sch_1):page209_i56@mstr_discrete.ir354xx(chips)!IR354XX_SM-IR35411,IC,H73688-0A!EU1C3!//jf4cfls225.pdx.intel.com/apd_proj/ppg_lib/epg_masterlib/logical/mstr_discrete/ir354xx/chips/chips.prt!IR354XX!IR354XX_SM-IR35411,IC,H73688-001!IR354XX_SM!!!F2078!!PVCCIN_CPU1_PWR_VR!!
S!@baseboard_fab2_lib.baseboard_fab2(sch_1):page208_i71@mstr_discrete.ir354xx(chips)!IR354XX_SM-IR35411,IC,H73688-0A!EU1D1!//jf4cfls225.pdx.intel.com/apd_proj/ppg_lib/epg_masterlib/logical/mstr_discrete/ir354xx/chips/chips.prt!IR354XX!IR354XX_SM-IR35411,IC,H73688-001!IR354XX_SM!!!F2077!!PVCCIN_CPU1_PWR_VR!!
S!@baseboard_fab2_lib.baseboard_fab2(sch_1):page203_i70@mstr_discrete.ir354xx(chips)!IR354XX_SM-IR35411,IC,H73688-0A!EU4D3!//jf4cfls225.pdx.intel.com/apd_proj/ppg_lib/epg_masterlib/logical/mstr_discrete/ir354xx/chips/chips.prt!IR354XX!IR354XX_SM-IR35411,IC,H73688-001!IR354XX_SM!!!F2069!!!!
S!@baseboard_fab2_lib.baseboard_fab2(sch_1):page203_i71@mstr_discrete.ir354xx(chips)!IR354XX_SM-IR35411,IC,H73688-0A!EU4D1!//jf4cfls225.pdx.intel.com/apd_proj/ppg_lib/epg_masterlib/logical/mstr_discrete/ir354xx/chips/chips.prt!IR354XX!IR354XX_SM-IR35411,IC,H73688-001!IR354XX_SM!!!F2070!!!!
S!@baseboard_fab2_lib.baseboard_fab2(sch_1):page204_i71@mstr_discrete.ir354xx(chips)!IR354XX_SM-IR35411,IC,H73688-0A!EU4C2!//jf4cfls225.pdx.intel.com/apd_proj/ppg_lib/epg_masterlib/logical/mstr_discrete/ir354xx/chips/chips.prt!IR354XX!IR354XX_SM-IR35411,IC,H73688-001!IR354XX_SM!!!F2071!!!!
S!@baseboard_fab2_lib.baseboard_fab2(sch_1):page202_i63@mstr_discrete.ir354xx(chips)!IR354XX_SM-IR35411,IC,H73688-0A!EU4E1!//jf4cfls225.pdx.intel.com/apd_proj/ppg_lib/epg_masterlib/logical/mstr_discrete/ir354xx/chips/chips.prt!IR354XX!IR354XX_SM-IR35411,IC,H73688-001!IR354XX_SM!!!F2067!!!!
S!@baseboard_fab2_lib.baseboard_fab2(sch_1):page208_i27@mstr_discrete.ir354xx(chips)!IR354XX_SM-IR35411,IC,H73688-0A!EU1D3!//jf4cfls225.pdx.intel.com/apd_proj/ppg_lib/epg_masterlib/logical/mstr_discrete/ir354xx/chips/chips.prt!IR354XX!IR354XX_SM-IR35411,IC,H73688-001!IR354XX_SM!!!F2076!!PVCCIN_CPU1_PWR_VR!!
S!@baseboard_fab2_lib.baseboard_fab2(sch_1):page207_i24@mstr_discrete.ir354xx(chips)!IR354XX_SM-IR35411,IC,H73688-0A!EU1D4!//jf4cfls225.pdx.intel.com/apd_proj/ppg_lib/epg_masterlib/logical/mstr_discrete/ir354xx/chips/chips.prt!IR354XX!IR354XX_SM-IR35411,IC,H73688-001!IR354XX_SM!!!F2075!!PVCCIN_CPU1_PWR_VR!!
S!@baseboard_fab2_lib.baseboard_fab2(sch_1):page207_i20@mstr_discrete.ir354xx(chips)!IR354XX_SM-IR35411,IC,H73688-0A!EU1E2!//jf4cfls225.pdx.intel.com/apd_proj/ppg_lib/epg_masterlib/logical/mstr_discrete/ir354xx/chips/chips.prt!IR354XX!IR354XX_SM-IR35411,IC,H73688-001!IR354XX_SM!!!F2074!!PVCCIN_CPU1_PWR_VR!!
S!@baseboard_fab2_lib.baseboard_fab2(sch_1):page104_i72@mstr_discrete.osc_c(chips)!OSC_C_6P10-156.25MHZ,OSC,G6383A!Y3F1!//jf4cfls225.pdx.intel.com/apd_proj/ppg_lib/epg_masterlib/logical/mstr_discrete/osc_c/chips/chips.prt!OSC_C!OSC_C_6P10-156.25MHZ,OSC,G63831-004!OSC_C_6P10!!!F1989!!!!
S!@baseboard_fab2_lib.baseboard_fab2(sch_1):page104_i71@mstr_discrete.osc_c(chips)!OSC_C_6P10-156.25MHZ,OSC,G6383A!Y6F1!//jf4cfls225.pdx.intel.com/apd_proj/ppg_lib/epg_masterlib/logical/mstr_discrete/osc_c/chips/chips.prt!OSC_C!OSC_C_6P10-156.25MHZ,OSC,G63831-004!OSC_C_6P10!!!F1988!!!!
S!@baseboard_fab2_lib.baseboard_fab2(sch_1):page170_i12@mstr_ttl.ttl08(chips)!TTL08_QFN15-74LVC08A,IC,D90404B!U8E1!//jf4cfls225.pdx.intel.com/apd_proj/ppg_lib/epg_masterlib/logical/mstr_ttl/ttl08/chips/chips.prt!TTL08!TTL08_QFN15-74LVC08A,IC,D90404-001!TTL08_QFN15!1!!F45!!FAST_PROCHOT!!
S!@baseboard_fab2_lib.baseboard_fab2(sch_1):page181_i243@mstr_ttl.ttl08(chips)!TTL08_QFN15-74LVC08A,IC,D90404B!U8E1!//jf4cfls225.pdx.intel.com/apd_proj/ppg_lib/epg_masterlib/logical/mstr_ttl/ttl08/chips/chips.prt!TTL08!TTL08_QFN15-74LVC08A,IC,D90404-001!TTL08_QFN15!1!!F44!!FAST_PROCHOT!!
S!@baseboard_fab2_lib.baseboard_fab2(sch_1):page170_i11@mstr_ttl.ttl08(chips)!TTL08_QFN15-74LVC08A,IC,D90404B!U8E1!//jf4cfls225.pdx.intel.com/apd_proj/ppg_lib/epg_masterlib/logical/mstr_ttl/ttl08/chips/chips.prt!TTL08!TTL08_QFN15-74LVC08A,IC,D90404-001!TTL08_QFN15!1!!F43!!FAST_PROCHOT!!
S!@baseboard_fab2_lib.baseboard_fab2(sch_1):page170_i10@mstr_ttl.ttl08(chips)!TTL08_QFN15-74LVC08A,IC,D90404B!U8E1!//jf4cfls225.pdx.intel.com/apd_proj/ppg_lib/epg_masterlib/logical/mstr_ttl/ttl08/chips/chips.prt!TTL08!TTL08_QFN15-74LVC08A,IC,D90404-001!TTL08_QFN15!1!!F42!!FAST_PROCHOT!!
S!@baseboard_fab2_lib.baseboard_fab2(sch_1):page161_i121@mstr_ttl.ttl1g08(chips)!TTL1G08_SOTLF-NC7SZ08,IC,D1032B!U1E2!//jf4cfls225.pdx.intel.com/apd_proj/ppg_lib/epg_masterlib/logical/mstr_ttl/ttl1g08/chips/chips.prt!TTL1G08!TTL1G08_SOTLF-NC7SZ08,IC,D10321-001!TTL1G08!1!!F32!!CPU_FANS!!
S!@baseboard_fab2_lib.baseboard_fab2(sch_1):page95_i117@mstr_ttl.ttl1g08(chips)!TTL1G08_SOTLF-NC7SZ08,IC,D1032B!U7E2!//jf4cfls225.pdx.intel.com/apd_proj/ppg_lib/epg_masterlib/logical/mstr_ttl/ttl1g08/chips/chips.prt!TTL1G08!TTL1G08_SOTLF-NC7SZ08,IC,D10321-001!TTL1G08!1!!F31!!CAT_ERR!!
S!@baseboard_fab2_lib.baseboard_fab2(sch_1):page95_i118@mstr_ttl.ttl1g08(chips)!TTL1G08_SOTLF-NC7SZ08,IC,D1032B!U7E3!//jf4cfls225.pdx.intel.com/apd_proj/ppg_lib/epg_masterlib/logical/mstr_ttl/ttl1g08/chips/chips.prt!TTL1G08!TTL1G08_SOTLF-NC7SZ08,IC,D10321-001!TTL1G08!1!!F30!!CAT_ERR!!
S!@baseboard_fab2_lib.baseboard_fab2(sch_1):page177_i70@mstr_ttl.ttl1g08(chips)!TTL1G08_SOTLF-NC7SZ08,IC,D1032C!U1M1!//jf4cfls225.pdx.intel.com/apd_proj/ppg_lib/epg_masterlib/logical/mstr_ttl/ttl1g08/chips/chips.prt!TTL1G08!TTL1G08_SOTLF-NC7SZ08,IC,D10321-001!TTL1G08!1!!F29!!MIO_CHASSIS!!
S!@baseboard_fab2_lib.baseboard_fab2(sch_1):page200_i103@mstr_ttl.ttl1g126_a(chips)!TTL1G126_A_SOT-74HC1G126,IC,A7B!U1D1!//jf4cfls225.pdx.intel.com/apd_proj/ppg_lib/epg_masterlib/logical/mstr_ttl/ttl1g126_a/chips/chips.prt!TTL1G126_A!TTL1G126_A_SOT-74HC1G126,IC,A79322-001!TTL1G126_A_SOT!!!F28!!HOT_SWAP!!
S!@baseboard_fab2_lib.baseboard_fab2(sch_1):page170_i20@mstr_ttl.ttl1g126_a(chips)!TTL1G126_A_SOT-74HC1G126,IC,A7B!U1R2!//jf4cfls225.pdx.intel.com/apd_proj/ppg_lib/epg_masterlib/logical/mstr_ttl/ttl1g126_a/chips/chips.prt!TTL1G126_A!TTL1G126_A_SOT-74HC1G126,IC,A79322-001!TTL1G126_A_SOT!!!F27!!FAST_PROCHOT!!
S!@baseboard_fab2_lib.baseboard_fab2(sch_1):page170_i38@mstr_ttl.ttl1g126_a(chips)!TTL1G126_A_SOT-74HC1G126,IC,A7B!U8D5!//jf4cfls225.pdx.intel.com/apd_proj/ppg_lib/epg_masterlib/logical/mstr_ttl/ttl1g126_a/chips/chips.prt!TTL1G126_A!TTL1G126_A_SOT-74HC1G126,IC,A79322-001!TTL1G126_A_SOT!!!F26!!PROC_SIDEBAND!!
S!@baseboard_fab2_lib.baseboard_fab2(sch_1):page136_i130@mstr_ttl.ttl1g126_a(chips)!TTL1G126_A_SOT-74HC1G126,IC,A7B!U8E3!//jf4cfls225.pdx.intel.com/apd_proj/ppg_lib/epg_masterlib/logical/mstr_ttl/ttl1g126_a/chips/chips.prt!TTL1G126_A!TTL1G126_A_SOT-74HC1G126,IC,A79322-001!TTL1G126_A_SOT!!!F25!!SB!!
S!@baseboard_fab2_lib.baseboard_fab2(sch_1):page142_i1@mstr_ttl.ttl1g126_a(chips)!TTL1G126_A_SOT-74HC1G126,IC,A7B!U8E4!//jf4cfls225.pdx.intel.com/apd_proj/ppg_lib/epg_masterlib/logical/mstr_ttl/ttl1g126_a/chips/chips.prt!TTL1G126_A!TTL1G126_A_SOT-74HC1G126,IC,A79322-001!TTL1G126_A_SOT!!!F24!!PCIE_WAKE_BUFFER!!
S!@baseboard_fab2_lib.baseboard_fab2(sch_1):page125_i60@mstr_discrete.res(chips)!RES_0402-8.2K,1%,1/16W,EMPTY,GA!R7D13!//jf4cfls225.pdx.intel.com/apd_proj/ppg_lib/epg_masterlib/logical/mstr_discrete/res/chips/chips.prt!RES!RES_0402-8.2K,1%,1/16W,EMPTY,G21796-345!RES!!!F292!!SB!!
S!@baseboard_fab2_lib.baseboard_fab2(sch_1):page110_i54@mstr_misc.tp3_pprobeb(chips)!TP3_PPROBEB_SM-EMPTY,NA!TC1!//jf4cfls225.pdx.intel.com/apd_proj/ppg_lib/epg_masterlib/logical/mstr_misc/tp3_pprobeb/chips/chips.prt!TP3_PPROBEB!TP3_PPROBEB_SM-EMPTY,NA!TP3_PPROBEB_SM!!!F60!!!!
S!@baseboard_fab2_lib.baseboard_fab2(sch_1):page110_i58@mstr_misc.tp3_pprobeb(chips)!TP3_PPROBEB_SM-EMPTY,NA!TC3!//jf4cfls225.pdx.intel.com/apd_proj/ppg_lib/epg_masterlib/logical/mstr_misc/tp3_pprobeb/chips/chips.prt!TP3_PPROBEB!TP3_PPROBEB_SM-EMPTY,NA!TP3_PPROBEB_SM!!!F59!!!!
S!@baseboard_fab2_lib.baseboard_fab2(sch_1):page110_i62@mstr_misc.tp3_pprobeb(chips)!TP3_PPROBEB_SM-EMPTY,NA!TC4!//jf4cfls225.pdx.intel.com/apd_proj/ppg_lib/epg_masterlib/logical/mstr_misc/tp3_pprobeb/chips/chips.prt!TP3_PPROBEB!TP3_PPROBEB_SM-EMPTY,NA!TP3_PPROBEB_SM!!!F58!!!!
S!@baseboard_fab2_lib.baseboard_fab2(sch_1):page110_i16@mstr_misc.tp3_pprobeb(chips)!TP3_PPROBEB_SM-EMPTY,NA!TC7!//jf4cfls225.pdx.intel.com/apd_proj/ppg_lib/epg_masterlib/logical/mstr_misc/tp3_pprobeb/chips/chips.prt!TP3_PPROBEB!TP3_PPROBEB_SM-EMPTY,NA!TP3_PPROBEB_SM!!!F57!!!!
S!@baseboard_fab2_lib.baseboard_fab2(sch_1):page110_i18@mstr_misc.tp3_pprobeb(chips)!TP3_PPROBEB_SM-EMPTY,NA!TC8!//jf4cfls225.pdx.intel.com/apd_proj/ppg_lib/epg_masterlib/logical/mstr_misc/tp3_pprobeb/chips/chips.prt!TP3_PPROBEB!TP3_PPROBEB_SM-EMPTY,NA!TP3_PPROBEB_SM!!!F56!!!!
S!@baseboard_fab2_lib.baseboard_fab2(sch_1):page110_i22@mstr_misc.tp3_pprobeb(chips)!TP3_PPROBEB_SM-EMPTY,NA!TC10!//jf4cfls225.pdx.intel.com/apd_proj/ppg_lib/epg_masterlib/logical/mstr_misc/tp3_pprobeb/chips/chips.prt!TP3_PPROBEB!TP3_PPROBEB_SM-EMPTY,NA!TP3_PPROBEB_SM!!!F55!!!!
S!@baseboard_fab2_lib.baseboard_fab2(sch_1):page110_i24@mstr_misc.tp3_pprobeb(chips)!TP3_PPROBEB_SM-EMPTY,NA!TC11!//jf4cfls225.pdx.intel.com/apd_proj/ppg_lib/epg_masterlib/logical/mstr_misc/tp3_pprobeb/chips/chips.prt!TP3_PPROBEB!TP3_PPROBEB_SM-EMPTY,NA!TP3_PPROBEB_SM!!!F54!!!!
S!@baseboard_fab2_lib.baseboard_fab2(sch_1):page110_i53@mstr_misc.tp3_pprobeb(chips)!TP3_PPROBEB_SM-EMPTY,NA!TC19!//jf4cfls225.pdx.intel.com/apd_proj/ppg_lib/epg_masterlib/logical/mstr_misc/tp3_pprobeb/chips/chips.prt!TP3_PPROBEB!TP3_PPROBEB_SM-EMPTY,NA!TP3_PPROBEB_SM!!!F53!!!!
S!@baseboard_fab2_lib.baseboard_fab2(sch_1):page110_i66@mstr_misc.tp3_pprobeb(chips)!TP3_PPROBEB_SM-EMPTY,NA!TC20!//jf4cfls225.pdx.intel.com/apd_proj/ppg_lib/epg_masterlib/logical/mstr_misc/tp3_pprobeb/chips/chips.prt!TP3_PPROBEB!TP3_PPROBEB_SM-EMPTY,NA!TP3_PPROBEB_SM!!!F52!!!!
S!@baseboard_fab2_lib.baseboard_fab2(sch_1):page139_i237@mstr_discrete.res(chips)!RES_0603-0,5.0%,1/10W,CHIP,G22A!R1R15!//jf4cfls225.pdx.intel.com/apd_proj/ppg_lib/epg_masterlib/logical/mstr_discrete/res/chips/chips.prt!RES!RES_0603-0,5.0%,1/10W,CHIP,G22178-002!RES!!!F281!!NIC_SPRV!!
S!@baseboard_fab2_lib.baseboard_fab2(sch_1):page139_i238@mstr_discrete.res(chips)!RES_0603-0,5.0%,1/10W,CHIP,G22A!R1T32!//jf4cfls225.pdx.intel.com/apd_proj/ppg_lib/epg_masterlib/logical/mstr_discrete/res/chips/chips.prt!RES!RES_0603-0,5.0%,1/10W,CHIP,G22178-002!RES!!!F280!!NIC_SPRV!!
S!@baseboard_fab2_lib.baseboard_fab2(sch_1):page139_i239@mstr_discrete.res(chips)!RES_0603-0,5.0%,1/10W,CHIP,G22A!R1T34!//jf4cfls225.pdx.intel.com/apd_proj/ppg_lib/epg_masterlib/logical/mstr_discrete/res/chips/chips.prt!RES!RES_0603-0,5.0%,1/10W,CHIP,G22178-002!RES!!!F279!!NIC_SPRV!!
S!@baseboard_fab2_lib.baseboard_fab2(sch_1):page139_i240@mstr_discrete.res(chips)!RES_0603-0,5.0%,1/10W,EMPTY,G2A!R1T33!//jf4cfls225.pdx.intel.com/apd_proj/ppg_lib/epg_masterlib/logical/mstr_discrete/res/chips/chips.prt!RES!RES_0603-0,5.0%,1/10W,EMPTY,G22178-002!RES!!!F278!!NIC_SPRV!!
S!@baseboard_fab2_lib.baseboard_fab2(sch_1):page141_i109@mstr_conn.conn17_h71061002(chips)!CONN17_H71061002_PIP1-CONN,H71A!JA9G1!//jf4cfls225.pdx.intel.com/apd_proj/ppg_lib/epg_masterlib/logical/mstr_conn/conn17_h71061002/chips/chips.prt!CONN17_H71061002!CONN17_H71061002_PIP1-CONN,H71061-002!CONN17_H71061002_PIP1!!!F2252!!NIC_SPRV!!
S!@baseboard_fab2_lib.baseboard_fab2(sch_1):page196_i80@mstr_analog.adm809(chips)!ADM809_SMLF-IC,D23047-001-GND=A!U1L3!//jf4cfls225.pdx.intel.com/apd_proj/ppg_lib/epg_masterlib/logical/mstr_analog/adm809/chips/chips.prt!ADM809!ADM809_SMLF-IC,D23047-001!ADM809!!!F4194!!V_SUPER!!
S!@baseboard_fab2_lib.baseboard_fab2(sch_1):page196_i89@mstr_analog.adm809(chips)!ADM809_SMLF-IC,D23047-001-GND=A!U8E2!//jf4cfls225.pdx.intel.com/apd_proj/ppg_lib/epg_masterlib/logical/mstr_analog/adm809/chips/chips.prt!ADM809!ADM809_SMLF-IC,D23047-001!ADM809!!!F4193!!V_SUPER!!
S!@baseboard_fab2_lib.baseboard_fab2(sch_1):page163_i1@mstr_digital.pca9517(chips)!PCA9517_SM-IC,G77073-001-GND=GA!U1B2!//jf4cfls225.pdx.intel.com/apd_proj/ppg_lib/epg_masterlib/logical/mstr_digital/pca9517/chips/chips.prt!PCA9517!PCA9517_SM-IC,G77073-001!PCA9517_SM!!!F1986!!SMB_PE_HP_CPU1!!
S!@baseboard_fab2_lib.baseboard_fab2(sch_1):page99_i75@mstr_digital.pca9617(chips)!PCA9617_SSOP-IC,G81764-001-GNDA!U3B1!//jf4cfls225.pdx.intel.com/apd_proj/ppg_lib/epg_masterlib/logical/mstr_digital/pca9617/chips/chips.prt!PCA9617!PCA9617_SSOP-IC,G81764-001!PCA9617_SSOP!!!F1985!!MEM!!
S!@baseboard_fab2_lib.baseboard_fab2(sch_1):page99_i63@mstr_digital.pca9617(chips)!PCA9617_SSOP-IC,G81764-001-GNDA!U4G1!//jf4cfls225.pdx.intel.com/apd_proj/ppg_lib/epg_masterlib/logical/mstr_digital/pca9617/chips/chips.prt!PCA9617!PCA9617_SSOP-IC,G81764-001!PCA9617_SSOP!!!F1984!!MEM!!
S!@baseboard_fab2_lib.baseboard_fab2(sch_1):page99_i15@mstr_digital.pca9617(chips)!PCA9617_SSOP-IC,G81764-001-GNDA!U6F1!//jf4cfls225.pdx.intel.com/apd_proj/ppg_lib/epg_masterlib/logical/mstr_digital/pca9617/chips/chips.prt!PCA9617!PCA9617_SSOP-IC,G81764-001!PCA9617_SSOP!!!F1983!!MEM!!
S!@baseboard_fab2_lib.baseboard_fab2(sch_1):page99_i61@mstr_digital.pca9617(chips)!PCA9617_SSOP-IC,G81764-001-GNDA!U7E1!//jf4cfls225.pdx.intel.com/apd_proj/ppg_lib/epg_masterlib/logical/mstr_digital/pca9617/chips/chips.prt!PCA9617!PCA9617_SSOP-IC,G81764-001!PCA9617_SSOP!!!F1982!!MEM!!
S!@baseboard_fab2_lib.baseboard_fab2(sch_1):page154_i75@mstr_digital.pi3b3257a(chips)!PI3B3257A_TSSOPLF-IC,E16801-001!U2T1!//jf4cfls225.pdx.intel.com/apd_proj/ppg_lib/epg_masterlib/logical/mstr_digital/pi3b3257a/chips/chips.prt!PI3B3257A!PI3B3257A_TSSOPLF-IC,E16801-001!PI3B3257A_TSSOPLF!!!F1981!!SB_BMC_SPI_MUX!!
S!@baseboard_fab2_lib.baseboard_fab2(sch_1):page154_i74@mstr_digital.pi3b3257a(chips)!PI3B3257A_TSSOPLF-IC,E16801-001!U8F1!//jf4cfls225.pdx.intel.com/apd_proj/ppg_lib/epg_masterlib/logical/mstr_digital/pi3b3257a/chips/chips.prt!PI3B3257A!PI3B3257A_TSSOPLF-IC,E16801-001!PI3B3257A_TSSOPLF!!!F1980!!SB_BMC_SPI_MUX!!
S!@baseboard_fab2_lib.baseboard_fab2(sch_1):page94_i104@mstr_discrete.res(chips)!RES_0402-33.0K,5%,1/16W,CHIP,GA!R4U4!//jf4cfls225.pdx.intel.com/apd_proj/ppg_lib/epg_masterlib/logical/mstr_discrete/res/chips/chips.prt!RES!RES_0402-33.0K,5%,1/16W,CHIP,G21497-023!RES!!!F758!!!!
S!@baseboard_fab2_lib.baseboard_fab2(sch_1):page181_i111@mstr_conn.conn76_h22707001(chips)!CONN76_H22707001_THMT1-CONN,H2A!J1F1!//jf4cfls225.pdx.intel.com/apd_proj/ppg_lib/epg_masterlib/logical/mstr_conn/conn76_h22707001/chips/chips.prt!CONN76_H22707001!CONN76_H22707001_THMT1-CONN,H22707-001!CONN76_H22707001_THMT1!!!F2238!!IO_SLOT!!
S!@baseboard_fab2_lib.baseboard_fab2(sch_1):page182_i18@mstr_conn.conn76_h22707001(chips)!CONN76_H22707001_THMT1-CONN,H2A!J1C1!//jf4cfls225.pdx.intel.com/apd_proj/ppg_lib/epg_masterlib/logical/mstr_conn/conn76_h22707001/chips/chips.prt!CONN76_H22707001!CONN76_H22707001_THMT1-CONN,H22707-001!CONN76_H22707001_THMT1!!!F2239!!IO_SLOT!!
S!@baseboard_fab2_lib.baseboard_fab2(sch_1):page235_i235@mstr_discrete.res(chips)!RES_0402-100.0K,1%,1/16W,EMPTYA!R2L25!//jf4cfls225.pdx.intel.com/apd_proj/ppg_lib/epg_masterlib/logical/mstr_discrete/res/chips/chips.prt!RES!RES_0402-100.0K,1%,1/16W,EMPTY,G21796-010!RES!!!F1113!!BMC!!
S!@baseboard_fab2_lib.baseboard_fab2(sch_1):page235_i236@mstr_discrete.res(chips)!RES_0402-100.0K,1%,1/16W,EMPTYA!R2L26!//jf4cfls225.pdx.intel.com/apd_proj/ppg_lib/epg_masterlib/logical/mstr_discrete/res/chips/chips.prt!RES!RES_0402-100.0K,1%,1/16W,EMPTY,G21796-010!RES!!!F1112!!BMC!!
S!@baseboard_fab2_lib.baseboard_fab2(sch_1):page211_i88@mstr_discrete.res(chips)!RES_0402-100.0K,1%,1/16W,EMPTYA!R3P21!//jf4cfls225.pdx.intel.com/apd_proj/ppg_lib/epg_masterlib/logical/mstr_discrete/res/chips/chips.prt!RES!RES_0402-100.0K,1%,1/16W,EMPTY,G21796-010!RES!!!F1120!!BMC!!
S!@baseboard_fab2_lib.baseboard_fab2(sch_1):page213_i91@mstr_discrete.res(chips)!RES_0402-100.0K,1%,1/16W,EMPTYA!R6P40!//jf4cfls225.pdx.intel.com/apd_proj/ppg_lib/epg_masterlib/logical/mstr_discrete/res/chips/chips.prt!RES!RES_0402-100.0K,1%,1/16W,EMPTY,G21796-010!RES!!!F1119!!BMC!!
S!@baseboard_fab2_lib.baseboard_fab2(sch_1):page215_i315@mstr_discrete.res(chips)!RES_0402-100.0K,1%,1/16W,EMPTYA!R7F20!//jf4cfls225.pdx.intel.com/apd_proj/ppg_lib/epg_masterlib/logical/mstr_discrete/res/chips/chips.prt!RES!RES_0402-100.0K,1%,1/16W,EMPTY,G21796-010!RES!!!F1118!!BMC!!
S!@baseboard_fab2_lib.baseboard_fab2(sch_1):page218_i35@mstr_discrete.res(chips)!RES_0402-100.0K,1%,1/16W,EMPTYA!R3M5!//jf4cfls225.pdx.intel.com/apd_proj/ppg_lib/epg_masterlib/logical/mstr_discrete/res/chips/chips.prt!RES!RES_0402-100.0K,1%,1/16W,EMPTY,G21796-010!RES!!!F1121!!VDDQ_DEF_PWR_VR!!
S!@baseboard_fab2_lib.baseboard_fab2(sch_1):page223_i85@mstr_discrete.res(chips)!RES_0402-100.0K,1%,1/16W,EMPTYA!R9U8!//jf4cfls225.pdx.intel.com/apd_proj/ppg_lib/epg_masterlib/logical/mstr_discrete/res/chips/chips.prt!RES!RES_0402-100.0K,1%,1/16W,EMPTY,G21796-010!RES!!!F1114!!BMC!!
S!@baseboard_fab2_lib.baseboard_fab2(sch_1):page226_i85@mstr_discrete.res(chips)!RES_0402-100.0K,1%,1/16W,EMPTYA!R9M5!//jf4cfls225.pdx.intel.com/apd_proj/ppg_lib/epg_masterlib/logical/mstr_discrete/res/chips/chips.prt!RES!RES_0402-100.0K,1%,1/16W,EMPTY,G21796-010!RES!!!F1115!!BMC!!
S!@baseboard_fab2_lib.baseboard_fab2(sch_1):page235_i222@mstr_discrete.res(chips)!RES_0402-100.0K,1%,1/16W,EMPTYA!R8A7!//jf4cfls225.pdx.intel.com/apd_proj/ppg_lib/epg_masterlib/logical/mstr_discrete/res/chips/chips.prt!RES!RES_0402-100.0K,1%,1/16W,EMPTY,G21796-010!RES!!!F1117!!BMC!!
S!@baseboard_fab2_lib.baseboard_fab2(sch_1):page240_i177@mstr_discrete.res(chips)!RES_0402-100.0K,1%,1/16W,EMPTYA!R8E40!//jf4cfls225.pdx.intel.com/apd_proj/ppg_lib/epg_masterlib/logical/mstr_discrete/res/chips/chips.prt!RES!RES_0402-100.0K,1%,1/16W,EMPTY,G21796-010!RES!!!F1116!!BMC!!
S!@baseboard_fab2_lib.baseboard_fab2(sch_1):page164_i29@mstr_discrete.res(chips)!RES_0402-2.7K,1%,1/16W,EMPTY,GA!R2N17!//jf4cfls225.pdx.intel.com/apd_proj/ppg_lib/epg_masterlib/logical/mstr_discrete/res/chips/chips.prt!RES!RES_0402-2.7K,1%,1/16W,EMPTY,G21796-344!RES!!!F982!!BMC_MISC!!
S!@baseboard_fab2_lib.baseboard_fab2(sch_1):page164_i24@mstr_discrete.res(chips)!RES_0402-2.7K,1%,1/16W,EMPTY,GA!R1U21!//jf4cfls225.pdx.intel.com/apd_proj/ppg_lib/epg_masterlib/logical/mstr_discrete/res/chips/chips.prt!RES!RES_0402-2.7K,1%,1/16W,EMPTY,G21796-344!RES!!!F984!!BMC_MISC!!
S!@baseboard_fab2_lib.baseboard_fab2(sch_1):page164_i27@mstr_discrete.res(chips)!RES_0402-2.7K,1%,1/16W,EMPTY,GA!R1U22!//jf4cfls225.pdx.intel.com/apd_proj/ppg_lib/epg_masterlib/logical/mstr_discrete/res/chips/chips.prt!RES!RES_0402-2.7K,1%,1/16W,EMPTY,G21796-344!RES!!!F983!!BMC_MISC!!
S!@baseboard_fab2_lib.baseboard_fab2(sch_1):page164_i11@mstr_discrete.res(chips)!RES_0402-2.7K,1%,1/16W,EMPTY,GA!R1T5!//jf4cfls225.pdx.intel.com/apd_proj/ppg_lib/epg_masterlib/logical/mstr_discrete/res/chips/chips.prt!RES!RES_0402-2.7K,1%,1/16W,EMPTY,G21796-344!RES!!!F986!!BMC_MISC!!
S!@baseboard_fab2_lib.baseboard_fab2(sch_1):page164_i13@mstr_discrete.res(chips)!RES_0402-2.7K,1%,1/16W,EMPTY,GA!R1T6!//jf4cfls225.pdx.intel.com/apd_proj/ppg_lib/epg_masterlib/logical/mstr_discrete/res/chips/chips.prt!RES!RES_0402-2.7K,1%,1/16W,EMPTY,G21796-344!RES!!!F985!!BMC_MISC!!
S!@baseboard_fab2_lib.baseboard_fab2(sch_1):page111_i83@mstr_discrete.res(chips)!RES_0402-33.2,1%,1/16W,EMPTY,GA!R9A2!//jf4cfls225.pdx.intel.com/apd_proj/ppg_lib/epg_masterlib/logical/mstr_discrete/res/chips/chips.prt!RES!RES_0402-33.2,1%,1/16W,EMPTY,G21796-074!RES!!!F666!!DEBUG!!
S!@baseboard_fab2_lib.baseboard_fab2(sch_1):page183_i20@mstr_discrete.cap(chips)!CAP_0402LF-12.0PF,50V,5%,COG,AA!C9F20!//jf4cfls225.pdx.intel.com/apd_proj/ppg_lib/epg_masterlib/logical/mstr_discrete/cap/chips/chips.prt!CAP!CAP_0402LF-12.0PF,50V,5%,COG,A36095-043!CAP!!!F3159!!LBG!!
S!@baseboard_fab2_lib.baseboard_fab2(sch_1):page183_i21@mstr_discrete.cap(chips)!CAP_0402LF-12.0PF,50V,5%,COG,AA!C9F21!//jf4cfls225.pdx.intel.com/apd_proj/ppg_lib/epg_masterlib/logical/mstr_discrete/cap/chips/chips.prt!CAP!CAP_0402LF-12.0PF,50V,5%,COG,A36095-043!CAP!!!F3158!!LBG!!
S!@baseboard_fab2_lib.baseboard_fab2(sch_1):page199_i123@mstr_conn.conn3_c95678002(chips)!CONN3_C95678002_PIP-CONN,C9567A!J1B3!//jf4cfls225.pdx.intel.com/apd_proj/ppg_lib/epg_masterlib/logical/mstr_conn/conn3_c95678002/chips/chips.prt!CONN3_C95678002!CONN3_C95678002_PIP-CONN,C95678-002!CONN3_C95678002_PIP!!!F2250!!SMBUS!!
S!@baseboard_fab2_lib.baseboard_fab2(sch_1):page156_i281@mstr_conn.conn3_c95678002(chips)!CONN3_C95678002_PIP-CONN,C9567A!J9B2!//jf4cfls225.pdx.intel.com/apd_proj/ppg_lib/epg_masterlib/logical/mstr_conn/conn3_c95678002/chips/chips.prt!CONN3_C95678002!CONN3_C95678002_PIP-CONN,C95678-002!CONN3_C95678002_PIP!!!F2247!!DEBUG!!
S!@baseboard_fab2_lib.baseboard_fab2(sch_1):page156_i285@mstr_conn.conn3_c95678002(chips)!CONN3_C95678002_PIP-CONN,C9567A!J8C1!//jf4cfls225.pdx.intel.com/apd_proj/ppg_lib/epg_masterlib/logical/mstr_conn/conn3_c95678002/chips/chips.prt!CONN3_C95678002!CONN3_C95678002_PIP-CONN,C95678-002!CONN3_C95678002_PIP!!!F2249!!DEBUG!!
S!@baseboard_fab2_lib.baseboard_fab2(sch_1):page201_i122@mstr_conn.conn3_c95678002(chips)!CONN3_C95678002_PIP-CONN,C9567A!J8D4!//jf4cfls225.pdx.intel.com/apd_proj/ppg_lib/epg_masterlib/logical/mstr_conn/conn3_c95678002/chips/chips.prt!CONN3_C95678002!CONN3_C95678002_PIP-CONN,C95678-002!CONN3_C95678002_PIP!!!F2248!!SMBUS!!
S!@baseboard_fab2_lib.baseboard_fab2(sch_1):page140_i1@mstr_memory.m25pe16(chips)!M25PE16_SM-IC,H77797-001!U9E1!//jf4cfls225.pdx.intel.com/apd_proj/ppg_lib/epg_masterlib/logical/mstr_memory/m25pe16/chips/chips.prt!M25PE16!M25PE16_SM-IC,H77797-001!M25PE16_SM!!!F2029!!NIC_SPRV!!
S!@baseboard_fab2_lib.baseboard_fab2(sch_1):page89_i35@mstr_discrete.npn_dual(chips)!NPN_DUAL_SSOPLF-MBT3904,XSTR,CA!Q8D1!//jf4cfls225.pdx.intel.com/apd_proj/ppg_lib/epg_masterlib/logical/mstr_discrete/npn_dual/chips/chips.prt!NPN_DUAL!NPN_DUAL_SSOPLF-MBT3904,XSTR,C52264-001!NPN_DUAL!1!!F1996!!NV_DIMM!!
S!@baseboard_fab2_lib.baseboard_fab2(sch_1):page89_i36@mstr_discrete.npn_dual(chips)!NPN_DUAL_SSOPLF-MBT3904,XSTR,CA!Q8D1!//jf4cfls225.pdx.intel.com/apd_proj/ppg_lib/epg_masterlib/logical/mstr_discrete/npn_dual/chips/chips.prt!NPN_DUAL!NPN_DUAL_SSOPLF-MBT3904,XSTR,C52264-001!NPN_DUAL!1!!F1995!!NV_DIMM!!
S!@baseboard_fab2_lib.baseboard_fab2(sch_1):page21_i259@chpset_lib.skx_ext_b(chips)!SKX_EXT_B_BGA1-IC,TBD!U5D1!//jf4cfls225.pdx.intel.com/apd_proj/ppg_lib/chpset_lib/logical/skx_ext_b/chips/chips.prt!SKX_EXT_B!SKX_EXT_B_BGA1-IC,TBD!SKX_EXT_B_BGA1!!!F101!!CPU0!!
S!@baseboard_fab2_lib.baseboard_fab2(sch_1):page22_i204@chpset_lib.skx_ext_b(chips)!SKX_EXT_B_BGA1-IC,TBD!U5D1!//jf4cfls225.pdx.intel.com/apd_proj/ppg_lib/chpset_lib/logical/skx_ext_b/chips/chips.prt!SKX_EXT_B!SKX_EXT_B_BGA1-IC,TBD!SKX_EXT_B_BGA1!!!F100!!CPU0!!
S!@baseboard_fab2_lib.baseboard_fab2(sch_1):page23_i172@chpset_lib.skx_ext_b(chips)!SKX_EXT_B_BGA1-IC,TBD!U5D1!//jf4cfls225.pdx.intel.com/apd_proj/ppg_lib/chpset_lib/logical/skx_ext_b/chips/chips.prt!SKX_EXT_B!SKX_EXT_B_BGA1-IC,TBD!SKX_EXT_B_BGA1!!!F99!!CPU0!!
S!@baseboard_fab2_lib.baseboard_fab2(sch_1):page24_i172@chpset_lib.skx_ext_b(chips)!SKX_EXT_B_BGA1-IC,TBD!U5D1!//jf4cfls225.pdx.intel.com/apd_proj/ppg_lib/chpset_lib/logical/skx_ext_b/chips/chips.prt!SKX_EXT_B!SKX_EXT_B_BGA1-IC,TBD!SKX_EXT_B_BGA1!!!F98!!CPU0!!
S!@baseboard_fab2_lib.baseboard_fab2(sch_1):page25_i172@chpset_lib.skx_ext_b(chips)!SKX_EXT_B_BGA1-IC,TBD!U5D1!//jf4cfls225.pdx.intel.com/apd_proj/ppg_lib/chpset_lib/logical/skx_ext_b/chips/chips.prt!SKX_EXT_B!SKX_EXT_B_BGA1-IC,TBD!SKX_EXT_B_BGA1!!!F97!!CPU0!!
S!@baseboard_fab2_lib.baseboard_fab2(sch_1):page26_i172@chpset_lib.skx_ext_b(chips)!SKX_EXT_B_BGA1-IC,TBD!U5D1!//jf4cfls225.pdx.intel.com/apd_proj/ppg_lib/chpset_lib/logical/skx_ext_b/chips/chips.prt!SKX_EXT_B!SKX_EXT_B_BGA1-IC,TBD!SKX_EXT_B_BGA1!!!F96!!CPU0!!
S!@baseboard_fab2_lib.baseboard_fab2(sch_1):page27_i172@chpset_lib.skx_ext_b(chips)!SKX_EXT_B_BGA1-IC,TBD!U5D1!//jf4cfls225.pdx.intel.com/apd_proj/ppg_lib/chpset_lib/logical/skx_ext_b/chips/chips.prt!SKX_EXT_B!SKX_EXT_B_BGA1-IC,TBD!SKX_EXT_B_BGA1!!!F95!!CPU0!!
S!@baseboard_fab2_lib.baseboard_fab2(sch_1):page28_i172@chpset_lib.skx_ext_b(chips)!SKX_EXT_B_BGA1-IC,TBD!U5D1!//jf4cfls225.pdx.intel.com/apd_proj/ppg_lib/chpset_lib/logical/skx_ext_b/chips/chips.prt!SKX_EXT_B!SKX_EXT_B_BGA1-IC,TBD!SKX_EXT_B_BGA1!!!F94!!CPU0!!
S!@baseboard_fab2_lib.baseboard_fab2(sch_1):page29_i61@chpset_lib.skx_ext_b(chips)!SKX_EXT_B_BGA1-IC,TBD!U5D1!//jf4cfls225.pdx.intel.com/apd_proj/ppg_lib/chpset_lib/logical/skx_ext_b/chips/chips.prt!SKX_EXT_B!SKX_EXT_B_BGA1-IC,TBD!SKX_EXT_B_BGA1!!!F93!!CPU0!!
S!@baseboard_fab2_lib.baseboard_fab2(sch_1):page30_i84@chpset_lib.skx_ext_b(chips)!SKX_EXT_B_BGA1-IC,TBD!U5D1!//jf4cfls225.pdx.intel.com/apd_proj/ppg_lib/chpset_lib/logical/skx_ext_b/chips/chips.prt!SKX_EXT_B!SKX_EXT_B_BGA1-IC,TBD!SKX_EXT_B_BGA1!!!F92!!CPU0!!
S!@baseboard_fab2_lib.baseboard_fab2(sch_1):page31_i106@chpset_lib.skx_ext_b(chips)!SKX_EXT_B_BGA1-IC,TBD!U5D1!//jf4cfls225.pdx.intel.com/apd_proj/ppg_lib/chpset_lib/logical/skx_ext_b/chips/chips.prt!SKX_EXT_B!SKX_EXT_B_BGA1-IC,TBD!SKX_EXT_B_BGA1!!!F91!!CPU0!!
S!@baseboard_fab2_lib.baseboard_fab2(sch_1):page32_i89@chpset_lib.skx_ext_b(chips)!SKX_EXT_B_BGA1-IC,TBD!U5D1!//jf4cfls225.pdx.intel.com/apd_proj/ppg_lib/chpset_lib/logical/skx_ext_b/chips/chips.prt!SKX_EXT_B!SKX_EXT_B_BGA1-IC,TBD!SKX_EXT_B_BGA1!!!F90!!!!
S!@baseboard_fab2_lib.baseboard_fab2(sch_1):page33_i86@chpset_lib.skx_ext_b(chips)!SKX_EXT_B_BGA1-IC,TBD!U5D1!//jf4cfls225.pdx.intel.com/apd_proj/ppg_lib/chpset_lib/logical/skx_ext_b/chips/chips.prt!SKX_EXT_B!SKX_EXT_B_BGA1-IC,TBD!SKX_EXT_B_BGA1!!!F89!!CPU0!!
S!@baseboard_fab2_lib.baseboard_fab2(sch_1):page34_i86@chpset_lib.skx_ext_b(chips)!SKX_EXT_B_BGA1-IC,TBD!U5D1!//jf4cfls225.pdx.intel.com/apd_proj/ppg_lib/chpset_lib/logical/skx_ext_b/chips/chips.prt!SKX_EXT_B!SKX_EXT_B_BGA1-IC,TBD!SKX_EXT_B_BGA1!!!F88!!CPU0!!
S!@baseboard_fab2_lib.baseboard_fab2(sch_1):page35_i3@chpset_lib.skx_ext_b(chips)!SKX_EXT_B_BGA1-IC,TBD!U5D1!//jf4cfls225.pdx.intel.com/apd_proj/ppg_lib/chpset_lib/logical/skx_ext_b/chips/chips.prt!SKX_EXT_B!SKX_EXT_B_BGA1-IC,TBD!SKX_EXT_B_BGA1!!!F87!!CPU0!!
S!@baseboard_fab2_lib.baseboard_fab2(sch_1):page36_i15@chpset_lib.skx_ext_b(chips)!SKX_EXT_B_BGA1-IC,TBD!U5D1!//jf4cfls225.pdx.intel.com/apd_proj/ppg_lib/chpset_lib/logical/skx_ext_b/chips/chips.prt!SKX_EXT_B!SKX_EXT_B_BGA1-IC,TBD!SKX_EXT_B_BGA1!!!F86!!CPU0!!
S!@baseboard_fab2_lib.baseboard_fab2(sch_1):page36_i16@chpset_lib.skx_ext_b(chips)!SKX_EXT_B_BGA1-IC,TBD!U5D1!//jf4cfls225.pdx.intel.com/apd_proj/ppg_lib/chpset_lib/logical/skx_ext_b/chips/chips.prt!SKX_EXT_B!SKX_EXT_B_BGA1-IC,TBD!SKX_EXT_B_BGA1!!!F85!!CPU0!!
S!@baseboard_fab2_lib.baseboard_fab2(sch_1):page37_i310@chpset_lib.skx_ext_b(chips)!SKX_EXT_B_BGA1-IC,TBD!U5D1!//jf4cfls225.pdx.intel.com/apd_proj/ppg_lib/chpset_lib/logical/skx_ext_b/chips/chips.prt!SKX_EXT_B!SKX_EXT_B_BGA1-IC,TBD!SKX_EXT_B_BGA1!!!F84!!CPU0!!
S!@baseboard_fab2_lib.baseboard_fab2(sch_1):page37_i311@chpset_lib.skx_ext_b(chips)!SKX_EXT_B_BGA1-IC,TBD!U5D1!//jf4cfls225.pdx.intel.com/apd_proj/ppg_lib/chpset_lib/logical/skx_ext_b/chips/chips.prt!SKX_EXT_B!SKX_EXT_B_BGA1-IC,TBD!SKX_EXT_B_BGA1!!!F83!!CPU0!!
S!@baseboard_fab2_lib.baseboard_fab2(sch_1):page38_i33@chpset_lib.skx_ext_b(chips)!SKX_EXT_B_BGA1-IC,TBD!U5D1!//jf4cfls225.pdx.intel.com/apd_proj/ppg_lib/chpset_lib/logical/skx_ext_b/chips/chips.prt!SKX_EXT_B!SKX_EXT_B_BGA1-IC,TBD!SKX_EXT_B_BGA1!!!F82!!CPU0!!
S!@baseboard_fab2_lib.baseboard_fab2(sch_1):page38_i34@chpset_lib.skx_ext_b(chips)!SKX_EXT_B_BGA1-IC,TBD!U5D1!//jf4cfls225.pdx.intel.com/apd_proj/ppg_lib/chpset_lib/logical/skx_ext_b/chips/chips.prt!SKX_EXT_B!SKX_EXT_B_BGA1-IC,TBD!SKX_EXT_B_BGA1!!!F81!!CPU0!!
S!@baseboard_fab2_lib.baseboard_fab2(sch_1):page39_i127@chpset_lib.skx_ext_b(chips)!SKX_EXT_B_BGA1-IC,TBD!U5D1!//jf4cfls225.pdx.intel.com/apd_proj/ppg_lib/chpset_lib/logical/skx_ext_b/chips/chips.prt!SKX_EXT_B!SKX_EXT_B_BGA1-IC,TBD!SKX_EXT_B_BGA1!!!F80!!CPU0!!
S!@baseboard_fab2_lib.baseboard_fab2(sch_1):page40_i20@chpset_lib.skx_ext_b(chips)!SKX_EXT_B_BGA1-IC,TBD!U5D1!//jf4cfls225.pdx.intel.com/apd_proj/ppg_lib/chpset_lib/logical/skx_ext_b/chips/chips.prt!SKX_EXT_B!SKX_EXT_B_BGA1-IC,TBD!SKX_EXT_B_BGA1!!!F79!!CPU0!!
S!@baseboard_fab2_lib.baseboard_fab2(sch_1):page40_i21@chpset_lib.skx_ext_b(chips)!SKX_EXT_B_BGA1-IC,TBD!U5D1!//jf4cfls225.pdx.intel.com/apd_proj/ppg_lib/chpset_lib/logical/skx_ext_b/chips/chips.prt!SKX_EXT_B!SKX_EXT_B_BGA1-IC,TBD!SKX_EXT_B_BGA1!!!F78!!CPU0!!
S!@baseboard_fab2_lib.baseboard_fab2(sch_1):page40_i22@chpset_lib.skx_ext_b(chips)!SKX_EXT_B_BGA1-IC,TBD!U5D1!//jf4cfls225.pdx.intel.com/apd_proj/ppg_lib/chpset_lib/logical/skx_ext_b/chips/chips.prt!SKX_EXT_B!SKX_EXT_B_BGA1-IC,TBD!SKX_EXT_B_BGA1!!!F77!!CPU0!!
S!@baseboard_fab2_lib.baseboard_fab2(sch_1):page40_i23@chpset_lib.skx_ext_b(chips)!SKX_EXT_B_BGA1-IC,TBD!U5D1!//jf4cfls225.pdx.intel.com/apd_proj/ppg_lib/chpset_lib/logical/skx_ext_b/chips/chips.prt!SKX_EXT_B!SKX_EXT_B_BGA1-IC,TBD!SKX_EXT_B_BGA1!!!F76!!CPU0!!
S!@baseboard_fab2_lib.baseboard_fab2(sch_1):page41_i283@chpset_lib.skx_ext_b(chips)!SKX_EXT_B_BGA1-IC,TBD!U5D1!//jf4cfls225.pdx.intel.com/apd_proj/ppg_lib/chpset_lib/logical/skx_ext_b/chips/chips.prt!SKX_EXT_B!SKX_EXT_B_BGA1-IC,TBD!SKX_EXT_B_BGA1!!!F75!!CPU0!!
S!@baseboard_fab2_lib.baseboard_fab2(sch_1):page41_i284@chpset_lib.skx_ext_b(chips)!SKX_EXT_B_BGA1-IC,TBD!U5D1!//jf4cfls225.pdx.intel.com/apd_proj/ppg_lib/chpset_lib/logical/skx_ext_b/chips/chips.prt!SKX_EXT_B!SKX_EXT_B_BGA1-IC,TBD!SKX_EXT_B_BGA1!!!F74!!CPU0!!
S!@baseboard_fab2_lib.baseboard_fab2(sch_1):page41_i285@chpset_lib.skx_ext_b(chips)!SKX_EXT_B_BGA1-IC,TBD!U5D1!//jf4cfls225.pdx.intel.com/apd_proj/ppg_lib/chpset_lib/logical/skx_ext_b/chips/chips.prt!SKX_EXT_B!SKX_EXT_B_BGA1-IC,TBD!SKX_EXT_B_BGA1!!!F73!!CPU0!!
S!@baseboard_fab2_lib.baseboard_fab2(sch_1):page41_i286@chpset_lib.skx_ext_b(chips)!SKX_EXT_B_BGA1-IC,TBD!U5D1!//jf4cfls225.pdx.intel.com/apd_proj/ppg_lib/chpset_lib/logical/skx_ext_b/chips/chips.prt!SKX_EXT_B!SKX_EXT_B_BGA1-IC,TBD!SKX_EXT_B_BGA1!!!F72!!CPU0!!
S!@baseboard_fab2_lib.baseboard_fab2(sch_1):page55_i172@chpset_lib.skx_ext_b(chips)!SKX_EXT_B_BGA1-IC,TBD!U2D1!//jf4cfls225.pdx.intel.com/apd_proj/ppg_lib/chpset_lib/logical/skx_ext_b/chips/chips.prt!SKX_EXT_B!SKX_EXT_B_BGA1-IC,TBD!SKX_EXT_B_BGA1!!!F131!!CPU1!!
S!@baseboard_fab2_lib.baseboard_fab2(sch_1):page56_i169@chpset_lib.skx_ext_b(chips)!SKX_EXT_B_BGA1-IC,TBD!U2D1!//jf4cfls225.pdx.intel.com/apd_proj/ppg_lib/chpset_lib/logical/skx_ext_b/chips/chips.prt!SKX_EXT_B!SKX_EXT_B_BGA1-IC,TBD!SKX_EXT_B_BGA1!!!F130!!!!
S!@baseboard_fab2_lib.baseboard_fab2(sch_1):page57_i172@chpset_lib.skx_ext_b(chips)!SKX_EXT_B_BGA1-IC,TBD!U2D1!//jf4cfls225.pdx.intel.com/apd_proj/ppg_lib/chpset_lib/logical/skx_ext_b/chips/chips.prt!SKX_EXT_B!SKX_EXT_B_BGA1-IC,TBD!SKX_EXT_B_BGA1!!!F129!!!!
S!@baseboard_fab2_lib.baseboard_fab2(sch_1):page58_i172@chpset_lib.skx_ext_b(chips)!SKX_EXT_B_BGA1-IC,TBD!U2D1!//jf4cfls225.pdx.intel.com/apd_proj/ppg_lib/chpset_lib/logical/skx_ext_b/chips/chips.prt!SKX_EXT_B!SKX_EXT_B_BGA1-IC,TBD!SKX_EXT_B_BGA1!!!F128!!!!
S!@baseboard_fab2_lib.baseboard_fab2(sch_1):page59_i172@chpset_lib.skx_ext_b(chips)!SKX_EXT_B_BGA1-IC,TBD!U2D1!//jf4cfls225.pdx.intel.com/apd_proj/ppg_lib/chpset_lib/logical/skx_ext_b/chips/chips.prt!SKX_EXT_B!SKX_EXT_B_BGA1-IC,TBD!SKX_EXT_B_BGA1!!!F127!!!!
S!@baseboard_fab2_lib.baseboard_fab2(sch_1):page60_i172@chpset_lib.skx_ext_b(chips)!SKX_EXT_B_BGA1-IC,TBD!U2D1!//jf4cfls225.pdx.intel.com/apd_proj/ppg_lib/chpset_lib/logical/skx_ext_b/chips/chips.prt!SKX_EXT_B!SKX_EXT_B_BGA1-IC,TBD!SKX_EXT_B_BGA1!!!F126!!!!
S!@baseboard_fab2_lib.baseboard_fab2(sch_1):page61_i172@chpset_lib.skx_ext_b(chips)!SKX_EXT_B_BGA1-IC,TBD!U2D1!//jf4cfls225.pdx.intel.com/apd_proj/ppg_lib/chpset_lib/logical/skx_ext_b/chips/chips.prt!SKX_EXT_B!SKX_EXT_B_BGA1-IC,TBD!SKX_EXT_B_BGA1!!!F125!!!!
S!@baseboard_fab2_lib.baseboard_fab2(sch_1):page62_i172@chpset_lib.skx_ext_b(chips)!SKX_EXT_B_BGA1-IC,TBD!U2D1!//jf4cfls225.pdx.intel.com/apd_proj/ppg_lib/chpset_lib/logical/skx_ext_b/chips/chips.prt!SKX_EXT_B!SKX_EXT_B_BGA1-IC,TBD!SKX_EXT_B_BGA1!!!F124!!!!
S!@baseboard_fab2_lib.baseboard_fab2(sch_1):page63_i23@chpset_lib.skx_ext_b(chips)!SKX_EXT_B_BGA1-IC,TBD!U2D1!//jf4cfls225.pdx.intel.com/apd_proj/ppg_lib/chpset_lib/logical/skx_ext_b/chips/chips.prt!SKX_EXT_B!SKX_EXT_B_BGA1-IC,TBD!SKX_EXT_B_BGA1!!!F123!!!!
S!@baseboard_fab2_lib.baseboard_fab2(sch_1):page64_i68@chpset_lib.skx_ext_b(chips)!SKX_EXT_B_BGA1-IC,TBD!U2D1!//jf4cfls225.pdx.intel.com/apd_proj/ppg_lib/chpset_lib/logical/skx_ext_b/chips/chips.prt!SKX_EXT_B!SKX_EXT_B_BGA1-IC,TBD!SKX_EXT_B_BGA1!!!F122!!!!
S!@baseboard_fab2_lib.baseboard_fab2(sch_1):page65_i68@chpset_lib.skx_ext_b(chips)!SKX_EXT_B_BGA1-IC,TBD!U2D1!//jf4cfls225.pdx.intel.com/apd_proj/ppg_lib/chpset_lib/logical/skx_ext_b/chips/chips.prt!SKX_EXT_B!SKX_EXT_B_BGA1-IC,TBD!SKX_EXT_B_BGA1!!!F121!!!!
S!@baseboard_fab2_lib.baseboard_fab2(sch_1):page66_i84@chpset_lib.skx_ext_b(chips)!SKX_EXT_B_BGA1-IC,TBD!U2D1!//jf4cfls225.pdx.intel.com/apd_proj/ppg_lib/chpset_lib/logical/skx_ext_b/chips/chips.prt!SKX_EXT_B!SKX_EXT_B_BGA1-IC,TBD!SKX_EXT_B_BGA1!!!F120!!!!
S!@baseboard_fab2_lib.baseboard_fab2(sch_1):page67_i132@chpset_lib.skx_ext_b(chips)!SKX_EXT_B_BGA1-IC,TBD!U2D1!//jf4cfls225.pdx.intel.com/apd_proj/ppg_lib/chpset_lib/logical/skx_ext_b/chips/chips.prt!SKX_EXT_B!SKX_EXT_B_BGA1-IC,TBD!SKX_EXT_B_BGA1!!!F119!!!!
S!@baseboard_fab2_lib.baseboard_fab2(sch_1):page68_i125@chpset_lib.skx_ext_b(chips)!SKX_EXT_B_BGA1-IC,TBD!U2D1!//jf4cfls225.pdx.intel.com/apd_proj/ppg_lib/chpset_lib/logical/skx_ext_b/chips/chips.prt!SKX_EXT_B!SKX_EXT_B_BGA1-IC,TBD!SKX_EXT_B_BGA1!!!F118!!!!
S!@baseboard_fab2_lib.baseboard_fab2(sch_1):page69_i1@chpset_lib.skx_ext_b(chips)!SKX_EXT_B_BGA1-IC,TBD!U2D1!//jf4cfls225.pdx.intel.com/apd_proj/ppg_lib/chpset_lib/logical/skx_ext_b/chips/chips.prt!SKX_EXT_B!SKX_EXT_B_BGA1-IC,TBD!SKX_EXT_B_BGA1!!!F117!!!!
S!@baseboard_fab2_lib.baseboard_fab2(sch_1):page70_i9@chpset_lib.skx_ext_b(chips)!SKX_EXT_B_BGA1-IC,TBD!U2D1!//jf4cfls225.pdx.intel.com/apd_proj/ppg_lib/chpset_lib/logical/skx_ext_b/chips/chips.prt!SKX_EXT_B!SKX_EXT_B_BGA1-IC,TBD!SKX_EXT_B_BGA1!!!F116!!!!
S!@baseboard_fab2_lib.baseboard_fab2(sch_1):page70_i10@chpset_lib.skx_ext_b(chips)!SKX_EXT_B_BGA1-IC,TBD!U2D1!//jf4cfls225.pdx.intel.com/apd_proj/ppg_lib/chpset_lib/logical/skx_ext_b/chips/chips.prt!SKX_EXT_B!SKX_EXT_B_BGA1-IC,TBD!SKX_EXT_B_BGA1!!!F115!!!!
S!@baseboard_fab2_lib.baseboard_fab2(sch_1):page71_i50@chpset_lib.skx_ext_b(chips)!SKX_EXT_B_BGA1-IC,TBD!U2D1!//jf4cfls225.pdx.intel.com/apd_proj/ppg_lib/chpset_lib/logical/skx_ext_b/chips/chips.prt!SKX_EXT_B!SKX_EXT_B_BGA1-IC,TBD!SKX_EXT_B_BGA1!!!F114!!!!
S!@baseboard_fab2_lib.baseboard_fab2(sch_1):page71_i51@chpset_lib.skx_ext_b(chips)!SKX_EXT_B_BGA1-IC,TBD!U2D1!//jf4cfls225.pdx.intel.com/apd_proj/ppg_lib/chpset_lib/logical/skx_ext_b/chips/chips.prt!SKX_EXT_B!SKX_EXT_B_BGA1-IC,TBD!SKX_EXT_B_BGA1!!!F113!!!!
S!@baseboard_fab2_lib.baseboard_fab2(sch_1):page72_i32@chpset_lib.skx_ext_b(chips)!SKX_EXT_B_BGA1-IC,TBD!U2D1!//jf4cfls225.pdx.intel.com/apd_proj/ppg_lib/chpset_lib/logical/skx_ext_b/chips/chips.prt!SKX_EXT_B!SKX_EXT_B_BGA1-IC,TBD!SKX_EXT_B_BGA1!!!F112!!!!
S!@baseboard_fab2_lib.baseboard_fab2(sch_1):page72_i33@chpset_lib.skx_ext_b(chips)!SKX_EXT_B_BGA1-IC,TBD!U2D1!//jf4cfls225.pdx.intel.com/apd_proj/ppg_lib/chpset_lib/logical/skx_ext_b/chips/chips.prt!SKX_EXT_B!SKX_EXT_B_BGA1-IC,TBD!SKX_EXT_B_BGA1!!!F111!!!!
S!@baseboard_fab2_lib.baseboard_fab2(sch_1):page73_i107@chpset_lib.skx_ext_b(chips)!SKX_EXT_B_BGA1-IC,TBD!U2D1!//jf4cfls225.pdx.intel.com/apd_proj/ppg_lib/chpset_lib/logical/skx_ext_b/chips/chips.prt!SKX_EXT_B!SKX_EXT_B_BGA1-IC,TBD!SKX_EXT_B_BGA1!!!F110!!!!
S!@baseboard_fab2_lib.baseboard_fab2(sch_1):page74_i20@chpset_lib.skx_ext_b(chips)!SKX_EXT_B_BGA1-IC,TBD!U2D1!//jf4cfls225.pdx.intel.com/apd_proj/ppg_lib/chpset_lib/logical/skx_ext_b/chips/chips.prt!SKX_EXT_B!SKX_EXT_B_BGA1-IC,TBD!SKX_EXT_B_BGA1!!!F109!!!!
S!@baseboard_fab2_lib.baseboard_fab2(sch_1):page74_i21@chpset_lib.skx_ext_b(chips)!SKX_EXT_B_BGA1-IC,TBD!U2D1!//jf4cfls225.pdx.intel.com/apd_proj/ppg_lib/chpset_lib/logical/skx_ext_b/chips/chips.prt!SKX_EXT_B!SKX_EXT_B_BGA1-IC,TBD!SKX_EXT_B_BGA1!!!F108!!!!
S!@baseboard_fab2_lib.baseboard_fab2(sch_1):page74_i22@chpset_lib.skx_ext_b(chips)!SKX_EXT_B_BGA1-IC,TBD!U2D1!//jf4cfls225.pdx.intel.com/apd_proj/ppg_lib/chpset_lib/logical/skx_ext_b/chips/chips.prt!SKX_EXT_B!SKX_EXT_B_BGA1-IC,TBD!SKX_EXT_B_BGA1!!!F107!!!!
S!@baseboard_fab2_lib.baseboard_fab2(sch_1):page74_i23@chpset_lib.skx_ext_b(chips)!SKX_EXT_B_BGA1-IC,TBD!U2D1!//jf4cfls225.pdx.intel.com/apd_proj/ppg_lib/chpset_lib/logical/skx_ext_b/chips/chips.prt!SKX_EXT_B!SKX_EXT_B_BGA1-IC,TBD!SKX_EXT_B_BGA1!!!F106!!!!
S!@baseboard_fab2_lib.baseboard_fab2(sch_1):page75_i17@chpset_lib.skx_ext_b(chips)!SKX_EXT_B_BGA1-IC,TBD!U2D1!//jf4cfls225.pdx.intel.com/apd_proj/ppg_lib/chpset_lib/logical/skx_ext_b/chips/chips.prt!SKX_EXT_B!SKX_EXT_B_BGA1-IC,TBD!SKX_EXT_B_BGA1!!!F105!!!!
S!@baseboard_fab2_lib.baseboard_fab2(sch_1):page75_i18@chpset_lib.skx_ext_b(chips)!SKX_EXT_B_BGA1-IC,TBD!U2D1!//jf4cfls225.pdx.intel.com/apd_proj/ppg_lib/chpset_lib/logical/skx_ext_b/chips/chips.prt!SKX_EXT_B!SKX_EXT_B_BGA1-IC,TBD!SKX_EXT_B_BGA1!!!F104!!!!
S!@baseboard_fab2_lib.baseboard_fab2(sch_1):page75_i19@chpset_lib.skx_ext_b(chips)!SKX_EXT_B_BGA1-IC,TBD!U2D1!//jf4cfls225.pdx.intel.com/apd_proj/ppg_lib/chpset_lib/logical/skx_ext_b/chips/chips.prt!SKX_EXT_B!SKX_EXT_B_BGA1-IC,TBD!SKX_EXT_B_BGA1!!!F103!!!!
S!@baseboard_fab2_lib.baseboard_fab2(sch_1):page75_i20@chpset_lib.skx_ext_b(chips)!SKX_EXT_B_BGA1-IC,TBD!U2D1!//jf4cfls225.pdx.intel.com/apd_proj/ppg_lib/chpset_lib/logical/skx_ext_b/chips/chips.prt!SKX_EXT_B!SKX_EXT_B_BGA1-IC,TBD!SKX_EXT_B_BGA1!!!F102!!!!
S!@baseboard_fab2_lib.baseboard_fab2(sch_1):page198_i1@mstr_vreg.slg55021(chips)!SLG55021_SM-IC,G56246-001!EU2T1!//jf4cfls225.pdx.intel.com/apd_proj/ppg_lib/epg_masterlib/logical/mstr_vreg/slg55021/chips/chips.prt!SLG55021!SLG55021_SM-IC,G56246-001!SLG55021_SM!!!F71!!P3V3_PWR_SWITCH!!
S!@baseboard_fab2_lib.baseboard_fab2(sch_1):page198_i19@mstr_vreg.slg55021(chips)!SLG55021_SM-IC,G56246-001!EU7E1!//jf4cfls225.pdx.intel.com/apd_proj/ppg_lib/epg_masterlib/logical/mstr_vreg/slg55021/chips/chips.prt!SLG55021!SLG55021_SM-IC,G56246-001!SLG55021_SM!!!F70!!P12V_PWR_SWITCH!!
S!@baseboard_fab2_lib.baseboard_fab2(sch_1):page198_i13@mstr_vreg.slg55021(chips)!SLG55021_SM-IC,G56246-001!EU8B1!//jf4cfls225.pdx.intel.com/apd_proj/ppg_lib/epg_masterlib/logical/mstr_vreg/slg55021/chips/chips.prt!SLG55021!SLG55021_SM-IC,G56246-001!SLG55021_SM!!!F69!!P5V_PWR_SWITCH!!
S!@baseboard_fab2_lib.baseboard_fab2(sch_1):page198_i69@mstr_vreg.slg55021(chips)!SLG55021_SM-IC,G56246-001!EU9M1!//jf4cfls225.pdx.intel.com/apd_proj/ppg_lib/epg_masterlib/logical/mstr_vreg/slg55021/chips/chips.prt!SLG55021!SLG55021_SM-IC,G56246-001!SLG55021_SM!!!F68!!P12V_FAN_PWR_SWITCH!!
S!@baseboard_fab2_lib.baseboard_fab2(sch_1):page139_i109@mstr_discrete.crystal(chips)!CRYSTAL_2013-25.000MHZ,IC,D717A!Y9E1!//jf4cfls225.pdx.intel.com/apd_proj/ppg_lib/epg_masterlib/logical/mstr_discrete/crystal/chips/chips.prt!CRYSTAL!CRYSTAL_2013-25.000MHZ,IC,D71700-057!CRYSTAL_2013!!!F2232!!NIC_SPRV!!
S!@baseboard_fab2_lib.baseboard_fab2(sch_1):page196_i74@mstr_discrete.res(chips)!RES_0402-90.9K,1%,1/16W,CHIP,GA!R3P48!//jf4cfls225.pdx.intel.com/apd_proj/ppg_lib/epg_masterlib/logical/mstr_discrete/res/chips/chips.prt!RES!RES_0402-90.9K,1%,1/16W,CHIP,G21796-058!RES!!!F282!!V_SUPER!!
S!@baseboard_fab2_lib.baseboard_fab2(sch_1):page199_i84@mstr_discrete.res(chips)!RES_0402-90.9K,1%,1/16W,CHIP,GA!R1D13!//jf4cfls225.pdx.intel.com/apd_proj/ppg_lib/epg_masterlib/logical/mstr_discrete/res/chips/chips.prt!RES!RES_0402-90.9K,1%,1/16W,CHIP,G21796-058!RES!!!F283!!HOT_SWAP!!
S!@baseboard_fab2_lib.baseboard_fab2(sch_1):page212_i25@mstr_discrete.inductor(chips)!INDUCTOR_SM-150NH,IND,D92183-0A!L7C2!//jf4cfls225.pdx.intel.com/apd_proj/ppg_lib/epg_masterlib/logical/mstr_discrete/inductor/chips/chips.prt!INDUCTOR!INDUCTOR_SM-150NH,IND,D92183-021!INDUCTOR!!!F2083!!PVCCIO_CPU0!!
S!@baseboard_fab2_lib.baseboard_fab2(sch_1):page214_i67@mstr_discrete.inductor(chips)!INDUCTOR_SM-150NH,IND,D92183-0A!L4E2!//jf4cfls225.pdx.intel.com/apd_proj/ppg_lib/epg_masterlib/logical/mstr_discrete/inductor/chips/chips.prt!INDUCTOR!INDUCTOR_SM-150NH,IND,D92183-021!INDUCTOR!!!F2084!!PVCCIO_CPU1!!
S!@baseboard_fab2_lib.baseboard_fab2(sch_1):page188_i41@mstr_discrete.cap(chips)!CAP_1206LF-22UF,16V,10%,X6S,D3A!C2P10!//jf4cfls225.pdx.intel.com/apd_proj/ppg_lib/epg_masterlib/logical/mstr_discrete/cap/chips/chips.prt!CAP!CAP_1206LF-22UF,16V,10%,X6S,D38464-005!CAP!!!F2285!!IO_MODULE!!
S!@baseboard_fab2_lib.baseboard_fab2(sch_1):page240_i137@mstr_discrete.cap(chips)!CAP_1206LF-22UF,16V,10%,X6S,D3A!C8E10!//jf4cfls225.pdx.intel.com/apd_proj/ppg_lib/epg_masterlib/logical/mstr_discrete/cap/chips/chips.prt!CAP!CAP_1206LF-22UF,16V,10%,X6S,D38464-005!CAP!!!F2283!!P3V3_STBY_VR!!
S!@baseboard_fab2_lib.baseboard_fab2(sch_1):page241_i39@mstr_discrete.cap(chips)!CAP_1206LF-22UF,16V,10%,X6S,D3A!C7E11!//jf4cfls225.pdx.intel.com/apd_proj/ppg_lib/epg_masterlib/logical/mstr_discrete/cap/chips/chips.prt!CAP!CAP_1206LF-22UF,16V,10%,X6S,D38464-005!CAP!!!F2284!!P5V_STBY_VR!!
S!@baseboard_fab2_lib.baseboard_fab2(sch_1):page172_i53@mstr_conn.conn4_h73295001(chips)!CONN4_H73295001_PIP-EMPTY,H732A!J2L1!//jf4cfls225.pdx.intel.com/apd_proj/ppg_lib/epg_masterlib/logical/mstr_conn/conn4_h73295001/chips/chips.prt!CONN4_H73295001!CONN4_H73295001_PIP-EMPTY,H73295-001!CONN4_H73295001_PIP!!!F2243!!ST_SATA!!
S!@baseboard_fab2_lib.baseboard_fab2(sch_1):page43_i1@mstr_sconn.sconn288_h44441004(chips)!SCONN288_H44441004_PIP-SCONN,HA!J4G1!//jf4cfls225.pdx.intel.com/apd_proj/ppg_lib/epg_masterlib/logical/mstr_sconn/sconn288_h44441004/chips/chips.prt!SCONN288_H44441004!SCONN288_H44441004_PIP-SCONN,H44441-004!SCONN288_H44441004_PIP!!!F148!!DDR4_CH_A!!
S!@baseboard_fab2_lib.baseboard_fab2(sch_1):page43_i2@mstr_sconn.sconn288_h44441004(chips)!SCONN288_H44441004_PIP-SCONN,HA!J4G1!//jf4cfls225.pdx.intel.com/apd_proj/ppg_lib/epg_masterlib/logical/mstr_sconn/sconn288_h44441004/chips/chips.prt!SCONN288_H44441004!SCONN288_H44441004_PIP-SCONN,H44441-004!SCONN288_H44441004_PIP!!!F147!!DDR4_CH_A!!
S!@baseboard_fab2_lib.baseboard_fab2(sch_1):page43_i259@mstr_sconn.sconn288_h44441004(chips)!SCONN288_H44441004_PIP-SCONN,HA!J4G1!//jf4cfls225.pdx.intel.com/apd_proj/ppg_lib/epg_masterlib/logical/mstr_sconn/sconn288_h44441004/chips/chips.prt!SCONN288_H44441004!SCONN288_H44441004_PIP-SCONN,H44441-004!SCONN288_H44441004_PIP!!!F146!!DDR4_CH_A!!
S!@baseboard_fab2_lib.baseboard_fab2(sch_1):page43_i260@mstr_sconn.sconn288_h44441004(chips)!SCONN288_H44441004_PIP-SCONN,HA!J4G1!//jf4cfls225.pdx.intel.com/apd_proj/ppg_lib/epg_masterlib/logical/mstr_sconn/sconn288_h44441004/chips/chips.prt!SCONN288_H44441004!SCONN288_H44441004_PIP-SCONN,H44441-004!SCONN288_H44441004_PIP!!!F145!!DDR4_CH_A!!
S!@baseboard_fab2_lib.baseboard_fab2(sch_1):page45_i111@mstr_sconn.sconn288_h44441004(chips)!SCONN288_H44441004_PIP-SCONN,HA!J4G2!//jf4cfls225.pdx.intel.com/apd_proj/ppg_lib/epg_masterlib/logical/mstr_sconn/sconn288_h44441004/chips/chips.prt!SCONN288_H44441004!SCONN288_H44441004_PIP-SCONN,H44441-004!SCONN288_H44441004_PIP!!!F144!!DDR4_CH_B!!
S!@baseboard_fab2_lib.baseboard_fab2(sch_1):page45_i61@mstr_sconn.sconn288_h44441004(chips)!SCONN288_H44441004_PIP-SCONN,HA!J4G2!//jf4cfls225.pdx.intel.com/apd_proj/ppg_lib/epg_masterlib/logical/mstr_sconn/sconn288_h44441004/chips/chips.prt!SCONN288_H44441004!SCONN288_H44441004_PIP-SCONN,H44441-004!SCONN288_H44441004_PIP!!!F143!!DDR4_CH_B!!
S!@baseboard_fab2_lib.baseboard_fab2(sch_1):page45_i43@mstr_sconn.sconn288_h44441004(chips)!SCONN288_H44441004_PIP-SCONN,HA!J4G2!//jf4cfls225.pdx.intel.com/apd_proj/ppg_lib/epg_masterlib/logical/mstr_sconn/sconn288_h44441004/chips/chips.prt!SCONN288_H44441004!SCONN288_H44441004_PIP-SCONN,H44441-004!SCONN288_H44441004_PIP!!!F142!!DDR4_CH_B!!
S!@baseboard_fab2_lib.baseboard_fab2(sch_1):page45_i169@mstr_sconn.sconn288_h44441004(chips)!SCONN288_H44441004_PIP-SCONN,HA!J4G2!//jf4cfls225.pdx.intel.com/apd_proj/ppg_lib/epg_masterlib/logical/mstr_sconn/sconn288_h44441004/chips/chips.prt!SCONN288_H44441004!SCONN288_H44441004_PIP-SCONN,H44441-004!SCONN288_H44441004_PIP!!!F141!!DDR4_CH_B!!
S!@baseboard_fab2_lib.baseboard_fab2(sch_1):page47_i111@mstr_sconn.sconn288_h44441004(chips)!SCONN288_H44441004_PIP-SCONN,HA!J4G3!//jf4cfls225.pdx.intel.com/apd_proj/ppg_lib/epg_masterlib/logical/mstr_sconn/sconn288_h44441004/chips/chips.prt!SCONN288_H44441004!SCONN288_H44441004_PIP-SCONN,H44441-004!SCONN288_H44441004_PIP!!!F140!!DDR4_CH_C!!
S!@baseboard_fab2_lib.baseboard_fab2(sch_1):page47_i61@mstr_sconn.sconn288_h44441004(chips)!SCONN288_H44441004_PIP-SCONN,HA!J4G3!//jf4cfls225.pdx.intel.com/apd_proj/ppg_lib/epg_masterlib/logical/mstr_sconn/sconn288_h44441004/chips/chips.prt!SCONN288_H44441004!SCONN288_H44441004_PIP-SCONN,H44441-004!SCONN288_H44441004_PIP!!!F139!!DDR4_CH_C!!
S!@baseboard_fab2_lib.baseboard_fab2(sch_1):page47_i43@mstr_sconn.sconn288_h44441004(chips)!SCONN288_H44441004_PIP-SCONN,HA!J4G3!//jf4cfls225.pdx.intel.com/apd_proj/ppg_lib/epg_masterlib/logical/mstr_sconn/sconn288_h44441004/chips/chips.prt!SCONN288_H44441004!SCONN288_H44441004_PIP-SCONN,H44441-004!SCONN288_H44441004_PIP!!!F138!!DDR4_CH_C!!
S!@baseboard_fab2_lib.baseboard_fab2(sch_1):page47_i179@mstr_sconn.sconn288_h44441004(chips)!SCONN288_H44441004_PIP-SCONN,HA!J4G3!//jf4cfls225.pdx.intel.com/apd_proj/ppg_lib/epg_masterlib/logical/mstr_sconn/sconn288_h44441004/chips/chips.prt!SCONN288_H44441004!SCONN288_H44441004_PIP-SCONN,H44441-004!SCONN288_H44441004_PIP!!!F137!!DDR4_CH_C!!
S!@baseboard_fab2_lib.baseboard_fab2(sch_1):page49_i111@mstr_sconn.sconn288_h44441004(chips)!SCONN288_H44441004_PIP-SCONN,HA!J4B1!//jf4cfls225.pdx.intel.com/apd_proj/ppg_lib/epg_masterlib/logical/mstr_sconn/sconn288_h44441004/chips/chips.prt!SCONN288_H44441004!SCONN288_H44441004_PIP-SCONN,H44441-004!SCONN288_H44441004_PIP!!!F152!!DDR4_CH_D!!
S!@baseboard_fab2_lib.baseboard_fab2(sch_1):page49_i66@mstr_sconn.sconn288_h44441004(chips)!SCONN288_H44441004_PIP-SCONN,HA!J4B1!//jf4cfls225.pdx.intel.com/apd_proj/ppg_lib/epg_masterlib/logical/mstr_sconn/sconn288_h44441004/chips/chips.prt!SCONN288_H44441004!SCONN288_H44441004_PIP-SCONN,H44441-004!SCONN288_H44441004_PIP!!!F151!!DDR4_CH_D!!
S!@baseboard_fab2_lib.baseboard_fab2(sch_1):page49_i43@mstr_sconn.sconn288_h44441004(chips)!SCONN288_H44441004_PIP-SCONN,HA!J4B1!//jf4cfls225.pdx.intel.com/apd_proj/ppg_lib/epg_masterlib/logical/mstr_sconn/sconn288_h44441004/chips/chips.prt!SCONN288_H44441004!SCONN288_H44441004_PIP-SCONN,H44441-004!SCONN288_H44441004_PIP!!!F150!!DDR4_CH_D!!
S!@baseboard_fab2_lib.baseboard_fab2(sch_1):page49_i169@mstr_sconn.sconn288_h44441004(chips)!SCONN288_H44441004_PIP-SCONN,HA!J4B1!//jf4cfls225.pdx.intel.com/apd_proj/ppg_lib/epg_masterlib/logical/mstr_sconn/sconn288_h44441004/chips/chips.prt!SCONN288_H44441004!SCONN288_H44441004_PIP-SCONN,H44441-004!SCONN288_H44441004_PIP!!!F149!!DDR4_CH_D!!
S!@baseboard_fab2_lib.baseboard_fab2(sch_1):page51_i111@mstr_sconn.sconn288_h44441004(chips)!SCONN288_H44441004_PIP-SCONN,HA!J4A2!//jf4cfls225.pdx.intel.com/apd_proj/ppg_lib/epg_masterlib/logical/mstr_sconn/sconn288_h44441004/chips/chips.prt!SCONN288_H44441004!SCONN288_H44441004_PIP-SCONN,H44441-004!SCONN288_H44441004_PIP!!!F156!!DDR4_CH_E!!
S!@baseboard_fab2_lib.baseboard_fab2(sch_1):page51_i66@mstr_sconn.sconn288_h44441004(chips)!SCONN288_H44441004_PIP-SCONN,HA!J4A2!//jf4cfls225.pdx.intel.com/apd_proj/ppg_lib/epg_masterlib/logical/mstr_sconn/sconn288_h44441004/chips/chips.prt!SCONN288_H44441004!SCONN288_H44441004_PIP-SCONN,H44441-004!SCONN288_H44441004_PIP!!!F155!!DDR4_CH_E!!
S!@baseboard_fab2_lib.baseboard_fab2(sch_1):page51_i43@mstr_sconn.sconn288_h44441004(chips)!SCONN288_H44441004_PIP-SCONN,HA!J4A2!//jf4cfls225.pdx.intel.com/apd_proj/ppg_lib/epg_masterlib/logical/mstr_sconn/sconn288_h44441004/chips/chips.prt!SCONN288_H44441004!SCONN288_H44441004_PIP-SCONN,H44441-004!SCONN288_H44441004_PIP!!!F154!!DDR4_CH_E!!
S!@baseboard_fab2_lib.baseboard_fab2(sch_1):page51_i167@mstr_sconn.sconn288_h44441004(chips)!SCONN288_H44441004_PIP-SCONN,HA!J4A2!//jf4cfls225.pdx.intel.com/apd_proj/ppg_lib/epg_masterlib/logical/mstr_sconn/sconn288_h44441004/chips/chips.prt!SCONN288_H44441004!SCONN288_H44441004_PIP-SCONN,H44441-004!SCONN288_H44441004_PIP!!!F153!!DDR4_CH_E!!
S!@baseboard_fab2_lib.baseboard_fab2(sch_1):page53_i111@mstr_sconn.sconn288_h44441004(chips)!SCONN288_H44441004_PIP-SCONN,HA!J4A1!//jf4cfls225.pdx.intel.com/apd_proj/ppg_lib/epg_masterlib/logical/mstr_sconn/sconn288_h44441004/chips/chips.prt!SCONN288_H44441004!SCONN288_H44441004_PIP-SCONN,H44441-004!SCONN288_H44441004_PIP!!!F160!!DDR4_CH_F!!
S!@baseboard_fab2_lib.baseboard_fab2(sch_1):page53_i66@mstr_sconn.sconn288_h44441004(chips)!SCONN288_H44441004_PIP-SCONN,HA!J4A1!//jf4cfls225.pdx.intel.com/apd_proj/ppg_lib/epg_masterlib/logical/mstr_sconn/sconn288_h44441004/chips/chips.prt!SCONN288_H44441004!SCONN288_H44441004_PIP-SCONN,H44441-004!SCONN288_H44441004_PIP!!!F159!!DDR4_CH_F!!
S!@baseboard_fab2_lib.baseboard_fab2(sch_1):page53_i43@mstr_sconn.sconn288_h44441004(chips)!SCONN288_H44441004_PIP-SCONN,HA!J4A1!//jf4cfls225.pdx.intel.com/apd_proj/ppg_lib/epg_masterlib/logical/mstr_sconn/sconn288_h44441004/chips/chips.prt!SCONN288_H44441004!SCONN288_H44441004_PIP-SCONN,H44441-004!SCONN288_H44441004_PIP!!!F158!!DDR4_CH_F!!
S!@baseboard_fab2_lib.baseboard_fab2(sch_1):page53_i171@mstr_sconn.sconn288_h44441004(chips)!SCONN288_H44441004_PIP-SCONN,HA!J4A1!//jf4cfls225.pdx.intel.com/apd_proj/ppg_lib/epg_masterlib/logical/mstr_sconn/sconn288_h44441004/chips/chips.prt!SCONN288_H44441004!SCONN288_H44441004_PIP-SCONN,H44441-004!SCONN288_H44441004_PIP!!!F157!!DDR4_CH_F!!
S!@baseboard_fab2_lib.baseboard_fab2(sch_1):page77_i111@mstr_sconn.sconn288_h44441004(chips)!SCONN288_H44441004_PIP-SCONN,HA!J1G1!//jf4cfls225.pdx.intel.com/apd_proj/ppg_lib/epg_masterlib/logical/mstr_sconn/sconn288_h44441004/chips/chips.prt!SCONN288_H44441004!SCONN288_H44441004_PIP-SCONN,H44441-004!SCONN288_H44441004_PIP!!!F172!!DDR4_CH_G!!
S!@baseboard_fab2_lib.baseboard_fab2(sch_1):page77_i66@mstr_sconn.sconn288_h44441004(chips)!SCONN288_H44441004_PIP-SCONN,HA!J1G1!//jf4cfls225.pdx.intel.com/apd_proj/ppg_lib/epg_masterlib/logical/mstr_sconn/sconn288_h44441004/chips/chips.prt!SCONN288_H44441004!SCONN288_H44441004_PIP-SCONN,H44441-004!SCONN288_H44441004_PIP!!!F171!!DDR4_CH_G!!
S!@baseboard_fab2_lib.baseboard_fab2(sch_1):page77_i43@mstr_sconn.sconn288_h44441004(chips)!SCONN288_H44441004_PIP-SCONN,HA!J1G1!//jf4cfls225.pdx.intel.com/apd_proj/ppg_lib/epg_masterlib/logical/mstr_sconn/sconn288_h44441004/chips/chips.prt!SCONN288_H44441004!SCONN288_H44441004_PIP-SCONN,H44441-004!SCONN288_H44441004_PIP!!!F170!!DDR4_CH_G!!
S!@baseboard_fab2_lib.baseboard_fab2(sch_1):page77_i171@mstr_sconn.sconn288_h44441004(chips)!SCONN288_H44441004_PIP-SCONN,HA!J1G1!//jf4cfls225.pdx.intel.com/apd_proj/ppg_lib/epg_masterlib/logical/mstr_sconn/sconn288_h44441004/chips/chips.prt!SCONN288_H44441004!SCONN288_H44441004_PIP-SCONN,H44441-004!SCONN288_H44441004_PIP!!!F169!!DDR4_CH_G!!
S!@baseboard_fab2_lib.baseboard_fab2(sch_1):page79_i111@mstr_sconn.sconn288_h44441004(chips)!SCONN288_H44441004_PIP-SCONN,HA!J1G2!//jf4cfls225.pdx.intel.com/apd_proj/ppg_lib/epg_masterlib/logical/mstr_sconn/sconn288_h44441004/chips/chips.prt!SCONN288_H44441004!SCONN288_H44441004_PIP-SCONN,H44441-004!SCONN288_H44441004_PIP!!!F168!!DDR4_CH_H!!
S!@baseboard_fab2_lib.baseboard_fab2(sch_1):page79_i64@mstr_sconn.sconn288_h44441004(chips)!SCONN288_H44441004_PIP-SCONN,HA!J1G2!//jf4cfls225.pdx.intel.com/apd_proj/ppg_lib/epg_masterlib/logical/mstr_sconn/sconn288_h44441004/chips/chips.prt!SCONN288_H44441004!SCONN288_H44441004_PIP-SCONN,H44441-004!SCONN288_H44441004_PIP!!!F167!!DDR4_CH_H!!
S!@baseboard_fab2_lib.baseboard_fab2(sch_1):page79_i43@mstr_sconn.sconn288_h44441004(chips)!SCONN288_H44441004_PIP-SCONN,HA!J1G2!//jf4cfls225.pdx.intel.com/apd_proj/ppg_lib/epg_masterlib/logical/mstr_sconn/sconn288_h44441004/chips/chips.prt!SCONN288_H44441004!SCONN288_H44441004_PIP-SCONN,H44441-004!SCONN288_H44441004_PIP!!!F166!!DDR4_CH_H!!
S!@baseboard_fab2_lib.baseboard_fab2(sch_1):page79_i169@mstr_sconn.sconn288_h44441004(chips)!SCONN288_H44441004_PIP-SCONN,HA!J1G2!//jf4cfls225.pdx.intel.com/apd_proj/ppg_lib/epg_masterlib/logical/mstr_sconn/sconn288_h44441004/chips/chips.prt!SCONN288_H44441004!SCONN288_H44441004_PIP-SCONN,H44441-004!SCONN288_H44441004_PIP!!!F165!!DDR4_CH_H!!
S!@baseboard_fab2_lib.baseboard_fab2(sch_1):page81_i186@mstr_sconn.sconn288_h44441004(chips)!SCONN288_H44441004_PIP-SCONN,HA!J1G3!//jf4cfls225.pdx.intel.com/apd_proj/ppg_lib/epg_masterlib/logical/mstr_sconn/sconn288_h44441004/chips/chips.prt!SCONN288_H44441004!SCONN288_H44441004_PIP-SCONN,H44441-004!SCONN288_H44441004_PIP!!!F164!!DDR4_CH_J!!
S!@baseboard_fab2_lib.baseboard_fab2(sch_1):page81_i67@mstr_sconn.sconn288_h44441004(chips)!SCONN288_H44441004_PIP-SCONN,HA!J1G3!//jf4cfls225.pdx.intel.com/apd_proj/ppg_lib/epg_masterlib/logical/mstr_sconn/sconn288_h44441004/chips/chips.prt!SCONN288_H44441004!SCONN288_H44441004_PIP-SCONN,H44441-004!SCONN288_H44441004_PIP!!!F163!!DDR4_CH_J!!
S!@baseboard_fab2_lib.baseboard_fab2(sch_1):page81_i185@mstr_sconn.sconn288_h44441004(chips)!SCONN288_H44441004_PIP-SCONN,HA!J1G3!//jf4cfls225.pdx.intel.com/apd_proj/ppg_lib/epg_masterlib/logical/mstr_sconn/sconn288_h44441004/chips/chips.prt!SCONN288_H44441004!SCONN288_H44441004_PIP-SCONN,H44441-004!SCONN288_H44441004_PIP!!!F162!!DDR4_CH_J!!
S!@baseboard_fab2_lib.baseboard_fab2(sch_1):page81_i169@mstr_sconn.sconn288_h44441004(chips)!SCONN288_H44441004_PIP-SCONN,HA!J1G3!//jf4cfls225.pdx.intel.com/apd_proj/ppg_lib/epg_masterlib/logical/mstr_sconn/sconn288_h44441004/chips/chips.prt!SCONN288_H44441004!SCONN288_H44441004_PIP-SCONN,H44441-004!SCONN288_H44441004_PIP!!!F161!!DDR4_CH_J!!
S!@baseboard_fab2_lib.baseboard_fab2(sch_1):page83_i111@mstr_sconn.sconn288_h44441004(chips)!SCONN288_H44441004_PIP-SCONN,HA!J1B1!//jf4cfls225.pdx.intel.com/apd_proj/ppg_lib/epg_masterlib/logical/mstr_sconn/sconn288_h44441004/chips/chips.prt!SCONN288_H44441004!SCONN288_H44441004_PIP-SCONN,H44441-004!SCONN288_H44441004_PIP!!!F176!!DDR4_CH_K!!
S!@baseboard_fab2_lib.baseboard_fab2(sch_1):page83_i66@mstr_sconn.sconn288_h44441004(chips)!SCONN288_H44441004_PIP-SCONN,HA!J1B1!//jf4cfls225.pdx.intel.com/apd_proj/ppg_lib/epg_masterlib/logical/mstr_sconn/sconn288_h44441004/chips/chips.prt!SCONN288_H44441004!SCONN288_H44441004_PIP-SCONN,H44441-004!SCONN288_H44441004_PIP!!!F175!!DDR4_CH_K!!
S!@baseboard_fab2_lib.baseboard_fab2(sch_1):page83_i43@mstr_sconn.sconn288_h44441004(chips)!SCONN288_H44441004_PIP-SCONN,HA!J1B1!//jf4cfls225.pdx.intel.com/apd_proj/ppg_lib/epg_masterlib/logical/mstr_sconn/sconn288_h44441004/chips/chips.prt!SCONN288_H44441004!SCONN288_H44441004_PIP-SCONN,H44441-004!SCONN288_H44441004_PIP!!!F174!!DDR4_CH_K!!
S!@baseboard_fab2_lib.baseboard_fab2(sch_1):page83_i167@mstr_sconn.sconn288_h44441004(chips)!SCONN288_H44441004_PIP-SCONN,HA!J1B1!//jf4cfls225.pdx.intel.com/apd_proj/ppg_lib/epg_masterlib/logical/mstr_sconn/sconn288_h44441004/chips/chips.prt!SCONN288_H44441004!SCONN288_H44441004_PIP-SCONN,H44441-004!SCONN288_H44441004_PIP!!!F173!!DDR4_CH_K!!
S!@baseboard_fab2_lib.baseboard_fab2(sch_1):page85_i111@mstr_sconn.sconn288_h44441004(chips)!SCONN288_H44441004_PIP-SCONN,HA!J1A2!//jf4cfls225.pdx.intel.com/apd_proj/ppg_lib/epg_masterlib/logical/mstr_sconn/sconn288_h44441004/chips/chips.prt!SCONN288_H44441004!SCONN288_H44441004_PIP-SCONN,H44441-004!SCONN288_H44441004_PIP!!!F180!!DDR4_CH_L!!
S!@baseboard_fab2_lib.baseboard_fab2(sch_1):page85_i66@mstr_sconn.sconn288_h44441004(chips)!SCONN288_H44441004_PIP-SCONN,HA!J1A2!//jf4cfls225.pdx.intel.com/apd_proj/ppg_lib/epg_masterlib/logical/mstr_sconn/sconn288_h44441004/chips/chips.prt!SCONN288_H44441004!SCONN288_H44441004_PIP-SCONN,H44441-004!SCONN288_H44441004_PIP!!!F179!!DDR4_CH_L!!
S!@baseboard_fab2_lib.baseboard_fab2(sch_1):page85_i43@mstr_sconn.sconn288_h44441004(chips)!SCONN288_H44441004_PIP-SCONN,HA!J1A2!//jf4cfls225.pdx.intel.com/apd_proj/ppg_lib/epg_masterlib/logical/mstr_sconn/sconn288_h44441004/chips/chips.prt!SCONN288_H44441004!SCONN288_H44441004_PIP-SCONN,H44441-004!SCONN288_H44441004_PIP!!!F178!!DDR4_CH_L!!
S!@baseboard_fab2_lib.baseboard_fab2(sch_1):page85_i172@mstr_sconn.sconn288_h44441004(chips)!SCONN288_H44441004_PIP-SCONN,HA!J1A2!//jf4cfls225.pdx.intel.com/apd_proj/ppg_lib/epg_masterlib/logical/mstr_sconn/sconn288_h44441004/chips/chips.prt!SCONN288_H44441004!SCONN288_H44441004_PIP-SCONN,H44441-004!SCONN288_H44441004_PIP!!!F177!!DDR4_CH_L!!
S!@baseboard_fab2_lib.baseboard_fab2(sch_1):page87_i186@mstr_sconn.sconn288_h44441004(chips)!SCONN288_H44441004_PIP-SCONN,HA!J1A1!//jf4cfls225.pdx.intel.com/apd_proj/ppg_lib/epg_masterlib/logical/mstr_sconn/sconn288_h44441004/chips/chips.prt!SCONN288_H44441004!SCONN288_H44441004_PIP-SCONN,H44441-004!SCONN288_H44441004_PIP!!!F184!!DDR4_CH_M!!
S!@baseboard_fab2_lib.baseboard_fab2(sch_1):page87_i187@mstr_sconn.sconn288_h44441004(chips)!SCONN288_H44441004_PIP-SCONN,HA!J1A1!//jf4cfls225.pdx.intel.com/apd_proj/ppg_lib/epg_masterlib/logical/mstr_sconn/sconn288_h44441004/chips/chips.prt!SCONN288_H44441004!SCONN288_H44441004_PIP-SCONN,H44441-004!SCONN288_H44441004_PIP!!!F183!!DDR4_CH_M!!
S!@baseboard_fab2_lib.baseboard_fab2(sch_1):page87_i185@mstr_sconn.sconn288_h44441004(chips)!SCONN288_H44441004_PIP-SCONN,HA!J1A1!//jf4cfls225.pdx.intel.com/apd_proj/ppg_lib/epg_masterlib/logical/mstr_sconn/sconn288_h44441004/chips/chips.prt!SCONN288_H44441004!SCONN288_H44441004_PIP-SCONN,H44441-004!SCONN288_H44441004_PIP!!!F182!!DDR4_CH_M!!
S!@baseboard_fab2_lib.baseboard_fab2(sch_1):page87_i169@mstr_sconn.sconn288_h44441004(chips)!SCONN288_H44441004_PIP-SCONN,HA!J1A1!//jf4cfls225.pdx.intel.com/apd_proj/ppg_lib/epg_masterlib/logical/mstr_sconn/sconn288_h44441004/chips/chips.prt!SCONN288_H44441004!SCONN288_H44441004_PIP-SCONN,H44441-004!SCONN288_H44441004_PIP!!!F181!!DDR4_CH_M!!
S!@baseboard_fab2_lib.baseboard_fab2(sch_1):page138_i159@mstr_discrete.res(chips)!RES_0402-20.0,1%,1/16W,EMPTY,GA!R2U12!//jf4cfls225.pdx.intel.com/apd_proj/ppg_lib/epg_masterlib/logical/mstr_discrete/res/chips/chips.prt!RES!RES_0402-20.0,1%,1/16W,EMPTY,G21796-173!RES!!!F912!!SMBUS!!
S!@baseboard_fab2_lib.baseboard_fab2(sch_1):page138_i158@mstr_discrete.res(chips)!RES_0402-20.0,1%,1/16W,EMPTY,GA!R2U8!//jf4cfls225.pdx.intel.com/apd_proj/ppg_lib/epg_masterlib/logical/mstr_discrete/res/chips/chips.prt!RES!RES_0402-20.0,1%,1/16W,EMPTY,G21796-173!RES!!!F913!!SMBUS!!
S!@baseboard_fab2_lib.baseboard_fab2(sch_1):page108_i320@mstr_discrete.res(chips)!RES_0402-20.0,1%,1/16W,EMPTY,GA!R2U35!//jf4cfls225.pdx.intel.com/apd_proj/ppg_lib/epg_masterlib/logical/mstr_discrete/res/chips/chips.prt!RES!RES_0402-20.0,1%,1/16W,EMPTY,G21796-173!RES!!!F911!!SMBUS!!
S!@baseboard_fab2_lib.baseboard_fab2(sch_1):page108_i340@mstr_discrete.res(chips)!RES_0402-20.0,1%,1/16W,EMPTY,GA!R2U36!//jf4cfls225.pdx.intel.com/apd_proj/ppg_lib/epg_masterlib/logical/mstr_discrete/res/chips/chips.prt!RES!RES_0402-20.0,1%,1/16W,EMPTY,G21796-173!RES!!!F910!!SMBUS!!
S!@baseboard_fab2_lib.baseboard_fab2(sch_1):page44_i13@mstr_sconn.sconn288_h44441003(chips)!SCONN288_H44441003_PIP-SCONN,HA!J6T1!//jf4cfls225.pdx.intel.com/apd_proj/ppg_lib/epg_masterlib/logical/mstr_sconn/sconn288_h44441003/chips/chips.prt!SCONN288_H44441003!SCONN288_H44441003_PIP-SCONN,H44441-003!SCONN288_H44441003_PIP!!!F220!!DDR4_CH_A!!
S!@baseboard_fab2_lib.baseboard_fab2(sch_1):page44_i120@mstr_sconn.sconn288_h44441003(chips)!SCONN288_H44441003_PIP-SCONN,HA!J6T1!//jf4cfls225.pdx.intel.com/apd_proj/ppg_lib/epg_masterlib/logical/mstr_sconn/sconn288_h44441003/chips/chips.prt!SCONN288_H44441003!SCONN288_H44441003_PIP-SCONN,H44441-003!SCONN288_H44441003_PIP!!!F219!!DDR4_CH_A!!
S!@baseboard_fab2_lib.baseboard_fab2(sch_1):page44_i139@mstr_sconn.sconn288_h44441003(chips)!SCONN288_H44441003_PIP-SCONN,HA!J6T1!//jf4cfls225.pdx.intel.com/apd_proj/ppg_lib/epg_masterlib/logical/mstr_sconn/sconn288_h44441003/chips/chips.prt!SCONN288_H44441003!SCONN288_H44441003_PIP-SCONN,H44441-003!SCONN288_H44441003_PIP!!!F218!!DDR4_CH_A!!
S!@baseboard_fab2_lib.baseboard_fab2(sch_1):page44_i75@mstr_sconn.sconn288_h44441003(chips)!SCONN288_H44441003_PIP-SCONN,HA!J6T1!//jf4cfls225.pdx.intel.com/apd_proj/ppg_lib/epg_masterlib/logical/mstr_sconn/sconn288_h44441003/chips/chips.prt!SCONN288_H44441003!SCONN288_H44441003_PIP-SCONN,H44441-003!SCONN288_H44441003_PIP!!!F217!!DDR4_CH_A!!
S!@baseboard_fab2_lib.baseboard_fab2(sch_1):page46_i14@mstr_sconn.sconn288_h44441003(chips)!SCONN288_H44441003_PIP-SCONN,HA!J6U1!//jf4cfls225.pdx.intel.com/apd_proj/ppg_lib/epg_masterlib/logical/mstr_sconn/sconn288_h44441003/chips/chips.prt!SCONN288_H44441003!SCONN288_H44441003_PIP-SCONN,H44441-003!SCONN288_H44441003_PIP!!!F216!!DDR4_CH_B!!
S!@baseboard_fab2_lib.baseboard_fab2(sch_1):page46_i112@mstr_sconn.sconn288_h44441003(chips)!SCONN288_H44441003_PIP-SCONN,HA!J6U1!//jf4cfls225.pdx.intel.com/apd_proj/ppg_lib/epg_masterlib/logical/mstr_sconn/sconn288_h44441003/chips/chips.prt!SCONN288_H44441003!SCONN288_H44441003_PIP-SCONN,H44441-003!SCONN288_H44441003_PIP!!!F215!!DDR4_CH_B!!
S!@baseboard_fab2_lib.baseboard_fab2(sch_1):page46_i138@mstr_sconn.sconn288_h44441003(chips)!SCONN288_H44441003_PIP-SCONN,HA!J6U1!//jf4cfls225.pdx.intel.com/apd_proj/ppg_lib/epg_masterlib/logical/mstr_sconn/sconn288_h44441003/chips/chips.prt!SCONN288_H44441003!SCONN288_H44441003_PIP-SCONN,H44441-003!SCONN288_H44441003_PIP!!!F214!!DDR4_CH_B!!
S!@baseboard_fab2_lib.baseboard_fab2(sch_1):page46_i67@mstr_sconn.sconn288_h44441003(chips)!SCONN288_H44441003_PIP-SCONN,HA!J6U1!//jf4cfls225.pdx.intel.com/apd_proj/ppg_lib/epg_masterlib/logical/mstr_sconn/sconn288_h44441003/chips/chips.prt!SCONN288_H44441003!SCONN288_H44441003_PIP-SCONN,H44441-003!SCONN288_H44441003_PIP!!!F213!!DDR4_CH_B!!
S!@baseboard_fab2_lib.baseboard_fab2(sch_1):page48_i111@mstr_sconn.sconn288_h44441003(chips)!SCONN288_H44441003_PIP-SCONN,HA!J6U2!//jf4cfls225.pdx.intel.com/apd_proj/ppg_lib/epg_masterlib/logical/mstr_sconn/sconn288_h44441003/chips/chips.prt!SCONN288_H44441003!SCONN288_H44441003_PIP-SCONN,H44441-003!SCONN288_H44441003_PIP!!!F212!!DDR4_CH_C1!!
S!@baseboard_fab2_lib.baseboard_fab2(sch_1):page48_i61@mstr_sconn.sconn288_h44441003(chips)!SCONN288_H44441003_PIP-SCONN,HA!J6U2!//jf4cfls225.pdx.intel.com/apd_proj/ppg_lib/epg_masterlib/logical/mstr_sconn/sconn288_h44441003/chips/chips.prt!SCONN288_H44441003!SCONN288_H44441003_PIP-SCONN,H44441-003!SCONN288_H44441003_PIP!!!F211!!DDR4_CH_C1!!
S!@baseboard_fab2_lib.baseboard_fab2(sch_1):page48_i43@mstr_sconn.sconn288_h44441003(chips)!SCONN288_H44441003_PIP-SCONN,HA!J6U2!//jf4cfls225.pdx.intel.com/apd_proj/ppg_lib/epg_masterlib/logical/mstr_sconn/sconn288_h44441003/chips/chips.prt!SCONN288_H44441003!SCONN288_H44441003_PIP-SCONN,H44441-003!SCONN288_H44441003_PIP!!!F210!!DDR4_CH_C1!!
S!@baseboard_fab2_lib.baseboard_fab2(sch_1):page48_i171@mstr_sconn.sconn288_h44441003(chips)!SCONN288_H44441003_PIP-SCONN,HA!J6U2!//jf4cfls225.pdx.intel.com/apd_proj/ppg_lib/epg_masterlib/logical/mstr_sconn/sconn288_h44441003/chips/chips.prt!SCONN288_H44441003!SCONN288_H44441003_PIP-SCONN,H44441-003!SCONN288_H44441003_PIP!!!F209!!DDR4_CH_C1!!
S!@baseboard_fab2_lib.baseboard_fab2(sch_1):page50_i158@mstr_sconn.sconn288_h44441003(chips)!SCONN288_H44441003_PIP-SCONN,HA!J6M1!//jf4cfls225.pdx.intel.com/apd_proj/ppg_lib/epg_masterlib/logical/mstr_sconn/sconn288_h44441003/chips/chips.prt!SCONN288_H44441003!SCONN288_H44441003_PIP-SCONN,H44441-003!SCONN288_H44441003_PIP!!!F224!!DDR4_CH_D!!
S!@baseboard_fab2_lib.baseboard_fab2(sch_1):page50_i46@mstr_sconn.sconn288_h44441003(chips)!SCONN288_H44441003_PIP-SCONN,HA!J6M1!//jf4cfls225.pdx.intel.com/apd_proj/ppg_lib/epg_masterlib/logical/mstr_sconn/sconn288_h44441003/chips/chips.prt!SCONN288_H44441003!SCONN288_H44441003_PIP-SCONN,H44441-003!SCONN288_H44441003_PIP!!!F223!!DDR4_CH_D!!
S!@baseboard_fab2_lib.baseboard_fab2(sch_1):page50_i44@mstr_sconn.sconn288_h44441003(chips)!SCONN288_H44441003_PIP-SCONN,HA!J6M1!//jf4cfls225.pdx.intel.com/apd_proj/ppg_lib/epg_masterlib/logical/mstr_sconn/sconn288_h44441003/chips/chips.prt!SCONN288_H44441003!SCONN288_H44441003_PIP-SCONN,H44441-003!SCONN288_H44441003_PIP!!!F222!!DDR4_CH_D!!
S!@baseboard_fab2_lib.baseboard_fab2(sch_1):page50_i50@mstr_sconn.sconn288_h44441003(chips)!SCONN288_H44441003_PIP-SCONN,HA!J6M1!//jf4cfls225.pdx.intel.com/apd_proj/ppg_lib/epg_masterlib/logical/mstr_sconn/sconn288_h44441003/chips/chips.prt!SCONN288_H44441003!SCONN288_H44441003_PIP-SCONN,H44441-003!SCONN288_H44441003_PIP!!!F221!!DDR4_CH_D!!
S!@baseboard_fab2_lib.baseboard_fab2(sch_1):page52_i12@mstr_sconn.sconn288_h44441003(chips)!SCONN288_H44441003_PIP-SCONN,HA!J6L2!//jf4cfls225.pdx.intel.com/apd_proj/ppg_lib/epg_masterlib/logical/mstr_sconn/sconn288_h44441003/chips/chips.prt!SCONN288_H44441003!SCONN288_H44441003_PIP-SCONN,H44441-003!SCONN288_H44441003_PIP!!!F228!!DDR4_CH_E!!
S!@baseboard_fab2_lib.baseboard_fab2(sch_1):page52_i100@mstr_sconn.sconn288_h44441003(chips)!SCONN288_H44441003_PIP-SCONN,HA!J6L2!//jf4cfls225.pdx.intel.com/apd_proj/ppg_lib/epg_masterlib/logical/mstr_sconn/sconn288_h44441003/chips/chips.prt!SCONN288_H44441003!SCONN288_H44441003_PIP-SCONN,H44441-003!SCONN288_H44441003_PIP!!!F227!!DDR4_CH_E!!
S!@baseboard_fab2_lib.baseboard_fab2(sch_1):page52_i138@mstr_sconn.sconn288_h44441003(chips)!SCONN288_H44441003_PIP-SCONN,HA!J6L2!//jf4cfls225.pdx.intel.com/apd_proj/ppg_lib/epg_masterlib/logical/mstr_sconn/sconn288_h44441003/chips/chips.prt!SCONN288_H44441003!SCONN288_H44441003_PIP-SCONN,H44441-003!SCONN288_H44441003_PIP!!!F226!!DDR4_CH_E!!
S!@baseboard_fab2_lib.baseboard_fab2(sch_1):page52_i55@mstr_sconn.sconn288_h44441003(chips)!SCONN288_H44441003_PIP-SCONN,HA!J6L2!//jf4cfls225.pdx.intel.com/apd_proj/ppg_lib/epg_masterlib/logical/mstr_sconn/sconn288_h44441003/chips/chips.prt!SCONN288_H44441003!SCONN288_H44441003_PIP-SCONN,H44441-003!SCONN288_H44441003_PIP!!!F225!!DDR4_CH_E!!
S!@baseboard_fab2_lib.baseboard_fab2(sch_1):page54_i111@mstr_sconn.sconn288_h44441003(chips)!SCONN288_H44441003_PIP-SCONN,HA!J6L1!//jf4cfls225.pdx.intel.com/apd_proj/ppg_lib/epg_masterlib/logical/mstr_sconn/sconn288_h44441003/chips/chips.prt!SCONN288_H44441003!SCONN288_H44441003_PIP-SCONN,H44441-003!SCONN288_H44441003_PIP!!!F232!!DDR4_CH_F1!!
S!@baseboard_fab2_lib.baseboard_fab2(sch_1):page54_i66@mstr_sconn.sconn288_h44441003(chips)!SCONN288_H44441003_PIP-SCONN,HA!J6L1!//jf4cfls225.pdx.intel.com/apd_proj/ppg_lib/epg_masterlib/logical/mstr_sconn/sconn288_h44441003/chips/chips.prt!SCONN288_H44441003!SCONN288_H44441003_PIP-SCONN,H44441-003!SCONN288_H44441003_PIP!!!F231!!DDR4_CH_F1!!
S!@baseboard_fab2_lib.baseboard_fab2(sch_1):page54_i43@mstr_sconn.sconn288_h44441003(chips)!SCONN288_H44441003_PIP-SCONN,HA!J6L1!//jf4cfls225.pdx.intel.com/apd_proj/ppg_lib/epg_masterlib/logical/mstr_sconn/sconn288_h44441003/chips/chips.prt!SCONN288_H44441003!SCONN288_H44441003_PIP-SCONN,H44441-003!SCONN288_H44441003_PIP!!!F230!!DDR4_CH_F1!!
S!@baseboard_fab2_lib.baseboard_fab2(sch_1):page54_i170@mstr_sconn.sconn288_h44441003(chips)!SCONN288_H44441003_PIP-SCONN,HA!J6L1!//jf4cfls225.pdx.intel.com/apd_proj/ppg_lib/epg_masterlib/logical/mstr_sconn/sconn288_h44441003/chips/chips.prt!SCONN288_H44441003!SCONN288_H44441003_PIP-SCONN,H44441-003!SCONN288_H44441003_PIP!!!F229!!DDR4_CH_F1!!
S!@baseboard_fab2_lib.baseboard_fab2(sch_1):page78_i13@mstr_sconn.sconn288_h44441003(chips)!SCONN288_H44441003_PIP-SCONN,HA!J9T1!//jf4cfls225.pdx.intel.com/apd_proj/ppg_lib/epg_masterlib/logical/mstr_sconn/sconn288_h44441003/chips/chips.prt!SCONN288_H44441003!SCONN288_H44441003_PIP-SCONN,H44441-003!SCONN288_H44441003_PIP!!!F196!!DDR4_GH_G!!
S!@baseboard_fab2_lib.baseboard_fab2(sch_1):page78_i120@mstr_sconn.sconn288_h44441003(chips)!SCONN288_H44441003_PIP-SCONN,HA!J9T1!//jf4cfls225.pdx.intel.com/apd_proj/ppg_lib/epg_masterlib/logical/mstr_sconn/sconn288_h44441003/chips/chips.prt!SCONN288_H44441003!SCONN288_H44441003_PIP-SCONN,H44441-003!SCONN288_H44441003_PIP!!!F195!!DDR4_GH_G!!
S!@baseboard_fab2_lib.baseboard_fab2(sch_1):page78_i144@mstr_sconn.sconn288_h44441003(chips)!SCONN288_H44441003_PIP-SCONN,HA!J9T1!//jf4cfls225.pdx.intel.com/apd_proj/ppg_lib/epg_masterlib/logical/mstr_sconn/sconn288_h44441003/chips/chips.prt!SCONN288_H44441003!SCONN288_H44441003_PIP-SCONN,H44441-003!SCONN288_H44441003_PIP!!!F194!!DDR4_GH_G!!
S!@baseboard_fab2_lib.baseboard_fab2(sch_1):page78_i75@mstr_sconn.sconn288_h44441003(chips)!SCONN288_H44441003_PIP-SCONN,HA!J9T1!//jf4cfls225.pdx.intel.com/apd_proj/ppg_lib/epg_masterlib/logical/mstr_sconn/sconn288_h44441003/chips/chips.prt!SCONN288_H44441003!SCONN288_H44441003_PIP-SCONN,H44441-003!SCONN288_H44441003_PIP!!!F193!!DDR4_GH_G!!
S!@baseboard_fab2_lib.baseboard_fab2(sch_1):page80_i24@mstr_sconn.sconn288_h44441003(chips)!SCONN288_H44441003_PIP-SCONN,HA!J9U1!//jf4cfls225.pdx.intel.com/apd_proj/ppg_lib/epg_masterlib/logical/mstr_sconn/sconn288_h44441003/chips/chips.prt!SCONN288_H44441003!SCONN288_H44441003_PIP-SCONN,H44441-003!SCONN288_H44441003_PIP!!!F192!!DDR4_GH_H!!
S!@baseboard_fab2_lib.baseboard_fab2(sch_1):page80_i101@mstr_sconn.sconn288_h44441003(chips)!SCONN288_H44441003_PIP-SCONN,HA!J9U1!//jf4cfls225.pdx.intel.com/apd_proj/ppg_lib/epg_masterlib/logical/mstr_sconn/sconn288_h44441003/chips/chips.prt!SCONN288_H44441003!SCONN288_H44441003_PIP-SCONN,H44441-003!SCONN288_H44441003_PIP!!!F191!!DDR4_GH_H!!
S!@baseboard_fab2_lib.baseboard_fab2(sch_1):page80_i138@mstr_sconn.sconn288_h44441003(chips)!SCONN288_H44441003_PIP-SCONN,HA!J9U1!//jf4cfls225.pdx.intel.com/apd_proj/ppg_lib/epg_masterlib/logical/mstr_sconn/sconn288_h44441003/chips/chips.prt!SCONN288_H44441003!SCONN288_H44441003_PIP-SCONN,H44441-003!SCONN288_H44441003_PIP!!!F190!!DDR4_GH_H!!
S!@baseboard_fab2_lib.baseboard_fab2(sch_1):page80_i56@mstr_sconn.sconn288_h44441003(chips)!SCONN288_H44441003_PIP-SCONN,HA!J9U1!//jf4cfls225.pdx.intel.com/apd_proj/ppg_lib/epg_masterlib/logical/mstr_sconn/sconn288_h44441003/chips/chips.prt!SCONN288_H44441003!SCONN288_H44441003_PIP-SCONN,H44441-003!SCONN288_H44441003_PIP!!!F189!!DDR4_GH_H!!
S!@baseboard_fab2_lib.baseboard_fab2(sch_1):page82_i187@mstr_sconn.sconn288_h44441003(chips)!SCONN288_H44441003_PIP-SCONN,HA!J9U2!//jf4cfls225.pdx.intel.com/apd_proj/ppg_lib/epg_masterlib/logical/mstr_sconn/sconn288_h44441003/chips/chips.prt!SCONN288_H44441003!SCONN288_H44441003_PIP-SCONN,H44441-003!SCONN288_H44441003_PIP!!!F188!!DDR4_CH_J!!
S!@baseboard_fab2_lib.baseboard_fab2(sch_1):page82_i64@mstr_sconn.sconn288_h44441003(chips)!SCONN288_H44441003_PIP-SCONN,HA!J9U2!//jf4cfls225.pdx.intel.com/apd_proj/ppg_lib/epg_masterlib/logical/mstr_sconn/sconn288_h44441003/chips/chips.prt!SCONN288_H44441003!SCONN288_H44441003_PIP-SCONN,H44441-003!SCONN288_H44441003_PIP!!!F187!!DDR4_CH_J!!
S!@baseboard_fab2_lib.baseboard_fab2(sch_1):page82_i188@mstr_sconn.sconn288_h44441003(chips)!SCONN288_H44441003_PIP-SCONN,HA!J9U2!//jf4cfls225.pdx.intel.com/apd_proj/ppg_lib/epg_masterlib/logical/mstr_sconn/sconn288_h44441003/chips/chips.prt!SCONN288_H44441003!SCONN288_H44441003_PIP-SCONN,H44441-003!SCONN288_H44441003_PIP!!!F186!!DDR4_CH_J!!
S!@baseboard_fab2_lib.baseboard_fab2(sch_1):page82_i171@mstr_sconn.sconn288_h44441003(chips)!SCONN288_H44441003_PIP-SCONN,HA!J9U2!//jf4cfls225.pdx.intel.com/apd_proj/ppg_lib/epg_masterlib/logical/mstr_sconn/sconn288_h44441003/chips/chips.prt!SCONN288_H44441003!SCONN288_H44441003_PIP-SCONN,H44441-003!SCONN288_H44441003_PIP!!!F185!!DDR4_CH_J!!
S!@baseboard_fab2_lib.baseboard_fab2(sch_1):page84_i14@mstr_sconn.sconn288_h44441003(chips)!SCONN288_H44441003_PIP-SCONN,HA!J9M1!//jf4cfls225.pdx.intel.com/apd_proj/ppg_lib/epg_masterlib/logical/mstr_sconn/sconn288_h44441003/chips/chips.prt!SCONN288_H44441003!SCONN288_H44441003_PIP-SCONN,H44441-003!SCONN288_H44441003_PIP!!!F200!!DDR4_CH_K!!
S!@baseboard_fab2_lib.baseboard_fab2(sch_1):page84_i102@mstr_sconn.sconn288_h44441003(chips)!SCONN288_H44441003_PIP-SCONN,HA!J9M1!//jf4cfls225.pdx.intel.com/apd_proj/ppg_lib/epg_masterlib/logical/mstr_sconn/sconn288_h44441003/chips/chips.prt!SCONN288_H44441003!SCONN288_H44441003_PIP-SCONN,H44441-003!SCONN288_H44441003_PIP!!!F199!!DDR4_CH_K!!
S!@baseboard_fab2_lib.baseboard_fab2(sch_1):page84_i138@mstr_sconn.sconn288_h44441003(chips)!SCONN288_H44441003_PIP-SCONN,HA!J9M1!//jf4cfls225.pdx.intel.com/apd_proj/ppg_lib/epg_masterlib/logical/mstr_sconn/sconn288_h44441003/chips/chips.prt!SCONN288_H44441003!SCONN288_H44441003_PIP-SCONN,H44441-003!SCONN288_H44441003_PIP!!!F198!!DDR4_CH_K!!
S!@baseboard_fab2_lib.baseboard_fab2(sch_1):page84_i57@mstr_sconn.sconn288_h44441003(chips)!SCONN288_H44441003_PIP-SCONN,HA!J9M1!//jf4cfls225.pdx.intel.com/apd_proj/ppg_lib/epg_masterlib/logical/mstr_sconn/sconn288_h44441003/chips/chips.prt!SCONN288_H44441003!SCONN288_H44441003_PIP-SCONN,H44441-003!SCONN288_H44441003_PIP!!!F197!!DDR4_CH_K!!
S!@baseboard_fab2_lib.baseboard_fab2(sch_1):page86_i12@mstr_sconn.sconn288_h44441003(chips)!SCONN288_H44441003_PIP-SCONN,HA!J9L2!//jf4cfls225.pdx.intel.com/apd_proj/ppg_lib/epg_masterlib/logical/mstr_sconn/sconn288_h44441003/chips/chips.prt!SCONN288_H44441003!SCONN288_H44441003_PIP-SCONN,H44441-003!SCONN288_H44441003_PIP!!!F204!!DDR4_CH_L!!
S!@baseboard_fab2_lib.baseboard_fab2(sch_1):page86_i100@mstr_sconn.sconn288_h44441003(chips)!SCONN288_H44441003_PIP-SCONN,HA!J9L2!//jf4cfls225.pdx.intel.com/apd_proj/ppg_lib/epg_masterlib/logical/mstr_sconn/sconn288_h44441003/chips/chips.prt!SCONN288_H44441003!SCONN288_H44441003_PIP-SCONN,H44441-003!SCONN288_H44441003_PIP!!!F203!!DDR4_CH_L!!
S!@baseboard_fab2_lib.baseboard_fab2(sch_1):page86_i138@mstr_sconn.sconn288_h44441003(chips)!SCONN288_H44441003_PIP-SCONN,HA!J9L2!//jf4cfls225.pdx.intel.com/apd_proj/ppg_lib/epg_masterlib/logical/mstr_sconn/sconn288_h44441003/chips/chips.prt!SCONN288_H44441003!SCONN288_H44441003_PIP-SCONN,H44441-003!SCONN288_H44441003_PIP!!!F202!!DDR4_CH_L!!
S!@baseboard_fab2_lib.baseboard_fab2(sch_1):page86_i55@mstr_sconn.sconn288_h44441003(chips)!SCONN288_H44441003_PIP-SCONN,HA!J9L2!//jf4cfls225.pdx.intel.com/apd_proj/ppg_lib/epg_masterlib/logical/mstr_sconn/sconn288_h44441003/chips/chips.prt!SCONN288_H44441003!SCONN288_H44441003_PIP-SCONN,H44441-003!SCONN288_H44441003_PIP!!!F201!!DDR4_CH_L!!
S!@baseboard_fab2_lib.baseboard_fab2(sch_1):page88_i111@mstr_sconn.sconn288_h44441003(chips)!SCONN288_H44441003_PIP-SCONN,HA!J9L1!//jf4cfls225.pdx.intel.com/apd_proj/ppg_lib/epg_masterlib/logical/mstr_sconn/sconn288_h44441003/chips/chips.prt!SCONN288_H44441003!SCONN288_H44441003_PIP-SCONN,H44441-003!SCONN288_H44441003_PIP!!!F208!!DDR4_CH_M!!
S!@baseboard_fab2_lib.baseboard_fab2(sch_1):page88_i87@mstr_sconn.sconn288_h44441003(chips)!SCONN288_H44441003_PIP-SCONN,HA!J9L1!//jf4cfls225.pdx.intel.com/apd_proj/ppg_lib/epg_masterlib/logical/mstr_sconn/sconn288_h44441003/chips/chips.prt!SCONN288_H44441003!SCONN288_H44441003_PIP-SCONN,H44441-003!SCONN288_H44441003_PIP!!!F207!!DDR4_CH_M!!
S!@baseboard_fab2_lib.baseboard_fab2(sch_1):page88_i25@mstr_sconn.sconn288_h44441003(chips)!SCONN288_H44441003_PIP-SCONN,HA!J9L1!//jf4cfls225.pdx.intel.com/apd_proj/ppg_lib/epg_masterlib/logical/mstr_sconn/sconn288_h44441003/chips/chips.prt!SCONN288_H44441003!SCONN288_H44441003_PIP-SCONN,H44441-003!SCONN288_H44441003_PIP!!!F206!!DDR4_CH_M!!
S!@baseboard_fab2_lib.baseboard_fab2(sch_1):page88_i168@mstr_sconn.sconn288_h44441003(chips)!SCONN288_H44441003_PIP-SCONN,HA!J9L1!//jf4cfls225.pdx.intel.com/apd_proj/ppg_lib/epg_masterlib/logical/mstr_sconn/sconn288_h44441003/chips/chips.prt!SCONN288_H44441003!SCONN288_H44441003_PIP-SCONN,H44441-003!SCONN288_H44441003_PIP!!!F205!!DDR4_CH_M!!
S!@baseboard_fab2_lib.baseboard_fab2(sch_1):page187_i119@mstr_sconn.sconn80_e67482007(chips)!SCONN80_E67482007_SM-CONN,E674A!J8E3!//jf4cfls225.pdx.intel.com/apd_proj/ppg_lib/epg_masterlib/logical/mstr_sconn/sconn80_e67482007/chips/chips.prt!SCONN80_E67482007!SCONN80_E67482007_SM-CONN,E67482-007!SCONN80_E67482007_SM!!!F132!!IO_SLOT!!
S!@baseboard_fab2_lib.baseboard_fab2(sch_1):page194_i156@mstr_discrete.res(chips)!RES_0402-16K,1.0%,1/16W,CHIP,GA!R3N29!//jf4cfls225.pdx.intel.com/apd_proj/ppg_lib/epg_masterlib/logical/mstr_discrete/res/chips/chips.prt!RES!RES_0402-16K,1.0%,1/16W,CHIP,G21796-317!RES!!!F1063!!VDDQ_ABC_PWR_VR!!
S!@baseboard_fab2_lib.baseboard_fab2(sch_1):page199_i102@mstr_discrete.res(chips)!RES_0402-16K,1.0%,1/16W,CHIP,GA!R1D34!//jf4cfls225.pdx.intel.com/apd_proj/ppg_lib/epg_masterlib/logical/mstr_discrete/res/chips/chips.prt!RES!RES_0402-16K,1.0%,1/16W,CHIP,G21796-317!RES!!!F1064!!HOT_SWAP!!
S!@baseboard_fab2_lib.baseboard_fab2(sch_1):page223_i78@mstr_discrete.res(chips)!RES_0402-5.36K,1.0%,1/16W,CHIPA!R1G22!//jf4cfls225.pdx.intel.com/apd_proj/ppg_lib/epg_masterlib/logical/mstr_discrete/res/chips/chips.prt!RES!RES_0402-5.36K,1.0%,1/16W,CHIP,G21796-297!RES!!!F388!!VDDQ_GHJ_PWR_VR!!
S!@baseboard_fab2_lib.baseboard_fab2(sch_1):page226_i77@mstr_discrete.res(chips)!RES_0402-5.36K,1.0%,1/16W,CHIPA!R1B15!//jf4cfls225.pdx.intel.com/apd_proj/ppg_lib/epg_masterlib/logical/mstr_discrete/res/chips/chips.prt!RES!RES_0402-5.36K,1.0%,1/16W,CHIP,G21796-297!RES!!!F389!!VDDQ_KLM_PWR_VR!!
S!@baseboard_fab2_lib.baseboard_fab2(sch_1):page186_i336@mstr_sconn.sconn120_a28699018(chips)!SCONN120_A28699018_SM-SCONN,A2A!J9B3!//jf4cfls225.pdx.intel.com/apd_proj/ppg_lib/epg_masterlib/logical/mstr_sconn/sconn120_a28699018/chips/chips.prt!SCONN120_A28699018!SCONN120_A28699018_SM-SCONN,A28699-018!SCONN120_A28699018_SM!!!F240!!IO_SLOT!!
S!@baseboard_fab2_lib.baseboard_fab2(sch_1):page111_i94@mstr_discrete.npn_dual(chips)!NPN_DUAL_SSOPLF-MBT3904,EMPTY,A!Q9A1!//jf4cfls225.pdx.intel.com/apd_proj/ppg_lib/epg_masterlib/logical/mstr_discrete/npn_dual/chips/chips.prt!NPN_DUAL!NPN_DUAL_SSOPLF-MBT3904,EMPTY,C52264-001!NPN_DUAL!1!!F1998!!DEBUG!!
S!@baseboard_fab2_lib.baseboard_fab2(sch_1):page111_i93@mstr_discrete.npn_dual(chips)!NPN_DUAL_SSOPLF-MBT3904,EMPTY,A!Q9A1!//jf4cfls225.pdx.intel.com/apd_proj/ppg_lib/epg_masterlib/logical/mstr_discrete/npn_dual/chips/chips.prt!NPN_DUAL!NPN_DUAL_SSOPLF-MBT3904,EMPTY,C52264-001!NPN_DUAL!1!!F1997!!DEBUG!!
S!@baseboard_fab2_lib.baseboard_fab2(sch_1):page161_i50@mstr_discrete.diode(chips)!DIODE_SM-SDMK0340L,EMPTY,H7179A!CR1E1!//jf4cfls225.pdx.intel.com/apd_proj/ppg_lib/epg_masterlib/logical/mstr_discrete/diode/chips/chips.prt!DIODE!DIODE_SM-SDMK0340L,EMPTY,H71799-001!DIODE_SM!!!F2216!!CPU_FANS!!
S!@baseboard_fab2_lib.baseboard_fab2(sch_1):page161_i64@mstr_discrete.diode(chips)!DIODE_SM-SDMK0340L,EMPTY,H7179A!CR1B1!//jf4cfls225.pdx.intel.com/apd_proj/ppg_lib/epg_masterlib/logical/mstr_discrete/diode/chips/chips.prt!DIODE!DIODE_SM-SDMK0340L,EMPTY,H71799-001!DIODE_SM!!!F2217!!CPU_FANS!!
S!@baseboard_fab2_lib.baseboard_fab2(sch_1):page184_i104@mstr_misc.standoff(chips)!STANDOFF_TH1-SO,H72821-001!RM8D1!//jf4cfls225.pdx.intel.com/apd_proj/ppg_lib/epg_masterlib/logical/mstr_misc/standoff/chips/chips.prt!STANDOFF!STANDOFF_TH1-SO,H72821-001!STANDOFF_TH1!!!F66!!!!
S!@baseboard_fab2_lib.baseboard_fab2(sch_1):page172_i25@mstr_conn.conn4_h73295001(chips)!CONN4_H73295001_PIP-CONN,H7329A!J8A4!//jf4cfls225.pdx.intel.com/apd_proj/ppg_lib/epg_masterlib/logical/mstr_conn/conn4_h73295001/chips/chips.prt!CONN4_H73295001!CONN4_H73295001_PIP-CONN,H73295-001!CONN4_H73295001_PIP!!!F2244!!ST_SATA!!
S!@baseboard_fab2_lib.baseboard_fab2(sch_1):page161_i133@mstr_discrete.diode(chips)!DIODE_SM-SDMK0340L,IC,H71799-0A!CR1F2!//jf4cfls225.pdx.intel.com/apd_proj/ppg_lib/epg_masterlib/logical/mstr_discrete/diode/chips/chips.prt!DIODE!DIODE_SM-SDMK0340L,IC,H71799-001!DIODE_SM!!!F2212!!CPU_FANS!!
S!@baseboard_fab2_lib.baseboard_fab2(sch_1):page161_i123@mstr_discrete.diode(chips)!DIODE_SM-SDMK0340L,IC,H71799-0A!CR1B3!//jf4cfls225.pdx.intel.com/apd_proj/ppg_lib/epg_masterlib/logical/mstr_discrete/diode/chips/chips.prt!DIODE!DIODE_SM-SDMK0340L,IC,H71799-001!DIODE_SM!!!F2214!!CPU_FANS!!
S!@baseboard_fab2_lib.baseboard_fab2(sch_1):page161_i42@mstr_discrete.diode(chips)!DIODE_SM-SDMK0340L,IC,H71799-0A!CR1F1!//jf4cfls225.pdx.intel.com/apd_proj/ppg_lib/epg_masterlib/logical/mstr_discrete/diode/chips/chips.prt!DIODE!DIODE_SM-SDMK0340L,IC,H71799-001!DIODE_SM!!!F2213!!CPU_FANS!!
S!@baseboard_fab2_lib.baseboard_fab2(sch_1):page161_i62@mstr_discrete.diode(chips)!DIODE_SM-SDMK0340L,IC,H71799-0A!CR1B2!//jf4cfls225.pdx.intel.com/apd_proj/ppg_lib/epg_masterlib/logical/mstr_discrete/diode/chips/chips.prt!DIODE!DIODE_SM-SDMK0340L,IC,H71799-001!DIODE_SM!!!F2215!!CPU_FANS!!
S!@baseboard_fab2_lib.baseboard_fab2(sch_1):page181_i178@mstr_discrete.diode(chips)!DIODE_SM-SDMK0340L,IC,H71799-0A!CR1F4!//jf4cfls225.pdx.intel.com/apd_proj/ppg_lib/epg_masterlib/logical/mstr_discrete/diode/chips/chips.prt!DIODE!DIODE_SM-SDMK0340L,IC,H71799-001!DIODE_SM!!!F2210!!IO_SLOT!!
S!@baseboard_fab2_lib.baseboard_fab2(sch_1):page181_i180@mstr_discrete.diode(chips)!DIODE_SM-SDMK0340L,IC,H71799-0A!CR1F3!//jf4cfls225.pdx.intel.com/apd_proj/ppg_lib/epg_masterlib/logical/mstr_discrete/diode/chips/chips.prt!DIODE!DIODE_SM-SDMK0340L,IC,H71799-001!DIODE_SM!!!F2211!!IO_SLOT!!
S!@baseboard_fab2_lib.baseboard_fab2(sch_1):page201_i102@mstr_discrete.res(chips)!RES_0402-2.0K,1%,1/16W,EMPTY,GA!R6P32!//jf4cfls225.pdx.intel.com/apd_proj/ppg_lib/epg_masterlib/logical/mstr_discrete/res/chips/chips.prt!RES!RES_0402-2.0K,1%,1/16W,EMPTY,G21796-001!RES!!!F1036!!PVCCIN_CPU0_VR!!
S!@baseboard_fab2_lib.baseboard_fab2(sch_1):page201_i103@mstr_discrete.res(chips)!RES_0402-2.0K,1%,1/16W,EMPTY,GA!R6P37!//jf4cfls225.pdx.intel.com/apd_proj/ppg_lib/epg_masterlib/logical/mstr_discrete/res/chips/chips.prt!RES!RES_0402-2.0K,1%,1/16W,EMPTY,G21796-001!RES!!!F1035!!PVCCIN_CPU0_VR!!
S!@baseboard_fab2_lib.baseboard_fab2(sch_1):page199_i85@mstr_discrete.res(chips)!RES_0402-69.8K,1%,1/16W,CHIP,GA!R1D16!//jf4cfls225.pdx.intel.com/apd_proj/ppg_lib/epg_masterlib/logical/mstr_discrete/res/chips/chips.prt!RES!RES_0402-69.8K,1%,1/16W,CHIP,G21796-007!RES!!!F315!!HOT_SWAP!!
S!@baseboard_fab2_lib.baseboard_fab2(sch_1):page199_i9@mstr_discrete.res(chips)!RES_0402-7.5K,1%,1/16W,CHIP,G2A!R1D43!//jf4cfls225.pdx.intel.com/apd_proj/ppg_lib/epg_masterlib/logical/mstr_discrete/res/chips/chips.prt!RES!RES_0402-7.5K,1%,1/16W,CHIP,G21796-177!RES!!!F314!!HOT_SWAP!!
S!@baseboard_fab2_lib.baseboard_fab2(sch_1):page200_i173@mstr_discrete.res(chips)!RES_0402-105.0K,1%,1/16W,CHIP,A!R1D14!//jf4cfls225.pdx.intel.com/apd_proj/ppg_lib/epg_masterlib/logical/mstr_discrete/res/chips/chips.prt!RES!RES_0402-105.0K,1%,1/16W,CHIP,G21796-099!RES!!!F1111!!!!
S!@baseboard_fab2_lib.baseboard_fab2(sch_1):page155_i191@mstr_discrete.res(chips)!RES_0402-20.0K,1%,1/16W,EMPTY,A!R9A6!//jf4cfls225.pdx.intel.com/apd_proj/ppg_lib/epg_masterlib/logical/mstr_discrete/res/chips/chips.prt!RES!RES_0402-20.0K,1%,1/16W,EMPTY,G21796-040!RES!!!F901!!BMC!!
S!@baseboard_fab2_lib.baseboard_fab2(sch_1):page177_i33@mstr_discrete.res(chips)!RES_0402-301.0,1%,1/16W,CHIP,GA!R1L37!//jf4cfls225.pdx.intel.com/apd_proj/ppg_lib/epg_masterlib/logical/mstr_discrete/res/chips/chips.prt!RES!RES_0402-301.0,1%,1/16W,CHIP,G21796-076!RES!!!F759!!MIO_CHASSIS!!
S!@baseboard_fab2_lib.baseboard_fab2(sch_1):page200_i155@mstr_discrete.cap(chips)!CAP_1206-0.068UF,50V,20%,X7R,1A!C1E2!//jf4cfls225.pdx.intel.com/apd_proj/ppg_lib/epg_masterlib/logical/mstr_discrete/cap/chips/chips.prt!CAP!CAP_1206-0.068UF,50V,20%,X7R,108427-047!CAP!!!F2286!!!!
S!@baseboard_fab2_lib.baseboard_fab2(sch_1):page189_i47@mstr_conn.conn8_c77962004(chips)!CONN8_C77962004_PIP-CONN,C7796A!J7G2!//jf4cfls225.pdx.intel.com/apd_proj/ppg_lib/epg_masterlib/logical/mstr_conn/conn8_c77962004/chips/chips.prt!CONN8_C77962004!CONN8_C77962004_PIP-CONN,C77962-004!CONN8_C77962004!!!F2235!!BMC_DEBUG_HEADER!!
S!@baseboard_fab2_lib.baseboard_fab2(sch_1):page234_i210@mstr_discrete.capp(chips)!CAPP_7343-220UF,4V,20%,POSCAP,A!C6L8!//jf4cfls225.pdx.intel.com/apd_proj/ppg_lib/epg_masterlib/logical/mstr_discrete/capp/chips/chips.prt!CAPP!CAPP_7343-220UF,4V,20%,POSCAP,724613-067!CAPP!!!F4104!!!!
S!@baseboard_fab2_lib.baseboard_fab2(sch_1):page231_i217@mstr_discrete.capp(chips)!CAPP_7343-220UF,4V,20%,POSCAP,A!C4T3!//jf4cfls225.pdx.intel.com/apd_proj/ppg_lib/epg_masterlib/logical/mstr_discrete/capp/chips/chips.prt!CAPP!CAPP_7343-220UF,4V,20%,POSCAP,724613-067!CAPP!!!F4105!!!!
S!@baseboard_fab2_lib.baseboard_fab2(sch_1):page232_i267@mstr_discrete.capp(chips)!CAPP_7343-220UF,4V,20%,POSCAP,A!C4M1!//jf4cfls225.pdx.intel.com/apd_proj/ppg_lib/epg_masterlib/logical/mstr_discrete/capp/chips/chips.prt!CAPP!CAPP_7343-220UF,4V,20%,POSCAP,724613-067!CAPP!!!F4106!!!!
S!@baseboard_fab2_lib.baseboard_fab2(sch_1):page233_i256@mstr_discrete.capp(chips)!CAPP_7343-220UF,4V,20%,POSCAP,A!C4F11!//jf4cfls225.pdx.intel.com/apd_proj/ppg_lib/epg_masterlib/logical/mstr_discrete/capp/chips/chips.prt!CAPP!CAPP_7343-220UF,4V,20%,POSCAP,724613-067!CAPP!!!F4107!!!!
S!@baseboard_fab2_lib.baseboard_fab2(sch_1):page193_i140@mstr_discrete.cap(chips)!CAP_0603-47UF,4V,20%,X5R,60243A!C3F1!//jf4cfls225.pdx.intel.com/apd_proj/ppg_lib/epg_masterlib/logical/mstr_discrete/cap/chips/chips.prt!CAP!CAP_0603-47UF,4V,20%,X5R,602433-106!CAP!!!F2730!!!!
S!@baseboard_fab2_lib.baseboard_fab2(sch_1):page193_i141@mstr_discrete.cap(chips)!CAP_0603-47UF,4V,20%,X5R,60243A!C4F2!//jf4cfls225.pdx.intel.com/apd_proj/ppg_lib/epg_masterlib/logical/mstr_discrete/cap/chips/chips.prt!CAP!CAP_0603-47UF,4V,20%,X5R,602433-106!CAP!!!F2727!!!!
S!@baseboard_fab2_lib.baseboard_fab2(sch_1):page194_i150@mstr_discrete.cap(chips)!CAP_0603-47UF,4V,20%,X5R,60243A!C3T2!//jf4cfls225.pdx.intel.com/apd_proj/ppg_lib/epg_masterlib/logical/mstr_discrete/cap/chips/chips.prt!CAP!CAP_0603-47UF,4V,20%,X5R,602433-106!CAP!!!F2728!!!!
S!@baseboard_fab2_lib.baseboard_fab2(sch_1):page194_i149@mstr_discrete.cap(chips)!CAP_0603-47UF,4V,20%,X5R,60243A!C3T1!//jf4cfls225.pdx.intel.com/apd_proj/ppg_lib/epg_masterlib/logical/mstr_discrete/cap/chips/chips.prt!CAP!CAP_0603-47UF,4V,20%,X5R,602433-106!CAP!!!F2729!!!!
S!@baseboard_fab2_lib.baseboard_fab2(sch_1):page217_i212@mstr_discrete.cap(chips)!CAP_0603-47UF,4V,20%,X5R,60243A!C5T1!//jf4cfls225.pdx.intel.com/apd_proj/ppg_lib/epg_masterlib/logical/mstr_discrete/cap/chips/chips.prt!CAP!CAP_0603-47UF,4V,20%,X5R,602433-106!CAP!!!F2710!!!!
S!@baseboard_fab2_lib.baseboard_fab2(sch_1):page217_i211@mstr_discrete.cap(chips)!CAP_0603-47UF,4V,20%,X5R,60243A!C5T4!//jf4cfls225.pdx.intel.com/apd_proj/ppg_lib/epg_masterlib/logical/mstr_discrete/cap/chips/chips.prt!CAP!CAP_0603-47UF,4V,20%,X5R,602433-106!CAP!!!F2707!!!!
S!@baseboard_fab2_lib.baseboard_fab2(sch_1):page217_i210@mstr_discrete.cap(chips)!CAP_0603-47UF,4V,20%,X5R,60243A!C5T13!//jf4cfls225.pdx.intel.com/apd_proj/ppg_lib/epg_masterlib/logical/mstr_discrete/cap/chips/chips.prt!CAP!CAP_0603-47UF,4V,20%,X5R,602433-106!CAP!!!F2706!!!!
S!@baseboard_fab2_lib.baseboard_fab2(sch_1):page217_i209@mstr_discrete.cap(chips)!CAP_0603-47UF,4V,20%,X5R,60243A!C5U11!//jf4cfls225.pdx.intel.com/apd_proj/ppg_lib/epg_masterlib/logical/mstr_discrete/cap/chips/chips.prt!CAP!CAP_0603-47UF,4V,20%,X5R,602433-106!CAP!!!F2705!!!!
S!@baseboard_fab2_lib.baseboard_fab2(sch_1):page217_i208@mstr_discrete.cap(chips)!CAP_0603-47UF,4V,20%,X5R,60243A!C5T2!//jf4cfls225.pdx.intel.com/apd_proj/ppg_lib/epg_masterlib/logical/mstr_discrete/cap/chips/chips.prt!CAP!CAP_0603-47UF,4V,20%,X5R,602433-106!CAP!!!F2709!!!!
S!@baseboard_fab2_lib.baseboard_fab2(sch_1):page225_i200@mstr_discrete.cap(chips)!CAP_0603-47UF,4V,20%,X5R,60243A!C2G15!//jf4cfls225.pdx.intel.com/apd_proj/ppg_lib/epg_masterlib/logical/mstr_discrete/cap/chips/chips.prt!CAP!CAP_0603-47UF,4V,20%,X5R,602433-106!CAP!!!F2731!!!!
S!@baseboard_fab2_lib.baseboard_fab2(sch_1):page225_i201@mstr_discrete.cap(chips)!CAP_0603-47UF,4V,20%,X5R,60243A!C2F1!//jf4cfls225.pdx.intel.com/apd_proj/ppg_lib/epg_masterlib/logical/mstr_discrete/cap/chips/chips.prt!CAP!CAP_0603-47UF,4V,20%,X5R,602433-106!CAP!!!F2734!!!!
S!@baseboard_fab2_lib.baseboard_fab2(sch_1):page225_i202@mstr_discrete.cap(chips)!CAP_0603-47UF,4V,20%,X5R,60243A!C8T1!//jf4cfls225.pdx.intel.com/apd_proj/ppg_lib/epg_masterlib/logical/mstr_discrete/cap/chips/chips.prt!CAP!CAP_0603-47UF,4V,20%,X5R,602433-106!CAP!!!F2693!!!!
S!@baseboard_fab2_lib.baseboard_fab2(sch_1):page225_i203@mstr_discrete.cap(chips)!CAP_0603-47UF,4V,20%,X5R,60243A!C8U9!//jf4cfls225.pdx.intel.com/apd_proj/ppg_lib/epg_masterlib/logical/mstr_discrete/cap/chips/chips.prt!CAP!CAP_0603-47UF,4V,20%,X5R,602433-106!CAP!!!F2688!!!!
S!@baseboard_fab2_lib.baseboard_fab2(sch_1):page225_i204@mstr_discrete.cap(chips)!CAP_0603-47UF,4V,20%,X5R,60243A!C8T11!//jf4cfls225.pdx.intel.com/apd_proj/ppg_lib/epg_masterlib/logical/mstr_discrete/cap/chips/chips.prt!CAP!CAP_0603-47UF,4V,20%,X5R,602433-106!CAP!!!F2689!!!!
S!@baseboard_fab2_lib.baseboard_fab2(sch_1):page228_i202@mstr_discrete.cap(chips)!CAP_0603-47UF,4V,20%,X5R,60243A!C7M5!//jf4cfls225.pdx.intel.com/apd_proj/ppg_lib/epg_masterlib/logical/mstr_discrete/cap/chips/chips.prt!CAP!CAP_0603-47UF,4V,20%,X5R,602433-106!CAP!!!F2702!!!!
S!@baseboard_fab2_lib.baseboard_fab2(sch_1):page228_i203@mstr_discrete.cap(chips)!CAP_0603-47UF,4V,20%,X5R,60243A!C8M10!//jf4cfls225.pdx.intel.com/apd_proj/ppg_lib/epg_masterlib/logical/mstr_discrete/cap/chips/chips.prt!CAP!CAP_0603-47UF,4V,20%,X5R,602433-106!CAP!!!F2695!!!!
S!@baseboard_fab2_lib.baseboard_fab2(sch_1):page228_i204@mstr_discrete.cap(chips)!CAP_0603-47UF,4V,20%,X5R,60243A!C2B2!//jf4cfls225.pdx.intel.com/apd_proj/ppg_lib/epg_masterlib/logical/mstr_discrete/cap/chips/chips.prt!CAP!CAP_0603-47UF,4V,20%,X5R,602433-106!CAP!!!F2735!!!!
S!@baseboard_fab2_lib.baseboard_fab2(sch_1):page228_i205@mstr_discrete.cap(chips)!CAP_0603-47UF,4V,20%,X5R,60243A!C8M9!//jf4cfls225.pdx.intel.com/apd_proj/ppg_lib/epg_masterlib/logical/mstr_discrete/cap/chips/chips.prt!CAP!CAP_0603-47UF,4V,20%,X5R,602433-106!CAP!!!F2696!!!!
S!@baseboard_fab2_lib.baseboard_fab2(sch_1):page228_i206@mstr_discrete.cap(chips)!CAP_0603-47UF,4V,20%,X5R,60243A!C8M2!//jf4cfls225.pdx.intel.com/apd_proj/ppg_lib/epg_masterlib/logical/mstr_discrete/cap/chips/chips.prt!CAP!CAP_0603-47UF,4V,20%,X5R,602433-106!CAP!!!F2698!!!!
S!@baseboard_fab2_lib.baseboard_fab2(sch_1):page220_i199@mstr_discrete.cap(chips)!CAP_0603-47UF,4V,20%,X5R,60243A!C5M3!//jf4cfls225.pdx.intel.com/apd_proj/ppg_lib/epg_masterlib/logical/mstr_discrete/cap/chips/chips.prt!CAP!CAP_0603-47UF,4V,20%,X5R,602433-106!CAP!!!F2715!!!!
S!@baseboard_fab2_lib.baseboard_fab2(sch_1):page220_i200@mstr_discrete.cap(chips)!CAP_0603-47UF,4V,20%,X5R,60243A!C5M11!//jf4cfls225.pdx.intel.com/apd_proj/ppg_lib/epg_masterlib/logical/mstr_discrete/cap/chips/chips.prt!CAP!CAP_0603-47UF,4V,20%,X5R,602433-106!CAP!!!F2712!!!!
S!@baseboard_fab2_lib.baseboard_fab2(sch_1):page221_i52@mstr_discrete.cap(chips)!CAP_0603-47UF,4V,20%,X5R,60243A!C5U16!//jf4cfls225.pdx.intel.com/apd_proj/ppg_lib/epg_masterlib/logical/mstr_discrete/cap/chips/chips.prt!CAP!CAP_0603-47UF,4V,20%,X5R,602433-106!CAP!!!F2703!!!!
S!@baseboard_fab2_lib.baseboard_fab2(sch_1):page221_i50@mstr_discrete.cap(chips)!CAP_0603-47UF,4V,20%,X5R,60243A!C5U12!//jf4cfls225.pdx.intel.com/apd_proj/ppg_lib/epg_masterlib/logical/mstr_discrete/cap/chips/chips.prt!CAP!CAP_0603-47UF,4V,20%,X5R,602433-106!CAP!!!F2704!!!!
S!@baseboard_fab2_lib.baseboard_fab2(sch_1):page221_i51@mstr_discrete.cap(chips)!CAP_0603-47UF,4V,20%,X5R,60243A!C5T3!//jf4cfls225.pdx.intel.com/apd_proj/ppg_lib/epg_masterlib/logical/mstr_discrete/cap/chips/chips.prt!CAP!CAP_0603-47UF,4V,20%,X5R,602433-106!CAP!!!F2708!!!!
S!@baseboard_fab2_lib.baseboard_fab2(sch_1):page222_i47@mstr_discrete.cap(chips)!CAP_0603-47UF,4V,20%,X5R,60243A!C5L4!//jf4cfls225.pdx.intel.com/apd_proj/ppg_lib/epg_masterlib/logical/mstr_discrete/cap/chips/chips.prt!CAP!CAP_0603-47UF,4V,20%,X5R,602433-106!CAP!!!F2718!!!!
S!@baseboard_fab2_lib.baseboard_fab2(sch_1):page222_i48@mstr_discrete.cap(chips)!CAP_0603-47UF,4V,20%,X5R,60243A!C5M13!//jf4cfls225.pdx.intel.com/apd_proj/ppg_lib/epg_masterlib/logical/mstr_discrete/cap/chips/chips.prt!CAP!CAP_0603-47UF,4V,20%,X5R,602433-106!CAP!!!F2711!!!!
S!@baseboard_fab2_lib.baseboard_fab2(sch_1):page222_i49@mstr_discrete.cap(chips)!CAP_0603-47UF,4V,20%,X5R,60243A!C5L5!//jf4cfls225.pdx.intel.com/apd_proj/ppg_lib/epg_masterlib/logical/mstr_discrete/cap/chips/chips.prt!CAP!CAP_0603-47UF,4V,20%,X5R,602433-106!CAP!!!F2717!!!!
S!@baseboard_fab2_lib.baseboard_fab2(sch_1):page229_i47@mstr_discrete.cap(chips)!CAP_0603-47UF,4V,20%,X5R,60243A!C2F2!//jf4cfls225.pdx.intel.com/apd_proj/ppg_lib/epg_masterlib/logical/mstr_discrete/cap/chips/chips.prt!CAP!CAP_0603-47UF,4V,20%,X5R,602433-106!CAP!!!F2733!!!!
S!@baseboard_fab2_lib.baseboard_fab2(sch_1):page229_i48@mstr_discrete.cap(chips)!CAP_0603-47UF,4V,20%,X5R,60243A!C8T3!//jf4cfls225.pdx.intel.com/apd_proj/ppg_lib/epg_masterlib/logical/mstr_discrete/cap/chips/chips.prt!CAP!CAP_0603-47UF,4V,20%,X5R,602433-106!CAP!!!F2691!!!!
S!@baseboard_fab2_lib.baseboard_fab2(sch_1):page229_i49@mstr_discrete.cap(chips)!CAP_0603-47UF,4V,20%,X5R,60243A!C8U10!//jf4cfls225.pdx.intel.com/apd_proj/ppg_lib/epg_masterlib/logical/mstr_discrete/cap/chips/chips.prt!CAP!CAP_0603-47UF,4V,20%,X5R,602433-106!CAP!!!F2687!!!!
S!@baseboard_fab2_lib.baseboard_fab2(sch_1):page230_i47@mstr_discrete.cap(chips)!CAP_0603-47UF,4V,20%,X5R,60243A!C8M12!//jf4cfls225.pdx.intel.com/apd_proj/ppg_lib/epg_masterlib/logical/mstr_discrete/cap/chips/chips.prt!CAP!CAP_0603-47UF,4V,20%,X5R,602433-106!CAP!!!F2694!!!!
S!@baseboard_fab2_lib.baseboard_fab2(sch_1):page230_i48@mstr_discrete.cap(chips)!CAP_0603-47UF,4V,20%,X5R,60243A!C8L3!//jf4cfls225.pdx.intel.com/apd_proj/ppg_lib/epg_masterlib/logical/mstr_discrete/cap/chips/chips.prt!CAP!CAP_0603-47UF,4V,20%,X5R,602433-106!CAP!!!F2701!!!!
S!@baseboard_fab2_lib.baseboard_fab2(sch_1):page230_i49@mstr_discrete.cap(chips)!CAP_0603-47UF,4V,20%,X5R,60243A!C8L4!//jf4cfls225.pdx.intel.com/apd_proj/ppg_lib/epg_masterlib/logical/mstr_discrete/cap/chips/chips.prt!CAP!CAP_0603-47UF,4V,20%,X5R,602433-106!CAP!!!F2700!!!!
S!@baseboard_fab2_lib.baseboard_fab2(sch_1):page220_i196@mstr_discrete.cap(chips)!CAP_0603-47UF,4V,20%,X5R,60243A!C4M5!//jf4cfls225.pdx.intel.com/apd_proj/ppg_lib/epg_masterlib/logical/mstr_discrete/cap/chips/chips.prt!CAP!CAP_0603-47UF,4V,20%,X5R,602433-106!CAP!!!F2726!!!!
S!@baseboard_fab2_lib.baseboard_fab2(sch_1):page220_i195@mstr_discrete.cap(chips)!CAP_0603-47UF,4V,20%,X5R,60243A!C5M9!//jf4cfls225.pdx.intel.com/apd_proj/ppg_lib/epg_masterlib/logical/mstr_discrete/cap/chips/chips.prt!CAP!CAP_0603-47UF,4V,20%,X5R,602433-106!CAP!!!F2714!!!!
S!@baseboard_fab2_lib.baseboard_fab2(sch_1):page220_i198@mstr_discrete.cap(chips)!CAP_0603-47UF,4V,20%,X5R,60243A!C5M10!//jf4cfls225.pdx.intel.com/apd_proj/ppg_lib/epg_masterlib/logical/mstr_discrete/cap/chips/chips.prt!CAP!CAP_0603-47UF,4V,20%,X5R,602433-106!CAP!!!F2713!!!!
S!@baseboard_fab2_lib.baseboard_fab2(sch_1):page217_i205@mstr_discrete.cap(chips)!CAP_0603-47UF,4V,20%,X5R,60243A!C5F2!//jf4cfls225.pdx.intel.com/apd_proj/ppg_lib/epg_masterlib/logical/mstr_discrete/cap/chips/chips.prt!CAP!CAP_0603-47UF,4V,20%,X5R,602433-106!CAP!!!F2721!!!!
S!@baseboard_fab2_lib.baseboard_fab2(sch_1):page217_i206@mstr_discrete.cap(chips)!CAP_0603-47UF,4V,20%,X5R,60243A!C5F1!//jf4cfls225.pdx.intel.com/apd_proj/ppg_lib/epg_masterlib/logical/mstr_discrete/cap/chips/chips.prt!CAP!CAP_0603-47UF,4V,20%,X5R,602433-106!CAP!!!F2722!!!!
S!@baseboard_fab2_lib.baseboard_fab2(sch_1):page217_i207@mstr_discrete.cap(chips)!CAP_0603-47UF,4V,20%,X5R,60243A!C5G10!//jf4cfls225.pdx.intel.com/apd_proj/ppg_lib/epg_masterlib/logical/mstr_discrete/cap/chips/chips.prt!CAP!CAP_0603-47UF,4V,20%,X5R,602433-106!CAP!!!F2720!!!!
S!@baseboard_fab2_lib.baseboard_fab2(sch_1):page220_i192@mstr_discrete.cap(chips)!CAP_0603-47UF,4V,20%,X5R,60243A!C5L15!//jf4cfls225.pdx.intel.com/apd_proj/ppg_lib/epg_masterlib/logical/mstr_discrete/cap/chips/chips.prt!CAP!CAP_0603-47UF,4V,20%,X5R,602433-106!CAP!!!F2716!!!!
S!@baseboard_fab2_lib.baseboard_fab2(sch_1):page220_i197@mstr_discrete.cap(chips)!CAP_0603-47UF,4V,20%,X5R,60243A!C5B2!//jf4cfls225.pdx.intel.com/apd_proj/ppg_lib/epg_masterlib/logical/mstr_discrete/cap/chips/chips.prt!CAP!CAP_0603-47UF,4V,20%,X5R,602433-106!CAP!!!F2723!!!!
S!@baseboard_fab2_lib.baseboard_fab2(sch_1):page220_i193@mstr_discrete.cap(chips)!CAP_0603-47UF,4V,20%,X5R,60243A!C5A5!//jf4cfls225.pdx.intel.com/apd_proj/ppg_lib/epg_masterlib/logical/mstr_discrete/cap/chips/chips.prt!CAP!CAP_0603-47UF,4V,20%,X5R,602433-106!CAP!!!F2725!!!!
S!@baseboard_fab2_lib.baseboard_fab2(sch_1):page220_i194@mstr_discrete.cap(chips)!CAP_0603-47UF,4V,20%,X5R,60243A!C5B1!//jf4cfls225.pdx.intel.com/apd_proj/ppg_lib/epg_masterlib/logical/mstr_discrete/cap/chips/chips.prt!CAP!CAP_0603-47UF,4V,20%,X5R,602433-106!CAP!!!F2724!!!!
S!@baseboard_fab2_lib.baseboard_fab2(sch_1):page225_i199@mstr_discrete.cap(chips)!CAP_0603-47UF,4V,20%,X5R,60243A!C8U13!//jf4cfls225.pdx.intel.com/apd_proj/ppg_lib/epg_masterlib/logical/mstr_discrete/cap/chips/chips.prt!CAP!CAP_0603-47UF,4V,20%,X5R,602433-106!CAP!!!F2686!!!!
S!@baseboard_fab2_lib.baseboard_fab2(sch_1):page225_i196@mstr_discrete.cap(chips)!CAP_0603-47UF,4V,20%,X5R,60243A!C8T4!//jf4cfls225.pdx.intel.com/apd_proj/ppg_lib/epg_masterlib/logical/mstr_discrete/cap/chips/chips.prt!CAP!CAP_0603-47UF,4V,20%,X5R,602433-106!CAP!!!F2690!!!!
S!@baseboard_fab2_lib.baseboard_fab2(sch_1):page225_i197@mstr_discrete.cap(chips)!CAP_0603-47UF,4V,20%,X5R,60243A!C2G8!//jf4cfls225.pdx.intel.com/apd_proj/ppg_lib/epg_masterlib/logical/mstr_discrete/cap/chips/chips.prt!CAP!CAP_0603-47UF,4V,20%,X5R,602433-106!CAP!!!F2732!!!!
S!@baseboard_fab2_lib.baseboard_fab2(sch_1):page225_i198@mstr_discrete.cap(chips)!CAP_0603-47UF,4V,20%,X5R,60243A!C8T2!//jf4cfls225.pdx.intel.com/apd_proj/ppg_lib/epg_masterlib/logical/mstr_discrete/cap/chips/chips.prt!CAP!CAP_0603-47UF,4V,20%,X5R,602433-106!CAP!!!F2692!!!!
S!@baseboard_fab2_lib.baseboard_fab2(sch_1):page228_i201@mstr_discrete.cap(chips)!CAP_0603-47UF,4V,20%,X5R,60243A!C8L12!//jf4cfls225.pdx.intel.com/apd_proj/ppg_lib/epg_masterlib/logical/mstr_discrete/cap/chips/chips.prt!CAP!CAP_0603-47UF,4V,20%,X5R,602433-106!CAP!!!F2699!!!!
S!@baseboard_fab2_lib.baseboard_fab2(sch_1):page228_i198@mstr_discrete.cap(chips)!CAP_0603-47UF,4V,20%,X5R,60243A!C8M8!//jf4cfls225.pdx.intel.com/apd_proj/ppg_lib/epg_masterlib/logical/mstr_discrete/cap/chips/chips.prt!CAP!CAP_0603-47UF,4V,20%,X5R,602433-106!CAP!!!F2697!!!!
S!@baseboard_fab2_lib.baseboard_fab2(sch_1):page228_i199@mstr_discrete.cap(chips)!CAP_0603-47UF,4V,20%,X5R,60243A!C2A5!//jf4cfls225.pdx.intel.com/apd_proj/ppg_lib/epg_masterlib/logical/mstr_discrete/cap/chips/chips.prt!CAP!CAP_0603-47UF,4V,20%,X5R,602433-106!CAP!!!F2737!!!!
S!@baseboard_fab2_lib.baseboard_fab2(sch_1):page228_i200@mstr_discrete.cap(chips)!CAP_0603-47UF,4V,20%,X5R,60243A!C2B1!//jf4cfls225.pdx.intel.com/apd_proj/ppg_lib/epg_masterlib/logical/mstr_discrete/cap/chips/chips.prt!CAP!CAP_0603-47UF,4V,20%,X5R,602433-106!CAP!!!F2736!!!!
S!@baseboard_fab2_lib.baseboard_fab2(sch_1):page217_i213@mstr_discrete.cap(chips)!CAP_0603-47UF,4V,20%,X5R,60243A!C5G19!//jf4cfls225.pdx.intel.com/apd_proj/ppg_lib/epg_masterlib/logical/mstr_discrete/cap/chips/chips.prt!CAP!CAP_0603-47UF,4V,20%,X5R,602433-106!CAP!!!F2719!!!!
S!@baseboard_fab2_lib.baseboard_fab2(sch_1):page195_i82@mstr_discrete.capp(chips)!CAPP_4040LF-470UF,16V,20%,ALUMA!C4F6!//jf4cfls225.pdx.intel.com/apd_proj/ppg_lib/epg_masterlib/logical/mstr_discrete/capp/chips/chips.prt!CAPP!CAPP_4040LF-470UF,16V,20%,ALUM,A93539-036!CAPP!!!F4108!!!!
S!@baseboard_fab2_lib.baseboard_fab2(sch_1):page195_i83@mstr_discrete.capp(chips)!CAPP_4040LF-470UF,16V,20%,ALUMA!C4B13!//jf4cfls225.pdx.intel.com/apd_proj/ppg_lib/epg_masterlib/logical/mstr_discrete/capp/chips/chips.prt!CAPP!CAPP_4040LF-470UF,16V,20%,ALUM,A93539-036!CAPP!!!F4109!!!!
S!@baseboard_fab2_lib.baseboard_fab2(sch_1):page195_i84@mstr_discrete.capp(chips)!CAPP_4040LF-470UF,16V,20%,ALUMA!C1B14!//jf4cfls225.pdx.intel.com/apd_proj/ppg_lib/epg_masterlib/logical/mstr_discrete/capp/chips/chips.prt!CAPP!CAPP_4040LF-470UF,16V,20%,ALUM,A93539-036!CAPP!!!F4111!!!!
S!@baseboard_fab2_lib.baseboard_fab2(sch_1):page195_i85@mstr_discrete.capp(chips)!CAPP_4040LF-470UF,16V,20%,ALUMA!C1F7!//jf4cfls225.pdx.intel.com/apd_proj/ppg_lib/epg_masterlib/logical/mstr_discrete/capp/chips/chips.prt!CAPP!CAPP_4040LF-470UF,16V,20%,ALUM,A93539-036!CAPP!!!F4110!!!!
S!@baseboard_fab2_lib.baseboard_fab2(sch_1):page172_i38@mstr_discrete.fuse(chips)!FUSE_SM-IC,C94311-016!F9B1!//jf4cfls225.pdx.intel.com/apd_proj/ppg_lib/epg_masterlib/logical/mstr_discrete/fuse/chips/chips.prt!FUSE!FUSE_SM-IC,C94311-016!FUSE_SM!1!!F2128!!ST_SATA!!
S!@baseboard_fab2_lib.baseboard_fab2(sch_1):page172_i41@mstr_discrete.fuse(chips)!FUSE_SMLF-IC,C94311-006!F8B1!//jf4cfls225.pdx.intel.com/apd_proj/ppg_lib/epg_masterlib/logical/mstr_discrete/fuse/chips/chips.prt!FUSE!FUSE_SMLF-IC,C94311-006!FUSE!1!!F2127!!ST_SATA!!
S!@baseboard_fab2_lib.baseboard_fab2(sch_1):page145_i133@mstr_discrete.res(chips)!RES_0402-348,1%,1/16W,EMPTY,G2A!R9F20!//jf4cfls225.pdx.intel.com/apd_proj/ppg_lib/epg_masterlib/logical/mstr_discrete/res/chips/chips.prt!RES!RES_0402-348,1%,1/16W,EMPTY,G21796-340!RES!!!F659!!BMC!!
S!@baseboard_fab2_lib.baseboard_fab2(sch_1):page155_i171@mstr_conn.conn14_h54902001(chips)!CONN14_H54902001_PIP-CONN,H549A!J9A2!//jf4cfls225.pdx.intel.com/apd_proj/ppg_lib/epg_masterlib/logical/mstr_conn/conn14_h54902001/chips/chips.prt!CONN14_H54902001!CONN14_H54902001_PIP-CONN,H54902-001!CONN14_H54902001_PIP!!!F2253!!BMC_DEBUG_HEADER!!
S!@baseboard_fab2_lib.baseboard_fab2(sch_1):page195_i26@mstr_conn.conn3_g98259001(chips)!CONN3_G98259001_PIP-CONN,G9825A!RM1E1!//jf4cfls225.pdx.intel.com/apd_proj/ppg_lib/epg_masterlib/logical/mstr_conn/conn3_g98259001/chips/chips.prt!CONN3_G98259001!CONN3_G98259001_PIP-CONN,G98259-001!CONN3_G98259001_PIP!!!F2246!!!!
S!@baseboard_fab2_lib.baseboard_fab2(sch_1):page134_i22@mstr_conn.conn4_d42317002(chips)!CONN4_D42317002_PIP-CONN,D4231A!J9A1!//jf4cfls225.pdx.intel.com/apd_proj/ppg_lib/epg_masterlib/logical/mstr_conn/conn4_d42317002/chips/chips.prt!CONN4_D42317002!CONN4_D42317002_PIP-CONN,D42317-002!CONN4_D42317002_PIP!!!F2245!!SB!!
S!@baseboard_fab2_lib.baseboard_fab2(sch_1):page181_i189@mstr_conn.conn8_h62179001(chips)!CONN8_H62179001_PIP-CONN,H6217A!J1F3!//jf4cfls225.pdx.intel.com/apd_proj/ppg_lib/epg_masterlib/logical/mstr_conn/conn8_h62179001/chips/chips.prt!CONN8_H62179001!CONN8_H62179001_PIP-CONN,H62179-001!CONN8_H62179001_PIP!!!F2234!!IO_SLOT!!
S!@baseboard_fab2_lib.baseboard_fab2(sch_1):page176_i69@mstr_conn.conn9_h51826001(chips)!CONN9_H51826001_PIP2-CONN,H518A!J9B1!//jf4cfls225.pdx.intel.com/apd_proj/ppg_lib/epg_masterlib/logical/mstr_conn/conn9_h51826001/chips/chips.prt!CONN9_H51826001!CONN9_H51826001_PIP2-CONN,H51826-001!CONN9_H51826001_PIP2!!!F2233!!USB_REAR!!
S!@baseboard_fab2_lib.baseboard_fab2(sch_1):page241_i54@mstr_discrete.res(chips)!RES_0402-24.9K,1%,1/16W,CHIP,GA!R8E39!//jf4cfls225.pdx.intel.com/apd_proj/ppg_lib/epg_masterlib/logical/mstr_discrete/res/chips/chips.prt!RES!RES_0402-24.9K,1%,1/16W,CHIP,G21796-254!RES!!!F844!!P5V_STBY_VR!!
S!@baseboard_fab2_lib.baseboard_fab2(sch_1):page158_i134@mstr_discrete.led(chips)!LED_A1LF-GREEN,IC,D14725-022!DS9A7!//jf4cfls225.pdx.intel.com/apd_proj/ppg_lib/epg_masterlib/logical/mstr_discrete/led/chips/chips.prt!LED!LED_A1LF-GREEN,IC,D14725-022!LED_A1LF!!!F2030!!UART_MUX!!
S!@baseboard_fab2_lib.baseboard_fab2(sch_1):page158_i130@mstr_discrete.led(chips)!LED_A1LF-GREEN,IC,D14725-022!DS9A4!//jf4cfls225.pdx.intel.com/apd_proj/ppg_lib/epg_masterlib/logical/mstr_discrete/led/chips/chips.prt!LED!LED_A1LF-GREEN,IC,D14725-022!LED_A1LF!!!F2031!!UART_MUX!!
S!@baseboard_fab2_lib.baseboard_fab2(sch_1):page175_i57@mstr_ttl.ttl1g86(chips)!TTL1G86_SOTLF-74AHCT1G86,IC,D3B!U1L2!//jf4cfls225.pdx.intel.com/apd_proj/ppg_lib/epg_masterlib/logical/mstr_ttl/ttl1g86/chips/chips.prt!TTL1G86!TTL1G86_SOTLF-74AHCT1G86,IC,D39848-001!TTL1G86_SOTLF!!!F21!!MIO_CHASSIS!!
S!@baseboard_fab2_lib.baseboard_fab2(sch_1):page195_i100@mstr_discrete.capp(chips)!CAPP_3018-68UF,16V,20%,TANT,72A!C3B6!//jf4cfls225.pdx.intel.com/apd_proj/ppg_lib/epg_masterlib/logical/mstr_discrete/capp/chips/chips.prt!CAPP!CAPP_3018-68UF,16V,20%,TANT,724613-112!CAPP!!!F4125!!!!
S!@baseboard_fab2_lib.baseboard_fab2(sch_1):page195_i113@mstr_discrete.capp(chips)!CAPP_3018-68UF,16V,20%,TANT,72A!C3T3!//jf4cfls225.pdx.intel.com/apd_proj/ppg_lib/epg_masterlib/logical/mstr_discrete/capp/chips/chips.prt!CAPP!CAPP_3018-68UF,16V,20%,TANT,724613-112!CAPP!!!F4124!!!!
S!@baseboard_fab2_lib.baseboard_fab2(sch_1):page195_i96@mstr_discrete.capp(chips)!CAPP_3018-68UF,16V,20%,TANT,72A!C4F5!//jf4cfls225.pdx.intel.com/apd_proj/ppg_lib/epg_masterlib/logical/mstr_discrete/capp/chips/chips.prt!CAPP!CAPP_3018-68UF,16V,20%,TANT,724613-112!CAPP!!!F4118!!!!
S!@baseboard_fab2_lib.baseboard_fab2(sch_1):page195_i112@mstr_discrete.capp(chips)!CAPP_3018-68UF,16V,20%,TANT,72A!C4F4!//jf4cfls225.pdx.intel.com/apd_proj/ppg_lib/epg_masterlib/logical/mstr_discrete/capp/chips/chips.prt!CAPP!CAPP_3018-68UF,16V,20%,TANT,724613-112!CAPP!!!F4119!!!!
S!@baseboard_fab2_lib.baseboard_fab2(sch_1):page195_i97@mstr_discrete.capp(chips)!CAPP_3018-68UF,16V,20%,TANT,72A!C4B14!//jf4cfls225.pdx.intel.com/apd_proj/ppg_lib/epg_masterlib/logical/mstr_discrete/capp/chips/chips.prt!CAPP!CAPP_3018-68UF,16V,20%,TANT,724613-112!CAPP!!!F4120!!!!
S!@baseboard_fab2_lib.baseboard_fab2(sch_1):page195_i111@mstr_discrete.capp(chips)!CAPP_3018-68UF,16V,20%,TANT,72A!C9T3!//jf4cfls225.pdx.intel.com/apd_proj/ppg_lib/epg_masterlib/logical/mstr_discrete/capp/chips/chips.prt!CAPP!CAPP_3018-68UF,16V,20%,TANT,724613-112!CAPP!!!F4112!!!!
S!@baseboard_fab2_lib.baseboard_fab2(sch_1):page195_i103@mstr_discrete.capp(chips)!CAPP_3018-68UF,16V,20%,TANT,72A!C1M5!//jf4cfls225.pdx.intel.com/apd_proj/ppg_lib/epg_masterlib/logical/mstr_discrete/capp/chips/chips.prt!CAPP!CAPP_3018-68UF,16V,20%,TANT,724613-112!CAPP!!!F4127!!!!
S!@baseboard_fab2_lib.baseboard_fab2(sch_1):page195_i109@mstr_discrete.capp(chips)!CAPP_3018-68UF,16V,20%,TANT,72A!C6N5!//jf4cfls225.pdx.intel.com/apd_proj/ppg_lib/epg_masterlib/logical/mstr_discrete/capp/chips/chips.prt!CAPP!CAPP_3018-68UF,16V,20%,TANT,724613-112!CAPP!!!F4115!!!!
S!@baseboard_fab2_lib.baseboard_fab2(sch_1):page195_i101@mstr_discrete.capp(chips)!CAPP_3018-68UF,16V,20%,TANT,72A!C1R23!//jf4cfls225.pdx.intel.com/apd_proj/ppg_lib/epg_masterlib/logical/mstr_discrete/capp/chips/chips.prt!CAPP!CAPP_3018-68UF,16V,20%,TANT,724613-112!CAPP!!!F4126!!!!
S!@baseboard_fab2_lib.baseboard_fab2(sch_1):page195_i108@mstr_discrete.capp(chips)!CAPP_3018-68UF,16V,20%,TANT,72A!C7M6!//jf4cfls225.pdx.intel.com/apd_proj/ppg_lib/epg_masterlib/logical/mstr_discrete/capp/chips/chips.prt!CAPP!CAPP_3018-68UF,16V,20%,TANT,724613-112!CAPP!!!F4114!!!!
S!@baseboard_fab2_lib.baseboard_fab2(sch_1):page195_i99@mstr_discrete.capp(chips)!CAPP_3018-68UF,16V,20%,TANT,72A!C9M3!//jf4cfls225.pdx.intel.com/apd_proj/ppg_lib/epg_masterlib/logical/mstr_discrete/capp/chips/chips.prt!CAPP!CAPP_3018-68UF,16V,20%,TANT,724613-112!CAPP!!!F4113!!!!
S!@baseboard_fab2_lib.baseboard_fab2(sch_1):page195_i104@mstr_discrete.capp(chips)!CAPP_3018-68UF,16V,20%,TANT,72A!C3T13!//jf4cfls225.pdx.intel.com/apd_proj/ppg_lib/epg_masterlib/logical/mstr_discrete/capp/chips/chips.prt!CAPP!CAPP_3018-68UF,16V,20%,TANT,724613-112!CAPP!!!F4122!!!!
S!@baseboard_fab2_lib.baseboard_fab2(sch_1):page195_i98@mstr_discrete.capp(chips)!CAPP_3018-68UF,16V,20%,TANT,72A!C3T6!//jf4cfls225.pdx.intel.com/apd_proj/ppg_lib/epg_masterlib/logical/mstr_discrete/capp/chips/chips.prt!CAPP!CAPP_3018-68UF,16V,20%,TANT,724613-112!CAPP!!!F4123!!!!
S!@baseboard_fab2_lib.baseboard_fab2(sch_1):page195_i106@mstr_discrete.capp(chips)!CAPP_3018-68UF,16V,20%,TANT,72A!C3T15!//jf4cfls225.pdx.intel.com/apd_proj/ppg_lib/epg_masterlib/logical/mstr_discrete/capp/chips/chips.prt!CAPP!CAPP_3018-68UF,16V,20%,TANT,724613-112!CAPP!!!F4121!!!!
S!@baseboard_fab2_lib.baseboard_fab2(sch_1):page195_i102@mstr_discrete.capp(chips)!CAPP_3018-68UF,16V,20%,TANT,72A!C4M6!//jf4cfls225.pdx.intel.com/apd_proj/ppg_lib/epg_masterlib/logical/mstr_discrete/capp/chips/chips.prt!CAPP!CAPP_3018-68UF,16V,20%,TANT,724613-112!CAPP!!!F4117!!!!
S!@baseboard_fab2_lib.baseboard_fab2(sch_1):page195_i105@mstr_discrete.capp(chips)!CAPP_3018-68UF,16V,20%,TANT,72A!C4M7!//jf4cfls225.pdx.intel.com/apd_proj/ppg_lib/epg_masterlib/logical/mstr_discrete/capp/chips/chips.prt!CAPP!CAPP_3018-68UF,16V,20%,TANT,724613-112!CAPP!!!F4116!!!!
S!@baseboard_fab2_lib.baseboard_fab2(sch_1):page241_i63@mstr_discrete.cap(chips)!CAP_0402LF-0.022UF,16V,10%,X7RA!C8E15!//jf4cfls225.pdx.intel.com/apd_proj/ppg_lib/epg_masterlib/logical/mstr_discrete/cap/chips/chips.prt!CAP!CAP_0402LF-0.022UF,16V,10%,X7R,A36096-073!CAP!!!F3491!!P5V_STBY_VR!!
S!@baseboard_fab2_lib.baseboard_fab2(sch_1):page103_i121@mstr_discrete.res(chips)!RES_0402-42.2,1.0%,1/16W,EMPTYA!R7P9!//jf4cfls225.pdx.intel.com/apd_proj/ppg_lib/epg_masterlib/logical/mstr_discrete/res/chips/chips.prt!RES!RES_0402-42.2,1.0%,1/16W,EMPTY,G21796-259!RES!!!F470!!DB1200Z!!
S!@baseboard_fab2_lib.baseboard_fab2(sch_1):page103_i123@mstr_discrete.res(chips)!RES_0402-42.2,1.0%,1/16W,EMPTYA!R7P12!//jf4cfls225.pdx.intel.com/apd_proj/ppg_lib/epg_masterlib/logical/mstr_discrete/res/chips/chips.prt!RES!RES_0402-42.2,1.0%,1/16W,EMPTY,G21796-259!RES!!!F469!!DB1200Z!!
S!@baseboard_fab2_lib.baseboard_fab2(sch_1):page103_i125@mstr_discrete.res(chips)!RES_0402-42.2,1.0%,1/16W,EMPTYA!R7P6!//jf4cfls225.pdx.intel.com/apd_proj/ppg_lib/epg_masterlib/logical/mstr_discrete/res/chips/chips.prt!RES!RES_0402-42.2,1.0%,1/16W,EMPTY,G21796-259!RES!!!F472!!DB1200Z!!
S!@baseboard_fab2_lib.baseboard_fab2(sch_1):page103_i127@mstr_discrete.res(chips)!RES_0402-42.2,1.0%,1/16W,EMPTYA!R7P7!//jf4cfls225.pdx.intel.com/apd_proj/ppg_lib/epg_masterlib/logical/mstr_discrete/res/chips/chips.prt!RES!RES_0402-42.2,1.0%,1/16W,EMPTY,G21796-259!RES!!!F471!!DB1200Z!!
S!@baseboard_fab2_lib.baseboard_fab2(sch_1):page103_i129@mstr_discrete.res(chips)!RES_0402-42.2,1.0%,1/16W,EMPTYA!R7P3!//jf4cfls225.pdx.intel.com/apd_proj/ppg_lib/epg_masterlib/logical/mstr_discrete/res/chips/chips.prt!RES!RES_0402-42.2,1.0%,1/16W,EMPTY,G21796-259!RES!!!F474!!DB1200Z!!
S!@baseboard_fab2_lib.baseboard_fab2(sch_1):page103_i131@mstr_discrete.res(chips)!RES_0402-42.2,1.0%,1/16W,EMPTYA!R7P4!//jf4cfls225.pdx.intel.com/apd_proj/ppg_lib/epg_masterlib/logical/mstr_discrete/res/chips/chips.prt!RES!RES_0402-42.2,1.0%,1/16W,EMPTY,G21796-259!RES!!!F473!!DB1200Z!!
S!@baseboard_fab2_lib.baseboard_fab2(sch_1):page103_i133@mstr_discrete.res(chips)!RES_0402-42.2,1.0%,1/16W,EMPTYA!R7P1!//jf4cfls225.pdx.intel.com/apd_proj/ppg_lib/epg_masterlib/logical/mstr_discrete/res/chips/chips.prt!RES!RES_0402-42.2,1.0%,1/16W,EMPTY,G21796-259!RES!!!F476!!DB1200Z!!
S!@baseboard_fab2_lib.baseboard_fab2(sch_1):page103_i135@mstr_discrete.res(chips)!RES_0402-42.2,1.0%,1/16W,EMPTYA!R7P2!//jf4cfls225.pdx.intel.com/apd_proj/ppg_lib/epg_masterlib/logical/mstr_discrete/res/chips/chips.prt!RES!RES_0402-42.2,1.0%,1/16W,EMPTY,G21796-259!RES!!!F475!!DB1200Z!!
S!@baseboard_fab2_lib.baseboard_fab2(sch_1):page103_i139@mstr_discrete.res(chips)!RES_0402-42.2,1.0%,1/16W,EMPTYA!R6P8!//jf4cfls225.pdx.intel.com/apd_proj/ppg_lib/epg_masterlib/logical/mstr_discrete/res/chips/chips.prt!RES!RES_0402-42.2,1.0%,1/16W,EMPTY,G21796-259!RES!!!F483!!DB1200Z!!
S!@baseboard_fab2_lib.baseboard_fab2(sch_1):page103_i141@mstr_discrete.res(chips)!RES_0402-42.2,1.0%,1/16W,EMPTYA!R6P5!//jf4cfls225.pdx.intel.com/apd_proj/ppg_lib/epg_masterlib/logical/mstr_discrete/res/chips/chips.prt!RES!RES_0402-42.2,1.0%,1/16W,EMPTY,G21796-259!RES!!!F486!!DB1200Z!!
S!@baseboard_fab2_lib.baseboard_fab2(sch_1):page103_i143@mstr_discrete.res(chips)!RES_0402-42.2,1.0%,1/16W,EMPTYA!R6P6!//jf4cfls225.pdx.intel.com/apd_proj/ppg_lib/epg_masterlib/logical/mstr_discrete/res/chips/chips.prt!RES!RES_0402-42.2,1.0%,1/16W,EMPTY,G21796-259!RES!!!F485!!DB1200Z!!
S!@baseboard_fab2_lib.baseboard_fab2(sch_1):page103_i145@mstr_discrete.res(chips)!RES_0402-42.2,1.0%,1/16W,EMPTYA!R6P3!//jf4cfls225.pdx.intel.com/apd_proj/ppg_lib/epg_masterlib/logical/mstr_discrete/res/chips/chips.prt!RES!RES_0402-42.2,1.0%,1/16W,EMPTY,G21796-259!RES!!!F488!!DB1200Z!!
S!@baseboard_fab2_lib.baseboard_fab2(sch_1):page103_i147@mstr_discrete.res(chips)!RES_0402-42.2,1.0%,1/16W,EMPTYA!R6P4!//jf4cfls225.pdx.intel.com/apd_proj/ppg_lib/epg_masterlib/logical/mstr_discrete/res/chips/chips.prt!RES!RES_0402-42.2,1.0%,1/16W,EMPTY,G21796-259!RES!!!F487!!DB1200Z!!
S!@baseboard_fab2_lib.baseboard_fab2(sch_1):page103_i149@mstr_discrete.res(chips)!RES_0402-42.2,1.0%,1/16W,EMPTYA!R6P1!//jf4cfls225.pdx.intel.com/apd_proj/ppg_lib/epg_masterlib/logical/mstr_discrete/res/chips/chips.prt!RES!RES_0402-42.2,1.0%,1/16W,EMPTY,G21796-259!RES!!!F490!!DB1200Z!!
S!@baseboard_fab2_lib.baseboard_fab2(sch_1):page103_i151@mstr_discrete.res(chips)!RES_0402-42.2,1.0%,1/16W,EMPTYA!R6P2!//jf4cfls225.pdx.intel.com/apd_proj/ppg_lib/epg_masterlib/logical/mstr_discrete/res/chips/chips.prt!RES!RES_0402-42.2,1.0%,1/16W,EMPTY,G21796-259!RES!!!F489!!DB1200Z!!
S!@baseboard_fab2_lib.baseboard_fab2(sch_1):page103_i153@mstr_discrete.res(chips)!RES_0402-42.2,1.0%,1/16W,EMPTYA!R6P11!//jf4cfls225.pdx.intel.com/apd_proj/ppg_lib/epg_masterlib/logical/mstr_discrete/res/chips/chips.prt!RES!RES_0402-42.2,1.0%,1/16W,EMPTY,G21796-259!RES!!!F481!!DB1200Z!!
S!@baseboard_fab2_lib.baseboard_fab2(sch_1):page103_i155@mstr_discrete.res(chips)!RES_0402-42.2,1.0%,1/16W,EMPTYA!R6P9!//jf4cfls225.pdx.intel.com/apd_proj/ppg_lib/epg_masterlib/logical/mstr_discrete/res/chips/chips.prt!RES!RES_0402-42.2,1.0%,1/16W,EMPTY,G21796-259!RES!!!F482!!DB1200Z!!
S!@baseboard_fab2_lib.baseboard_fab2(sch_1):page103_i157@mstr_discrete.res(chips)!RES_0402-42.2,1.0%,1/16W,EMPTYA!R6P13!//jf4cfls225.pdx.intel.com/apd_proj/ppg_lib/epg_masterlib/logical/mstr_discrete/res/chips/chips.prt!RES!RES_0402-42.2,1.0%,1/16W,EMPTY,G21796-259!RES!!!F479!!DB1200Z!!
S!@baseboard_fab2_lib.baseboard_fab2(sch_1):page103_i159@mstr_discrete.res(chips)!RES_0402-42.2,1.0%,1/16W,EMPTYA!R6P12!//jf4cfls225.pdx.intel.com/apd_proj/ppg_lib/epg_masterlib/logical/mstr_discrete/res/chips/chips.prt!RES!RES_0402-42.2,1.0%,1/16W,EMPTY,G21796-259!RES!!!F480!!DB1200Z!!
S!@baseboard_fab2_lib.baseboard_fab2(sch_1):page103_i161@mstr_discrete.res(chips)!RES_0402-42.2,1.0%,1/16W,EMPTYA!R4D24!//jf4cfls225.pdx.intel.com/apd_proj/ppg_lib/epg_masterlib/logical/mstr_discrete/res/chips/chips.prt!RES!RES_0402-42.2,1.0%,1/16W,EMPTY,G21796-259!RES!!!F491!!DB1200Z!!
S!@baseboard_fab2_lib.baseboard_fab2(sch_1):page103_i163@mstr_discrete.res(chips)!RES_0402-42.2,1.0%,1/16W,EMPTYA!R4D18!//jf4cfls225.pdx.intel.com/apd_proj/ppg_lib/epg_masterlib/logical/mstr_discrete/res/chips/chips.prt!RES!RES_0402-42.2,1.0%,1/16W,EMPTY,G21796-259!RES!!!F492!!DB1200Z!!
S!@baseboard_fab2_lib.baseboard_fab2(sch_1):page103_i165@mstr_discrete.res(chips)!RES_0402-42.2,1.0%,1/16W,EMPTYA!R6P17!//jf4cfls225.pdx.intel.com/apd_proj/ppg_lib/epg_masterlib/logical/mstr_discrete/res/chips/chips.prt!RES!RES_0402-42.2,1.0%,1/16W,EMPTY,G21796-259!RES!!!F477!!DB1200Z!!
S!@baseboard_fab2_lib.baseboard_fab2(sch_1):page103_i167@mstr_discrete.res(chips)!RES_0402-42.2,1.0%,1/16W,EMPTYA!R6P15!//jf4cfls225.pdx.intel.com/apd_proj/ppg_lib/epg_masterlib/logical/mstr_discrete/res/chips/chips.prt!RES!RES_0402-42.2,1.0%,1/16W,EMPTY,G21796-259!RES!!!F478!!DB1200Z!!
S!@baseboard_fab2_lib.baseboard_fab2(sch_1):page103_i137@mstr_discrete.res(chips)!RES_0402-42.2,1.0%,1/16W,EMPTYA!R6P7!//jf4cfls225.pdx.intel.com/apd_proj/ppg_lib/epg_masterlib/logical/mstr_discrete/res/chips/chips.prt!RES!RES_0402-42.2,1.0%,1/16W,EMPTY,G21796-259!RES!!!F484!!DB1200Z!!
S!@baseboard_fab2_lib.baseboard_fab2(sch_1):page199_i55@mstr_discrete.res(chips)!RES_0402-12.1K,1%,1/16W,CHIP,GA!R9P24!//jf4cfls225.pdx.intel.com/apd_proj/ppg_lib/epg_masterlib/logical/mstr_discrete/res/chips/chips.prt!RES!RES_0402-12.1K,1%,1/16W,CHIP,G21796-089!RES!!!F1107!!HOT_SWAP!!
S!@baseboard_fab2_lib.baseboard_fab2(sch_1):page199_i19@mstr_discrete.res(chips)!RES_0805-0.0,5%,1/8W,CHIP,G221A!R1D41!//jf4cfls225.pdx.intel.com/apd_proj/ppg_lib/epg_masterlib/logical/mstr_discrete/res/chips/chips.prt!RES!RES_0805-0.0,5%,1/8W,CHIP,G22179-004!RES!!!F255!!HOT_SWAP!!
S!@baseboard_fab2_lib.baseboard_fab2(sch_1):page240_i173@mstr_discrete.inductor(chips)!INDUCTOR_SM-1.00UH,IND,E98679-A!L8F1!//jf4cfls225.pdx.intel.com/apd_proj/ppg_lib/epg_masterlib/logical/mstr_discrete/inductor/chips/chips.prt!INDUCTOR!INDUCTOR_SM-1.00UH,IND,E98679-006!INDUCTOR!!!F2092!!!!
S!@baseboard_fab2_lib.baseboard_fab2(sch_1):page241_i90@mstr_discrete.inductor(chips)!INDUCTOR_SM-2.2UH,IND,E98761-0A!L8E1!//jf4cfls225.pdx.intel.com/apd_proj/ppg_lib/epg_masterlib/logical/mstr_discrete/inductor/chips/chips.prt!INDUCTOR!INDUCTOR_SM-2.2UH,IND,E98761-003!INDUCTOR!!!F2082!!!!
S!@baseboard_fab2_lib.baseboard_fab2(sch_1):page231_i194@mstr_discrete.cap(chips)!CAP_0402-0.027UF,16V,10%,X7R,AA!C7F10!//jf4cfls225.pdx.intel.com/apd_proj/ppg_lib/epg_masterlib/logical/mstr_discrete/cap/chips/chips.prt!CAP!CAP_0402-0.027UF,16V,10%,X7R,A36096-129!CAP_0402!!!F4087!!PVPP_KLM_VR!!
S!@baseboard_fab2_lib.baseboard_fab2(sch_1):page232_i197@mstr_discrete.cap(chips)!CAP_0402-0.027UF,16V,10%,X7R,AA!C7B11!//jf4cfls225.pdx.intel.com/apd_proj/ppg_lib/epg_masterlib/logical/mstr_discrete/cap/chips/chips.prt!CAP!CAP_0402-0.027UF,16V,10%,X7R,A36096-129!CAP_0402!!!F4088!!PVPP_KLM_VR!!
S!@baseboard_fab2_lib.baseboard_fab2(sch_1):page233_i194@mstr_discrete.cap(chips)!CAP_0402-0.027UF,16V,10%,X7R,AA!C4G8!//jf4cfls225.pdx.intel.com/apd_proj/ppg_lib/epg_masterlib/logical/mstr_discrete/cap/chips/chips.prt!CAP!CAP_0402-0.027UF,16V,10%,X7R,A36096-129!CAP_0402!!!F4089!!PVPP_KLM_VR!!
S!@baseboard_fab2_lib.baseboard_fab2(sch_1):page234_i146@mstr_discrete.cap(chips)!CAP_0402-0.027UF,16V,10%,X7R,AA!C4B6!//jf4cfls225.pdx.intel.com/apd_proj/ppg_lib/epg_masterlib/logical/mstr_discrete/cap/chips/chips.prt!CAP!CAP_0402-0.027UF,16V,10%,X7R,A36096-129!CAP_0402!!!F4090!!PVPP_KLM_VR!!
S!@baseboard_fab2_lib.baseboard_fab2(sch_1):page196_i75@mstr_discrete.res(chips)!RES_0402-6.34K,1%,1/16W,CHIP,GA!R3P51!//jf4cfls225.pdx.intel.com/apd_proj/ppg_lib/epg_masterlib/logical/mstr_discrete/res/chips/chips.prt!RES!RES_0402-6.34K,1%,1/16W,CHIP,G21796-146!RES!!!F369!!V_SUPER!!
S!@baseboard_fab2_lib.baseboard_fab2(sch_1):page231_i166@mstr_discrete.res(chips)!RES_0402-6.34K,1%,1/16W,CHIP,GA!R7F11!//jf4cfls225.pdx.intel.com/apd_proj/ppg_lib/epg_masterlib/logical/mstr_discrete/res/chips/chips.prt!RES!RES_0402-6.34K,1%,1/16W,CHIP,G21796-146!RES!!!F365!!PVPP_KLM_VR!!
S!@baseboard_fab2_lib.baseboard_fab2(sch_1):page232_i304@mstr_discrete.res(chips)!RES_0402-6.34K,1%,1/16W,CHIP,GA!R7B13!//jf4cfls225.pdx.intel.com/apd_proj/ppg_lib/epg_masterlib/logical/mstr_discrete/res/chips/chips.prt!RES!RES_0402-6.34K,1%,1/16W,CHIP,G21796-146!RES!!!F366!!PVPP_KLM_VR!!
S!@baseboard_fab2_lib.baseboard_fab2(sch_1):page233_i269@mstr_discrete.res(chips)!RES_0402-6.34K,1%,1/16W,CHIP,GA!R4G9!//jf4cfls225.pdx.intel.com/apd_proj/ppg_lib/epg_masterlib/logical/mstr_discrete/res/chips/chips.prt!RES!RES_0402-6.34K,1%,1/16W,CHIP,G21796-146!RES!!!F367!!PVPP_KLM_VR!!
S!@baseboard_fab2_lib.baseboard_fab2(sch_1):page234_i216@mstr_discrete.res(chips)!RES_0402-6.34K,1%,1/16W,CHIP,GA!R4B4!//jf4cfls225.pdx.intel.com/apd_proj/ppg_lib/epg_masterlib/logical/mstr_discrete/res/chips/chips.prt!RES!RES_0402-6.34K,1%,1/16W,CHIP,G21796-146!RES!!!F368!!PVPP_KLM_VR!!
S!@baseboard_fab2_lib.baseboard_fab2(sch_1):page240_i106@mstr_discrete.res(chips)!RES_0402-64.9K,1%,1/16W,CHIP,GA!R8F9!//jf4cfls225.pdx.intel.com/apd_proj/ppg_lib/epg_masterlib/logical/mstr_discrete/res/chips/chips.prt!RES!RES_0402-64.9K,1%,1/16W,CHIP,G21796-148!RES!!!F358!!P3V3_STBY_VR!!
S!@baseboard_fab2_lib.baseboard_fab2(sch_1):page231_i134@mstr_discrete.res(chips)!RES_0402-7.87K,1.0%,1/16W,CHIPA!R7F15!//jf4cfls225.pdx.intel.com/apd_proj/ppg_lib/epg_masterlib/logical/mstr_discrete/res/chips/chips.prt!RES!RES_0402-7.87K,1.0%,1/16W,CHIP,G21796-242!RES!!!F307!!PVPP_KLM_VR!!
S!@baseboard_fab2_lib.baseboard_fab2(sch_1):page231_i201@mstr_discrete.res(chips)!RES_0402-7.87K,1.0%,1/16W,CHIPA!R7F18!//jf4cfls225.pdx.intel.com/apd_proj/ppg_lib/epg_masterlib/logical/mstr_discrete/res/chips/chips.prt!RES!RES_0402-7.87K,1.0%,1/16W,CHIP,G21796-242!RES!!!F306!!PVPP_KLM_VR!!
S!@baseboard_fab2_lib.baseboard_fab2(sch_1):page232_i300@mstr_discrete.res(chips)!RES_0402-7.87K,1.0%,1/16W,CHIPA!R7B16!//jf4cfls225.pdx.intel.com/apd_proj/ppg_lib/epg_masterlib/logical/mstr_discrete/res/chips/chips.prt!RES!RES_0402-7.87K,1.0%,1/16W,CHIP,G21796-242!RES!!!F308!!PVPP_KLM_VR!!
S!@baseboard_fab2_lib.baseboard_fab2(sch_1):page232_i193@mstr_discrete.res(chips)!RES_0402-7.87K,1.0%,1/16W,CHIPA!R7B14!//jf4cfls225.pdx.intel.com/apd_proj/ppg_lib/epg_masterlib/logical/mstr_discrete/res/chips/chips.prt!RES!RES_0402-7.87K,1.0%,1/16W,CHIP,G21796-242!RES!!!F309!!PVPP_KLM_VR!!
S!@baseboard_fab2_lib.baseboard_fab2(sch_1):page233_i184@mstr_discrete.res(chips)!RES_0402-7.87K,1.0%,1/16W,CHIPA!R4G11!//jf4cfls225.pdx.intel.com/apd_proj/ppg_lib/epg_masterlib/logical/mstr_discrete/res/chips/chips.prt!RES!RES_0402-7.87K,1.0%,1/16W,CHIP,G21796-242!RES!!!F311!!PVPP_KLM_VR!!
S!@baseboard_fab2_lib.baseboard_fab2(sch_1):page234_i140@mstr_discrete.res(chips)!RES_0402-7.87K,1.0%,1/16W,CHIPA!R4B6!//jf4cfls225.pdx.intel.com/apd_proj/ppg_lib/epg_masterlib/logical/mstr_discrete/res/chips/chips.prt!RES!RES_0402-7.87K,1.0%,1/16W,CHIP,G21796-242!RES!!!F313!!PVPP_KLM_VR!!
S!@baseboard_fab2_lib.baseboard_fab2(sch_1):page233_i272@mstr_discrete.res(chips)!RES_0402-7.87K,1.0%,1/16W,CHIPA!R4G13!//jf4cfls225.pdx.intel.com/apd_proj/ppg_lib/epg_masterlib/logical/mstr_discrete/res/chips/chips.prt!RES!RES_0402-7.87K,1.0%,1/16W,CHIP,G21796-242!RES!!!F310!!PVPP_KLM_VR!!
S!@baseboard_fab2_lib.baseboard_fab2(sch_1):page234_i213@mstr_discrete.res(chips)!RES_0402-7.87K,1.0%,1/16W,CHIPA!R4B8!//jf4cfls225.pdx.intel.com/apd_proj/ppg_lib/epg_masterlib/logical/mstr_discrete/res/chips/chips.prt!RES!RES_0402-7.87K,1.0%,1/16W,CHIP,G21796-242!RES!!!F312!!PVPP_KLM_VR!!
S!@baseboard_fab2_lib.baseboard_fab2(sch_1):page200_i145@mstr_discrete.res(chips)!RES_0402-249K,1.0%,1/16W,CHIP,A!R9P7!//jf4cfls225.pdx.intel.com/apd_proj/ppg_lib/epg_masterlib/logical/mstr_discrete/res/chips/chips.prt!RES!RES_0402-249K,1.0%,1/16W,CHIP,G21796-189!RES!!!F806!!HOT_SWAP!!
S!@baseboard_fab2_lib.baseboard_fab2(sch_1):page200_i107@mstr_discrete.res(chips)!RES_0402-274K,1.0%,1/16W,CHIP,A!R9P13!//jf4cfls225.pdx.intel.com/apd_proj/ppg_lib/epg_masterlib/logical/mstr_discrete/res/chips/chips.prt!RES!RES_0402-274K,1.0%,1/16W,CHIP,G21796-331!RES!!!F781!!HOT_SWAP!!
S!@baseboard_fab2_lib.baseboard_fab2(sch_1):page108_i258@mstr_sconn.sconn200_h68296001(chips)!SCONN200_H68296001_SM-CONN,H68A!J8G1!//jf4cfls225.pdx.intel.com/apd_proj/ppg_lib/epg_masterlib/logical/mstr_sconn/sconn200_h68296001/chips/chips.prt!SCONN200_H68296001!SCONN200_H68296001_SM-CONN,H68296-001!SCONN200_H68296001_SM!!!F235!!IO_SLOT!!
S!@baseboard_fab2_lib.baseboard_fab2(sch_1):page109_i243@mstr_sconn.sconn200_h68296001(chips)!SCONN200_H68296001_SM-CONN,H68A!J8G1!//jf4cfls225.pdx.intel.com/apd_proj/ppg_lib/epg_masterlib/logical/mstr_sconn/sconn200_h68296001/chips/chips.prt!SCONN200_H68296001!SCONN200_H68296001_SM-CONN,H68296-001!SCONN200_H68296001_SM!!!F234!!IO_SLOT!!
S!@baseboard_fab2_lib.baseboard_fab2(sch_1):page196_i104@mstr_vreg.tps3700(chips)!TPS3700_SM-IC,H69492-001!U8D8!//jf4cfls225.pdx.intel.com/apd_proj/ppg_lib/epg_masterlib/logical/mstr_vreg/tps3700/chips/chips.prt!TPS3700!TPS3700_SM-IC,H69492-001!TPS3700_SM!!!F49!!V_SUPER!!
S!@baseboard_fab2_lib.baseboard_fab2(sch_1):page200_i200@mstr_vreg.tps3700(chips)!TPS3700_SM-IC,H69492-001!U9P2!//jf4cfls225.pdx.intel.com/apd_proj/ppg_lib/epg_masterlib/logical/mstr_vreg/tps3700/chips/chips.prt!TPS3700!TPS3700_SM-IC,H69492-001!TPS3700_SM!!!F47!!!!
S!@baseboard_fab2_lib.baseboard_fab2(sch_1):page200_i170@mstr_vreg.tps3700(chips)!TPS3700_SM-IC,H69492-001!U1D2!//jf4cfls225.pdx.intel.com/apd_proj/ppg_lib/epg_masterlib/logical/mstr_vreg/tps3700/chips/chips.prt!TPS3700!TPS3700_SM-IC,H69492-001!TPS3700_SM!!!F50!!!!
S!@baseboard_fab2_lib.baseboard_fab2(sch_1):page200_i163@mstr_vreg.tps3700(chips)!TPS3700_SM-IC,H69492-001!U9P1!//jf4cfls225.pdx.intel.com/apd_proj/ppg_lib/epg_masterlib/logical/mstr_vreg/tps3700/chips/chips.prt!TPS3700!TPS3700_SM-IC,H69492-001!TPS3700_SM!!!F48!!!!
S!@baseboard_fab2_lib.baseboard_fab2(sch_1):page199_i99@mstr_discrete.zener(chips)!ZENER_SM-13V,IC,H69095-001!VR1D1!//jf4cfls225.pdx.intel.com/apd_proj/ppg_lib/epg_masterlib/logical/mstr_discrete/zener/chips/chips.prt!ZENER!ZENER_SM-13V,IC,H69095-001!ZENER_SM!!!F0!!!!
S!@baseboard_fab2_lib.baseboard_fab2(sch_1):page175_i50@mstr_discrete.led(chips)!LED_1NC-BLUE,IC,C96565-012!DS9A1!//jf4cfls225.pdx.intel.com/apd_proj/ppg_lib/epg_masterlib/logical/mstr_discrete/led/chips/chips.prt!LED!LED_1NC-BLUE,IC,C96565-012!LED_1NC!!!F2038!!MIO_CHASSIS!!
S!@baseboard_fab2_lib.baseboard_fab2(sch_1):page175_i67@mstr_discrete.led(chips)!LED_1NCLF-YELLOW,IC,C96565-003!DS9A3!//jf4cfls225.pdx.intel.com/apd_proj/ppg_lib/epg_masterlib/logical/mstr_discrete/led/chips/chips.prt!LED!LED_1NCLF-YELLOW,IC,C96565-003!LED_1NCLF!!!F2036!!MIO_CHASSIS!!
S!@baseboard_fab2_lib.baseboard_fab2(sch_1):page170_i42@mstr_discrete.cap(chips)!CAP_0402LF-470PF,50V,10%,EMPTYA!C8D3!//jf4cfls225.pdx.intel.com/apd_proj/ppg_lib/epg_masterlib/logical/mstr_discrete/cap/chips/chips.prt!CAP!CAP_0402LF-470PF,50V,10%,EMPTY,A36096-049!CAP!!!F3098!!PROC_SIDEBAND!!
S!@baseboard_fab2_lib.baseboard_fab2(sch_1):page181_i224@mstr_discrete.cap(chips)!CAP_0402LF-470PF,50V,10%,EMPTYA!C2R6!//jf4cfls225.pdx.intel.com/apd_proj/ppg_lib/epg_masterlib/logical/mstr_discrete/cap/chips/chips.prt!CAP!CAP_0402LF-470PF,50V,10%,EMPTY,A36096-049!CAP!!!F3099!!IO_SLOT!!
S!@baseboard_fab2_lib.baseboard_fab2(sch_1):page114_i124@mstr_discrete.res(chips)!RES_0402-49.9,1%,1/16W,EMPTY,GA!R8B21!//jf4cfls225.pdx.intel.com/apd_proj/ppg_lib/epg_masterlib/logical/mstr_discrete/res/chips/chips.prt!RES!RES_0402-49.9,1%,1/16W,EMPTY,G21796-047!RES!!!F400!!SB!!
S!@baseboard_fab2_lib.baseboard_fab2(sch_1):page118_i67@mstr_discrete.res(chips)!RES_0402-49.9,1%,1/16W,EMPTY,GA!R3N14!//jf4cfls225.pdx.intel.com/apd_proj/ppg_lib/epg_masterlib/logical/mstr_discrete/res/chips/chips.prt!RES!RES_0402-49.9,1%,1/16W,EMPTY,G21796-047!RES!!!F403!!SB!!
S!@baseboard_fab2_lib.baseboard_fab2(sch_1):page215_i330@mstr_discrete.res(chips)!RES_0402-49.9,1%,1/16W,EMPTY,GA!R3T11!//jf4cfls225.pdx.intel.com/apd_proj/ppg_lib/epg_masterlib/logical/mstr_discrete/res/chips/chips.prt!RES!RES_0402-49.9,1%,1/16W,EMPTY,G21796-047!RES!!!F401!!VDDQ_ABC_PWR_VR!!
S!@baseboard_fab2_lib.baseboard_fab2(sch_1):page223_i50@mstr_discrete.res(chips)!RES_0402-49.9,1%,1/16W,EMPTY,GA!R9U4!//jf4cfls225.pdx.intel.com/apd_proj/ppg_lib/epg_masterlib/logical/mstr_discrete/res/chips/chips.prt!RES!RES_0402-49.9,1%,1/16W,EMPTY,G21796-047!RES!!!F399!!VDDQ_GHJ_PWR_VR!!
S!@baseboard_fab2_lib.baseboard_fab2(sch_1):page211_i28@mstr_discrete.res(chips)!RES_0402-49.9,1%,1/16W,EMPTY,GA!R3P17!//jf4cfls225.pdx.intel.com/apd_proj/ppg_lib/epg_masterlib/logical/mstr_discrete/res/chips/chips.prt!RES!RES_0402-49.9,1%,1/16W,EMPTY,G21796-047!RES!!!F402!!PVCCIO_CPU0!!
S!@baseboard_fab2_lib.baseboard_fab2(sch_1):page196_i51@mstr_discrete.vert_batt_3pin(chips)!VERT_BATT_3PIN_TH-3PVERT,C6861A!XBT8G1!//jf4cfls225.pdx.intel.com/apd_proj/ppg_lib/epg_masterlib/logical/mstr_discrete/vert_batt_3pin/chips/chips.prt!VERT_BATT_3PIN!VERT_BATT_3PIN_TH-3PVERT,C68619-005!VERT_BATT_3PIN_TH!!!F4!!SB_VRD!!
S!@baseboard_fab2_lib.baseboard_fab2(sch_1):page189_i49@mstr_discrete.diode(chips)!DIODE_SMLF-1N5819HW,IC,D55839-A!CR3U1!//jf4cfls225.pdx.intel.com/apd_proj/ppg_lib/epg_masterlib/logical/mstr_discrete/diode/chips/chips.prt!DIODE!DIODE_SMLF-1N5819HW,IC,D55839-001!DIODE_SMLF!!!F2209!!BMC_DEBUG_HEADER!!
S!@baseboard_fab2_lib.baseboard_fab2(sch_1):page200_i172@mstr_discrete.res(chips)!RES_0402-150.0K,1%,1/16W,CHIP,A!R1D20!//jf4cfls225.pdx.intel.com/apd_proj/ppg_lib/epg_masterlib/logical/mstr_discrete/res/chips/chips.prt!RES!RES_0402-150.0K,1%,1/16W,CHIP,G21796-109!RES!!!F1067!!!!
S!@baseboard_fab2_lib.baseboard_fab2(sch_1):page199_i33@mstr_discrete.res(chips)!RES_0402-150.0K,1%,1/16W,CHIP,A!R9P17!//jf4cfls225.pdx.intel.com/apd_proj/ppg_lib/epg_masterlib/logical/mstr_discrete/res/chips/chips.prt!RES!RES_0402-150.0K,1%,1/16W,CHIP,G21796-109!RES!!!F1066!!HOT_SWAP!!
S!@baseboard_fab2_lib.baseboard_fab2(sch_1):page157_i351@mstr_misc.switch_d90553001(chips)!SWITCH_D90553001_SMLF-IC,D9055A!S8E1!//jf4cfls225.pdx.intel.com/apd_proj/ppg_lib/epg_masterlib/logical/mstr_misc/switch_d90553001/chips/chips.prt!SWITCH_D90553001!SWITCH_D90553001_SMLF-IC,D90553-001!SWITCH_D90553001_SMLF!!!F64!!MIO_CHASSIS!!
S!@baseboard_fab2_lib.baseboard_fab2(sch_1):page231_i180@mstr_discrete.capp(chips)!CAPP_7343LF-330UF,6.3V,20%,POSA!C6F4!//jf4cfls225.pdx.intel.com/apd_proj/ppg_lib/epg_masterlib/logical/mstr_discrete/capp/chips/chips.prt!CAPP!CAPP_7343LF-330UF,6.3V,20%,POSCAP,724613-042!CAPP!!!F4099!!PVPP_KLM_VR!!
S!@baseboard_fab2_lib.baseboard_fab2(sch_1):page232_i229@mstr_discrete.capp(chips)!CAPP_7343LF-330UF,6.3V,20%,POSA!C6B7!//jf4cfls225.pdx.intel.com/apd_proj/ppg_lib/epg_masterlib/logical/mstr_discrete/capp/chips/chips.prt!CAPP!CAPP_7343LF-330UF,6.3V,20%,POSCAP,724613-042!CAPP!!!F4100!!PVPP_KLM_VR!!
S!@baseboard_fab2_lib.baseboard_fab2(sch_1):page233_i217@mstr_discrete.capp(chips)!CAPP_7343LF-330UF,6.3V,20%,POSA!C4F7!//jf4cfls225.pdx.intel.com/apd_proj/ppg_lib/epg_masterlib/logical/mstr_discrete/capp/chips/chips.prt!CAPP!CAPP_7343LF-330UF,6.3V,20%,POSCAP,724613-042!CAPP!!!F4101!!PVPP_KLM_VR!!
S!@baseboard_fab2_lib.baseboard_fab2(sch_1):page234_i167@mstr_discrete.capp(chips)!CAPP_7343LF-330UF,6.3V,20%,POSA!C3B3!//jf4cfls225.pdx.intel.com/apd_proj/ppg_lib/epg_masterlib/logical/mstr_discrete/capp/chips/chips.prt!CAPP!CAPP_7343LF-330UF,6.3V,20%,POSCAP,724613-042!CAPP!!!F4102!!PVPP_KLM_VR!!
S!@baseboard_fab2_lib.baseboard_fab2(sch_1):page240_i154@mstr_discrete.capp(chips)!CAPP_3018-470UF,6.3V,20%,POSCAA!C8F14!//jf4cfls225.pdx.intel.com/apd_proj/ppg_lib/epg_masterlib/logical/mstr_discrete/capp/chips/chips.prt!CAPP!CAPP_3018-470UF,6.3V,20%,POSCAP,724613-091!CAPP!!!F4128!!P3V3_STBY_VR!!
S!@baseboard_fab2_lib.baseboard_fab2(sch_1):page240_i155@mstr_discrete.capp(chips)!CAPP_3018-470UF,6.3V,20%,POSCAA!C8F8!//jf4cfls225.pdx.intel.com/apd_proj/ppg_lib/epg_masterlib/logical/mstr_discrete/capp/chips/chips.prt!CAPP!CAPP_3018-470UF,6.3V,20%,POSCAP,724613-091!CAPP!!!F4129!!P3V3_STBY_VR!!
S!@baseboard_fab2_lib.baseboard_fab2(sch_1):page241_i8@mstr_discrete.capp(chips)!CAPP_3018-470UF,6.3V,20%,POSCAA!C8E4!//jf4cfls225.pdx.intel.com/apd_proj/ppg_lib/epg_masterlib/logical/mstr_discrete/capp/chips/chips.prt!CAPP!CAPP_3018-470UF,6.3V,20%,POSCAP,724613-091!CAPP!!!F4130!!!!
S!@baseboard_fab2_lib.baseboard_fab2(sch_1):page158_i74@mstr_analog.fsa3357(chips)!FSA3357_SM-IC,C63273-001!U9F2!//jf4cfls225.pdx.intel.com/apd_proj/ppg_lib/epg_masterlib/logical/mstr_analog/fsa3357/chips/chips.prt!FSA3357!FSA3357_SM-IC,C63273-001!FSA3357_SM!!!F2129!!UART_MUX!!
S!@baseboard_fab2_lib.baseboard_fab2(sch_1):page158_i75@mstr_analog.fsa3357(chips)!FSA3357_SM-IC,C63273-001!U9F1!//jf4cfls225.pdx.intel.com/apd_proj/ppg_lib/epg_masterlib/logical/mstr_analog/fsa3357/chips/chips.prt!FSA3357!FSA3357_SM-IC,C63273-001!FSA3357_SM!!!F2130!!UART_MUX!!
S!@baseboard_fab2_lib.baseboard_fab2(sch_1):page110_i7@mstr_misc.rcc_dfx1940(chips)!RCC_DFX1940_ID4-EMPTY,N_A!TC1A1!//jf4cfls225.pdx.intel.com/apd_proj/ppg_lib/epg_masterlib/logical/mstr_misc/rcc_dfx1940/chips/chips.prt!RCC_DFX1940!RCC_DFX1940_ID4-EMPTY,N_A!RCC_DFX1940!!!F1967!!!!
S!@baseboard_fab2_lib.baseboard_fab2(sch_1):page110_i9@mstr_misc.rcc_dfx1940(chips)!RCC_DFX1940_ID4-EMPTY,N_A!TC9A1!//jf4cfls225.pdx.intel.com/apd_proj/ppg_lib/epg_masterlib/logical/mstr_misc/rcc_dfx1940/chips/chips.prt!RCC_DFX1940!RCC_DFX1940_ID4-EMPTY,N_A!RCC_DFX1940!!!F1965!!!!
S!@baseboard_fab2_lib.baseboard_fab2(sch_1):page110_i3@mstr_misc.rcc_dfx1940(chips)!RCC_DFX1940_ID4-EMPTY,N_A!TC1G1!//jf4cfls225.pdx.intel.com/apd_proj/ppg_lib/epg_masterlib/logical/mstr_misc/rcc_dfx1940/chips/chips.prt!RCC_DFX1940!RCC_DFX1940_ID4-EMPTY,N_A!RCC_DFX1940!!!F1966!!!!
S!@baseboard_fab2_lib.baseboard_fab2(sch_1):page110_i1@mstr_misc.rcc_dfx1940(chips)!RCC_DFX1940_ID4-EMPTY,N_A!TC9F1!//jf4cfls225.pdx.intel.com/apd_proj/ppg_lib/epg_masterlib/logical/mstr_misc/rcc_dfx1940/chips/chips.prt!RCC_DFX1940!RCC_DFX1940_ID4-EMPTY,N_A!RCC_DFX1940!!!F1964!!!!
S!@baseboard_fab2_lib.baseboard_fab2(sch_1):page110_i11@mstr_misc.snlabel_a(chips)!SNLABEL_A_LABEL-EMPTY,N_A!LB2F1!//jf4cfls225.pdx.intel.com/apd_proj/ppg_lib/epg_masterlib/logical/mstr_misc/snlabel_a/chips/chips.prt!SNLABEL_A!SNLABEL_A_LABEL-EMPTY,N_A!SNLABEL_A!!!TF-12953!!LABELS!!
S!@baseboard_fab2_lib.baseboard_fab2(sch_1):page110_i12@mstr_misc.snlabel_a(chips)!SNLABEL_A_LABEL-EMPTY,N_A!LB5F1!//jf4cfls225.pdx.intel.com/apd_proj/ppg_lib/epg_masterlib/logical/mstr_misc/snlabel_a/chips/chips.prt!SNLABEL_A!SNLABEL_A_LABEL-EMPTY,N_A!SNLABEL_A!!!TF-12952!!LABELS!!
S!@baseboard_fab2_lib.baseboard_fab2(sch_1):page110_i13@mstr_misc.snlabel_a(chips)!SNLABEL_A_LABEL-EMPTY,N_A!LB2B1!//jf4cfls225.pdx.intel.com/apd_proj/ppg_lib/epg_masterlib/logical/mstr_misc/snlabel_a/chips/chips.prt!SNLABEL_A!SNLABEL_A_LABEL-EMPTY,N_A!SNLABEL_A!!!TF-12951!!LABELS!!
S!@baseboard_fab2_lib.baseboard_fab2(sch_1):page110_i14@mstr_misc.snlabel_a(chips)!SNLABEL_A_LABEL-EMPTY,N_A!LB5B1!//jf4cfls225.pdx.intel.com/apd_proj/ppg_lib/epg_masterlib/logical/mstr_misc/snlabel_a/chips/chips.prt!SNLABEL_A!SNLABEL_A_LABEL-EMPTY,N_A!SNLABEL_A!!!TF-12950!!LABELS!!
S!@baseboard_fab2_lib.baseboard_fab2(sch_1):page110_i15@mstr_misc.snlabel_a(chips)!SNLABEL_A_LABEL-EMPTY,N_A!LB6T1!//jf4cfls225.pdx.intel.com/apd_proj/ppg_lib/epg_masterlib/logical/mstr_misc/snlabel_a/chips/chips.prt!SNLABEL_A!SNLABEL_A_LABEL-EMPTY,N_A!SNLABEL_A!!!TF-12949!!LABELS!!
S!@baseboard_fab2_lib.baseboard_fab2(sch_1):page175_i84@mstr_misc.sw_h67881001(chips)!SW_H67881001_SM-IC,H67881-001!S9A2!//jf4cfls225.pdx.intel.com/apd_proj/ppg_lib/epg_masterlib/logical/mstr_misc/sw_h67881001/chips/chips.prt!SW_H67881001!SW_H67881001_SM-IC,H67881-001!SW_H67881001_SM!!!F63!!MIO_CHASSIS!!
S!@baseboard_fab2_lib.baseboard_fab2(sch_1):page176_i100@mstr_vreg.tps2061(chips)!TPS2061_SM-IC,H66405-001!U1M3!//jf4cfls225.pdx.intel.com/apd_proj/ppg_lib/epg_masterlib/logical/mstr_vreg/tps2061/chips/chips.prt!TPS2061!TPS2061_SM-IC,H66405-001!TPS2061_SM!!!F51!!USB_REAR!!
S!@baseboard_fab2_lib.baseboard_fab2(sch_1):page141_i100@mstr_discrete.cap(chips)!CAP_0402LF-4700PF,50V,10%,EMPTA!C9G12!//jf4cfls225.pdx.intel.com/apd_proj/ppg_lib/epg_masterlib/logical/mstr_discrete/cap/chips/chips.prt!CAP!CAP_0402LF-4700PF,50V,10%,EMPTY,A36096-066!CAP!!!F3102!!NIC_SPRV!!
S!@baseboard_fab2_lib.baseboard_fab2(sch_1):page141_i102@mstr_discrete.cap(chips)!CAP_0402LF-4700PF,50V,10%,EMPTA!C9G13!//jf4cfls225.pdx.intel.com/apd_proj/ppg_lib/epg_masterlib/logical/mstr_discrete/cap/chips/chips.prt!CAP!CAP_0402LF-4700PF,50V,10%,EMPTY,A36096-066!CAP!!!F3101!!NIC_SPRV!!
S!@baseboard_fab2_lib.baseboard_fab2(sch_1):page141_i99@mstr_discrete.cap(chips)!CAP_0402LF-4700PF,50V,10%,EMPTA!C9G9!//jf4cfls225.pdx.intel.com/apd_proj/ppg_lib/epg_masterlib/logical/mstr_discrete/cap/chips/chips.prt!CAP!CAP_0402LF-4700PF,50V,10%,EMPTY,A36096-066!CAP!!!F3103!!NIC_SPRV!!
S!@baseboard_fab2_lib.baseboard_fab2(sch_1):page141_i101@mstr_discrete.cap(chips)!CAP_0402LF-4700PF,50V,10%,EMPTA!C9G16!//jf4cfls225.pdx.intel.com/apd_proj/ppg_lib/epg_masterlib/logical/mstr_discrete/cap/chips/chips.prt!CAP!CAP_0402LF-4700PF,50V,10%,EMPTY,A36096-066!CAP!!!F3100!!NIC_SPRV!!
S!@baseboard_fab2_lib.baseboard_fab2(sch_1):page217_i91@mstr_discrete.cap(chips)!CAP_0805-100UF,4V,20%,X5R,6024A!C4T4!//jf4cfls225.pdx.intel.com/apd_proj/ppg_lib/epg_masterlib/logical/mstr_discrete/cap/chips/chips.prt!CAP!CAP_0805-100UF,4V,20%,X5R,602433-112!CAP!!!F2584!!VDDQ_ABC_PWR_VR!!
S!@baseboard_fab2_lib.baseboard_fab2(sch_1):page217_i83@mstr_discrete.cap(chips)!CAP_0805-100UF,4V,20%,X5R,6024A!C5U10!//jf4cfls225.pdx.intel.com/apd_proj/ppg_lib/epg_masterlib/logical/mstr_discrete/cap/chips/chips.prt!CAP!CAP_0805-100UF,4V,20%,X5R,602433-112!CAP!!!F2572!!VDDQ_ABC_PWR_VR!!
S!@baseboard_fab2_lib.baseboard_fab2(sch_1):page217_i89@mstr_discrete.cap(chips)!CAP_0805-100UF,4V,20%,X5R,6024A!C5U14!//jf4cfls225.pdx.intel.com/apd_proj/ppg_lib/epg_masterlib/logical/mstr_discrete/cap/chips/chips.prt!CAP!CAP_0805-100UF,4V,20%,X5R,602433-112!CAP!!!F2570!!VDDQ_ABC_PWR_VR!!
S!@baseboard_fab2_lib.baseboard_fab2(sch_1):page217_i88@mstr_discrete.cap(chips)!CAP_0805-100UF,4V,20%,X5R,6024A!C5U1!//jf4cfls225.pdx.intel.com/apd_proj/ppg_lib/epg_masterlib/logical/mstr_discrete/cap/chips/chips.prt!CAP!CAP_0805-100UF,4V,20%,X5R,602433-112!CAP!!!F2573!!VDDQ_ABC_PWR_VR!!
S!@baseboard_fab2_lib.baseboard_fab2(sch_1):page217_i82@mstr_discrete.cap(chips)!CAP_0805-100UF,4V,20%,X5R,6024A!C5U13!//jf4cfls225.pdx.intel.com/apd_proj/ppg_lib/epg_masterlib/logical/mstr_discrete/cap/chips/chips.prt!CAP!CAP_0805-100UF,4V,20%,X5R,602433-112!CAP!!!F2571!!VDDQ_ABC_PWR_VR!!
S!@baseboard_fab2_lib.baseboard_fab2(sch_1):page217_i90@mstr_discrete.cap(chips)!CAP_0805-100UF,4V,20%,X5R,6024A!C5U15!//jf4cfls225.pdx.intel.com/apd_proj/ppg_lib/epg_masterlib/logical/mstr_discrete/cap/chips/chips.prt!CAP!CAP_0805-100UF,4V,20%,X5R,602433-112!CAP!!!F2569!!VDDQ_ABC_PWR_VR!!
S!@baseboard_fab2_lib.baseboard_fab2(sch_1):page217_i92@mstr_discrete.cap(chips)!CAP_0805-100UF,4V,20%,X5R,6024A!C5G9!//jf4cfls225.pdx.intel.com/apd_proj/ppg_lib/epg_masterlib/logical/mstr_discrete/cap/chips/chips.prt!CAP!CAP_0805-100UF,4V,20%,X5R,602433-112!CAP!!!F2581!!VDDQ_ABC_PWR_VR!!
S!@baseboard_fab2_lib.baseboard_fab2(sch_1):page217_i110@mstr_discrete.cap(chips)!CAP_0805-100UF,4V,20%,X5R,6024A!C5G20!//jf4cfls225.pdx.intel.com/apd_proj/ppg_lib/epg_masterlib/logical/mstr_discrete/cap/chips/chips.prt!CAP!CAP_0805-100UF,4V,20%,X5R,602433-112!CAP!!!F2580!!VDDQ_ABC_PWR_VR!!
S!@baseboard_fab2_lib.baseboard_fab2(sch_1):page225_i110@mstr_discrete.cap(chips)!CAP_0805-100UF,4V,20%,X5R,6024A!C2G16!//jf4cfls225.pdx.intel.com/apd_proj/ppg_lib/epg_masterlib/logical/mstr_discrete/cap/chips/chips.prt!CAP!CAP_0805-100UF,4V,20%,X5R,602433-112!CAP!!!F2585!!VDDQ_GHJ_PWR_VR!!
S!@baseboard_fab2_lib.baseboard_fab2(sch_1):page225_i92@mstr_discrete.cap(chips)!CAP_0805-100UF,4V,20%,X5R,6024A!C2G7!//jf4cfls225.pdx.intel.com/apd_proj/ppg_lib/epg_masterlib/logical/mstr_discrete/cap/chips/chips.prt!CAP!CAP_0805-100UF,4V,20%,X5R,602433-112!CAP!!!F2586!!VDDQ_GHJ_PWR_VR!!
S!@baseboard_fab2_lib.baseboard_fab2(sch_1):page225_i91@mstr_discrete.cap(chips)!CAP_0805-100UF,4V,20%,X5R,6024A!C7U7!//jf4cfls225.pdx.intel.com/apd_proj/ppg_lib/epg_masterlib/logical/mstr_discrete/cap/chips/chips.prt!CAP!CAP_0805-100UF,4V,20%,X5R,602433-112!CAP!!!F2566!!VDDQ_GHJ_PWR_VR!!
S!@baseboard_fab2_lib.baseboard_fab2(sch_1):page225_i90@mstr_discrete.cap(chips)!CAP_0805-100UF,4V,20%,X5R,6024A!C7T1!//jf4cfls225.pdx.intel.com/apd_proj/ppg_lib/epg_masterlib/logical/mstr_discrete/cap/chips/chips.prt!CAP!CAP_0805-100UF,4V,20%,X5R,602433-112!CAP!!!F2567!!VDDQ_GHJ_PWR_VR!!
S!@baseboard_fab2_lib.baseboard_fab2(sch_1):page225_i89@mstr_discrete.cap(chips)!CAP_0805-100UF,4V,20%,X5R,6024A!C8U11!//jf4cfls225.pdx.intel.com/apd_proj/ppg_lib/epg_masterlib/logical/mstr_discrete/cap/chips/chips.prt!CAP!CAP_0805-100UF,4V,20%,X5R,602433-112!CAP!!!F2558!!VDDQ_GHJ_PWR_VR!!
S!@baseboard_fab2_lib.baseboard_fab2(sch_1):page225_i88@mstr_discrete.cap(chips)!CAP_0805-100UF,4V,20%,X5R,6024A!C8U12!//jf4cfls225.pdx.intel.com/apd_proj/ppg_lib/epg_masterlib/logical/mstr_discrete/cap/chips/chips.prt!CAP!CAP_0805-100UF,4V,20%,X5R,602433-112!CAP!!!F2557!!VDDQ_GHJ_PWR_VR!!
S!@baseboard_fab2_lib.baseboard_fab2(sch_1):page225_i83@mstr_discrete.cap(chips)!CAP_0805-100UF,4V,20%,X5R,6024A!C8U8!//jf4cfls225.pdx.intel.com/apd_proj/ppg_lib/epg_masterlib/logical/mstr_discrete/cap/chips/chips.prt!CAP!CAP_0805-100UF,4V,20%,X5R,602433-112!CAP!!!F2559!!VDDQ_GHJ_PWR_VR!!
S!@baseboard_fab2_lib.baseboard_fab2(sch_1):page225_i82@mstr_discrete.cap(chips)!CAP_0805-100UF,4V,20%,X5R,6024A!C8U1!//jf4cfls225.pdx.intel.com/apd_proj/ppg_lib/epg_masterlib/logical/mstr_discrete/cap/chips/chips.prt!CAP!CAP_0805-100UF,4V,20%,X5R,602433-112!CAP!!!F2560!!VDDQ_GHJ_PWR_VR!!
S!@baseboard_fab2_lib.baseboard_fab2(sch_1):page228_i110@mstr_discrete.cap(chips)!CAP_0805-100UF,4V,20%,X5R,6024A!C8L1!//jf4cfls225.pdx.intel.com/apd_proj/ppg_lib/epg_masterlib/logical/mstr_discrete/cap/chips/chips.prt!CAP!CAP_0805-100UF,4V,20%,X5R,602433-112!CAP!!!F2565!!VDDQ_KLM_PWR_VR!!
S!@baseboard_fab2_lib.baseboard_fab2(sch_1):page228_i92@mstr_discrete.cap(chips)!CAP_0805-100UF,4V,20%,X5R,6024A!C7L1!//jf4cfls225.pdx.intel.com/apd_proj/ppg_lib/epg_masterlib/logical/mstr_discrete/cap/chips/chips.prt!CAP!CAP_0805-100UF,4V,20%,X5R,602433-112!CAP!!!F2568!!VDDQ_KLM_PWR_VR!!
S!@baseboard_fab2_lib.baseboard_fab2(sch_1):page228_i91@mstr_discrete.cap(chips)!CAP_0805-100UF,4V,20%,X5R,6024A!C8M11!//jf4cfls225.pdx.intel.com/apd_proj/ppg_lib/epg_masterlib/logical/mstr_discrete/cap/chips/chips.prt!CAP!CAP_0805-100UF,4V,20%,X5R,602433-112!CAP!!!F2561!!VDDQ_KLM_PWR_VR!!
S!@baseboard_fab2_lib.baseboard_fab2(sch_1):page228_i90@mstr_discrete.cap(chips)!CAP_0805-100UF,4V,20%,X5R,6024A!C8M7!//jf4cfls225.pdx.intel.com/apd_proj/ppg_lib/epg_masterlib/logical/mstr_discrete/cap/chips/chips.prt!CAP!CAP_0805-100UF,4V,20%,X5R,602433-112!CAP!!!F2562!!VDDQ_KLM_PWR_VR!!
S!@baseboard_fab2_lib.baseboard_fab2(sch_1):page228_i89@mstr_discrete.cap(chips)!CAP_0805-100UF,4V,20%,X5R,6024A!C2A16!//jf4cfls225.pdx.intel.com/apd_proj/ppg_lib/epg_masterlib/logical/mstr_discrete/cap/chips/chips.prt!CAP!CAP_0805-100UF,4V,20%,X5R,602433-112!CAP!!!F2587!!VDDQ_KLM_PWR_VR!!
S!@baseboard_fab2_lib.baseboard_fab2(sch_1):page228_i88@mstr_discrete.cap(chips)!CAP_0805-100UF,4V,20%,X5R,6024A!C8L11!//jf4cfls225.pdx.intel.com/apd_proj/ppg_lib/epg_masterlib/logical/mstr_discrete/cap/chips/chips.prt!CAP!CAP_0805-100UF,4V,20%,X5R,602433-112!CAP!!!F2563!!VDDQ_KLM_PWR_VR!!
S!@baseboard_fab2_lib.baseboard_fab2(sch_1):page228_i83@mstr_discrete.cap(chips)!CAP_0805-100UF,4V,20%,X5R,6024A!C8L2!//jf4cfls225.pdx.intel.com/apd_proj/ppg_lib/epg_masterlib/logical/mstr_discrete/cap/chips/chips.prt!CAP!CAP_0805-100UF,4V,20%,X5R,602433-112!CAP!!!F2564!!VDDQ_KLM_PWR_VR!!
S!@baseboard_fab2_lib.baseboard_fab2(sch_1):page228_i82@mstr_discrete.cap(chips)!CAP_0805-100UF,4V,20%,X5R,6024A!C2A8!//jf4cfls225.pdx.intel.com/apd_proj/ppg_lib/epg_masterlib/logical/mstr_discrete/cap/chips/chips.prt!CAP!CAP_0805-100UF,4V,20%,X5R,602433-112!CAP!!!F2588!!VDDQ_KLM_PWR_VR!!
S!@baseboard_fab2_lib.baseboard_fab2(sch_1):page220_i110@mstr_discrete.cap(chips)!CAP_0805-100UF,4V,20%,X5R,6024A!C5A10!//jf4cfls225.pdx.intel.com/apd_proj/ppg_lib/epg_masterlib/logical/mstr_discrete/cap/chips/chips.prt!CAP!CAP_0805-100UF,4V,20%,X5R,602433-112!CAP!!!F2583!!VDDQ_DEF_PWR_VR!!
S!@baseboard_fab2_lib.baseboard_fab2(sch_1):page220_i91@mstr_discrete.cap(chips)!CAP_0805-100UF,4V,20%,X5R,6024A!C5L1!//jf4cfls225.pdx.intel.com/apd_proj/ppg_lib/epg_masterlib/logical/mstr_discrete/cap/chips/chips.prt!CAP!CAP_0805-100UF,4V,20%,X5R,602433-112!CAP!!!F2579!!VDDQ_DEF_PWR_VR!!
S!@baseboard_fab2_lib.baseboard_fab2(sch_1):page220_i89@mstr_discrete.cap(chips)!CAP_0805-100UF,4V,20%,X5R,6024A!C5L3!//jf4cfls225.pdx.intel.com/apd_proj/ppg_lib/epg_masterlib/logical/mstr_discrete/cap/chips/chips.prt!CAP!CAP_0805-100UF,4V,20%,X5R,602433-112!CAP!!!F2577!!VDDQ_DEF_PWR_VR!!
S!@baseboard_fab2_lib.baseboard_fab2(sch_1):page220_i83@mstr_discrete.cap(chips)!CAP_0805-100UF,4V,20%,X5R,6024A!C5L14!//jf4cfls225.pdx.intel.com/apd_proj/ppg_lib/epg_masterlib/logical/mstr_discrete/cap/chips/chips.prt!CAP!CAP_0805-100UF,4V,20%,X5R,602433-112!CAP!!!F2576!!VDDQ_DEF_PWR_VR!!
S!@baseboard_fab2_lib.baseboard_fab2(sch_1):page220_i82@mstr_discrete.cap(chips)!CAP_0805-100UF,4V,20%,X5R,6024A!C5M8!//jf4cfls225.pdx.intel.com/apd_proj/ppg_lib/epg_masterlib/logical/mstr_discrete/cap/chips/chips.prt!CAP!CAP_0805-100UF,4V,20%,X5R,602433-112!CAP!!!F2575!!VDDQ_DEF_PWR_VR!!
S!@baseboard_fab2_lib.baseboard_fab2(sch_1):page220_i92@mstr_discrete.cap(chips)!CAP_0805-100UF,4V,20%,X5R,6024A!C5A20!//jf4cfls225.pdx.intel.com/apd_proj/ppg_lib/epg_masterlib/logical/mstr_discrete/cap/chips/chips.prt!CAP!CAP_0805-100UF,4V,20%,X5R,602433-112!CAP!!!F2582!!VDDQ_DEF_PWR_VR!!
S!@baseboard_fab2_lib.baseboard_fab2(sch_1):page220_i90@mstr_discrete.cap(chips)!CAP_0805-100UF,4V,20%,X5R,6024A!C5L2!//jf4cfls225.pdx.intel.com/apd_proj/ppg_lib/epg_masterlib/logical/mstr_discrete/cap/chips/chips.prt!CAP!CAP_0805-100UF,4V,20%,X5R,602433-112!CAP!!!F2578!!VDDQ_DEF_PWR_VR!!
S!@baseboard_fab2_lib.baseboard_fab2(sch_1):page220_i88@mstr_discrete.cap(chips)!CAP_0805-100UF,4V,20%,X5R,6024A!C5M12!//jf4cfls225.pdx.intel.com/apd_proj/ppg_lib/epg_masterlib/logical/mstr_discrete/cap/chips/chips.prt!CAP!CAP_0805-100UF,4V,20%,X5R,602433-112!CAP!!!F2574!!VDDQ_DEF_PWR_VR!!
S!@baseboard_fab2_lib.baseboard_fab2(sch_1):page183_i19@mstr_discrete.crystal(chips)!CRYSTAL_SM-24.000MHZ,IC,D95126A!Y9F1!//jf4cfls225.pdx.intel.com/apd_proj/ppg_lib/epg_masterlib/logical/mstr_discrete/crystal/chips/chips.prt!CRYSTAL!CRYSTAL_SM-24.000MHZ,IC,D95126-001!CRYSTAL_SM!!!F2228!!LBG!!
S!@baseboard_fab2_lib.baseboard_fab2(sch_1):page240_i143@mstr_discrete.res(chips)!RES_0402-23.2K,1%,1/16W,CHIP,GA!R8E31!//jf4cfls225.pdx.intel.com/apd_proj/ppg_lib/epg_masterlib/logical/mstr_discrete/res/chips/chips.prt!RES!RES_0402-23.2K,1%,1/16W,CHIP,G21796-114!RES!!!F845!!P3V3_STBY_VR!!
S!@baseboard_fab2_lib.baseboard_fab2(sch_1):page240_i170@mstr_discrete.csd87384m(chips)!CSD87384M_SM-IC,H66258-001!EU8E1!//jf4cfls225.pdx.intel.com/apd_proj/ppg_lib/epg_masterlib/logical/mstr_discrete/csd87384m/chips/chips.prt!CSD87384M!CSD87384M_SM-IC,H66258-001!CSD87384M_SM!!!F2226!!P3V3_STBY_VR!!
S!@baseboard_fab2_lib.baseboard_fab2(sch_1):page183_i1@mstr_controller.pi7c9x1172(chips)!PI7C9X1172_QFN-IC,H66899-001!EU9F3!//jf4cfls225.pdx.intel.com/apd_proj/ppg_lib/epg_masterlib/logical/mstr_controller/pi7c9x1172/chips/chips.prt!PI7C9X1172!PI7C9X1172_QFN-IC,H66899-001!PI7C9X1172_QFN!!!F1979!!LBG!!
S!@baseboard_fab2_lib.baseboard_fab2(sch_1):page240_i125@mstr_vreg.rt8240(chips)!RT8240_QFN-IC,H66262-001!EU8F1!//jf4cfls225.pdx.intel.com/apd_proj/ppg_lib/epg_masterlib/logical/mstr_vreg/rt8240/chips/chips.prt!RT8240!RT8240_QFN-IC,H66262-001!RT8240_QFN!!!F246!!P3V3_STBY_VR!!
S!@baseboard_fab2_lib.baseboard_fab2(sch_1):page184_i87@mstr_sconn.sconn11_h67026001(chips)!SCONN11_H67026001_SM-CONN,H670A!J8E1!//jf4cfls225.pdx.intel.com/apd_proj/ppg_lib/epg_masterlib/logical/mstr_sconn/sconn11_h67026001/chips/chips.prt!SCONN11_H67026001!SCONN11_H67026001_SM-CONN,H67026-001!SCONN11_H67026001_SM!!!F241!!TPM!!
S!@baseboard_fab2_lib.baseboard_fab2(sch_1):page91_i1@mstr_sconn.sconn24_h46321001(chips)!SCONN24_H46321001_SM-SCONN,H46A!J8B1!//jf4cfls225.pdx.intel.com/apd_proj/ppg_lib/epg_masterlib/logical/mstr_sconn/sconn24_h46321001/chips/chips.prt!SCONN24_H46321001!SCONN24_H46321001_SM-SCONN,H46321-001!SCONN24_H46321001_SM!!!F233!!HFI!!
S!@baseboard_fab2_lib.baseboard_fab2(sch_1):page190_i179@mstr_memory.lcmxo2(chips)!LCMXO2_256BGA-IC,H63395-001!U8D7!//jf4cfls225.pdx.intel.com/apd_proj/ppg_lib/epg_masterlib/logical/mstr_memory/lcmxo2/chips/chips.prt!LCMXO2!LCMXO2_256BGA-IC,H63395-001!LCMXO2_256BGA!!!F2041!!CPLD!!
S!@baseboard_fab2_lib.baseboard_fab2(sch_1):page191_i59@mstr_memory.lcmxo2(chips)!LCMXO2_256BGA-IC,H63395-001!U8D7!//jf4cfls225.pdx.intel.com/apd_proj/ppg_lib/epg_masterlib/logical/mstr_memory/lcmxo2/chips/chips.prt!LCMXO2!LCMXO2_256BGA-IC,H63395-001!LCMXO2_256BGA!!!F2040!!CPLD!!
S!@baseboard_fab2_lib.baseboard_fab2(sch_1):page192_i14@mstr_memory.lcmxo2(chips)!LCMXO2_256BGA-IC,H63395-001!U8D7!//jf4cfls225.pdx.intel.com/apd_proj/ppg_lib/epg_masterlib/logical/mstr_memory/lcmxo2/chips/chips.prt!LCMXO2!LCMXO2_256BGA-IC,H63395-001!LCMXO2_256BGA!!!F2039!!CPLD!!
S!@baseboard_fab2_lib.baseboard_fab2(sch_1):page191_i166@mstr_discrete.res(chips)!RES_0402-51,5.0%,1/16W,CHIP,G2A!R2R6!//jf4cfls225.pdx.intel.com/apd_proj/ppg_lib/epg_masterlib/logical/mstr_discrete/res/chips/chips.prt!RES!RES_0402-51,5.0%,1/16W,CHIP,G21497-048!RES!!!F383!!CPLD!!
S!@baseboard_fab2_lib.baseboard_fab2(sch_1):page144_i547@mstr_discrete.res(chips)!RES_0402-51,5.0%,1/16W,CHIP,G2A!R1U12!//jf4cfls225.pdx.intel.com/apd_proj/ppg_lib/epg_masterlib/logical/mstr_discrete/res/chips/chips.prt!RES!RES_0402-51,5.0%,1/16W,CHIP,G21497-048!RES!!!F386!!BMC!!
S!@baseboard_fab2_lib.baseboard_fab2(sch_1):page144_i546@mstr_discrete.res(chips)!RES_0402-51,5.0%,1/16W,CHIP,G2A!R1U13!//jf4cfls225.pdx.intel.com/apd_proj/ppg_lib/epg_masterlib/logical/mstr_discrete/res/chips/chips.prt!RES!RES_0402-51,5.0%,1/16W,CHIP,G21497-048!RES!!!F385!!BMC!!
S!@baseboard_fab2_lib.baseboard_fab2(sch_1):page144_i548@mstr_discrete.res(chips)!RES_0402-51,5.0%,1/16W,CHIP,G2A!R1U14!//jf4cfls225.pdx.intel.com/apd_proj/ppg_lib/epg_masterlib/logical/mstr_discrete/res/chips/chips.prt!RES!RES_0402-51,5.0%,1/16W,CHIP,G21497-048!RES!!!F384!!BMC!!
S!@baseboard_fab2_lib.baseboard_fab2(sch_1):page155_i129@mstr_discrete.fuse(chips)!FUSE_SMT-IC,H45581-001!F1L1!//jf4cfls225.pdx.intel.com/apd_proj/ppg_lib/epg_masterlib/logical/mstr_discrete/fuse/chips/chips.prt!FUSE!FUSE_SMT-IC,H45581-001!FUSE_SMT!1!!F2126!!BMC_DEBUG_HEADER!!
S!@baseboard_fab2_lib.baseboard_fab2(sch_1):page239_i15@mstr_discrete.res(chips)!RES_0402-13K,1.0%,1/16W,CHIP,GA!R9F32!//jf4cfls225.pdx.intel.com/apd_proj/ppg_lib/epg_masterlib/logical/mstr_discrete/res/chips/chips.prt!RES!RES_0402-13K,1.0%,1/16W,CHIP,G21796-221!RES!!!F1105!!P1V538_BMC_STBY_VR!!
S!@baseboard_fab2_lib.baseboard_fab2(sch_1):page175_i78@mstr_misc.switch_d37771002(chips)!SWITCH_D37771002_SM-IC,D37771-A!S9A1!//jf4cfls225.pdx.intel.com/apd_proj/ppg_lib/epg_masterlib/logical/mstr_misc/switch_d37771002/chips/chips.prt!SWITCH_D37771002!SWITCH_D37771002_SM-IC,D37771-002!SWITCH_D37771002_SM!!!F65!!MIO_CHASSIS!!
S!@baseboard_fab2_lib.baseboard_fab2(sch_1):page216_i55@mstr_discrete.inductor(chips)!INDUCTOR_SM-0.12UH,IND,D92183-A!L7G1!//jf4cfls225.pdx.intel.com/apd_proj/ppg_lib/epg_masterlib/logical/mstr_discrete/inductor/chips/chips.prt!INDUCTOR!INDUCTOR_SM-0.12UH,IND,D92183-034!INDUCTOR!!!F2102!!VDDQ_ABC_PWR_VR!!
S!@baseboard_fab2_lib.baseboard_fab2(sch_1):page216_i65@mstr_discrete.inductor(chips)!INDUCTOR_SM-0.12UH,IND,D92183-A!L7G2!//jf4cfls225.pdx.intel.com/apd_proj/ppg_lib/epg_masterlib/logical/mstr_discrete/inductor/chips/chips.prt!INDUCTOR!INDUCTOR_SM-0.12UH,IND,D92183-034!INDUCTOR!!!F2101!!VDDQ_ABC_PWR_VR!!
S!@baseboard_fab2_lib.baseboard_fab2(sch_1):page219_i55@mstr_discrete.inductor(chips)!INDUCTOR_SM-0.12UH,IND,D92183-A!L7A1!//jf4cfls225.pdx.intel.com/apd_proj/ppg_lib/epg_masterlib/logical/mstr_discrete/inductor/chips/chips.prt!INDUCTOR!INDUCTOR_SM-0.12UH,IND,D92183-034!INDUCTOR!!!F2104!!VDDQ_DEF_PWR_VR!!
S!@baseboard_fab2_lib.baseboard_fab2(sch_1):page219_i65@mstr_discrete.inductor(chips)!INDUCTOR_SM-0.12UH,IND,D92183-A!L7A3!//jf4cfls225.pdx.intel.com/apd_proj/ppg_lib/epg_masterlib/logical/mstr_discrete/inductor/chips/chips.prt!INDUCTOR!INDUCTOR_SM-0.12UH,IND,D92183-034!INDUCTOR!!!F2103!!VDDQ_DEF_PWR_VR!!
S!@baseboard_fab2_lib.baseboard_fab2(sch_1):page227_i55@mstr_discrete.inductor(chips)!INDUCTOR_SM-0.12UH,IND,D92183-A!L1A2!//jf4cfls225.pdx.intel.com/apd_proj/ppg_lib/epg_masterlib/logical/mstr_discrete/inductor/chips/chips.prt!INDUCTOR!INDUCTOR_SM-0.12UH,IND,D92183-034!INDUCTOR!!!F2117!!VDDQ_KLM_PWR_VR!!
S!@baseboard_fab2_lib.baseboard_fab2(sch_1):page227_i65@mstr_discrete.inductor(chips)!INDUCTOR_SM-0.12UH,IND,D92183-A!L1A1!//jf4cfls225.pdx.intel.com/apd_proj/ppg_lib/epg_masterlib/logical/mstr_discrete/inductor/chips/chips.prt!INDUCTOR!INDUCTOR_SM-0.12UH,IND,D92183-034!INDUCTOR!!!F2118!!VDDQ_KLM_PWR_VR!!
S!@baseboard_fab2_lib.baseboard_fab2(sch_1):page224_i55@mstr_discrete.inductor(chips)!INDUCTOR_SM-0.12UH,IND,D92183-A!L1G1!//jf4cfls225.pdx.intel.com/apd_proj/ppg_lib/epg_masterlib/logical/mstr_discrete/inductor/chips/chips.prt!INDUCTOR!INDUCTOR_SM-0.12UH,IND,D92183-034!INDUCTOR!!!F2110!!VDDQ_GHJ_PWR_VR!!
S!@baseboard_fab2_lib.baseboard_fab2(sch_1):page224_i65@mstr_discrete.inductor(chips)!INDUCTOR_SM-0.12UH,IND,D92183-A!L1F2!//jf4cfls225.pdx.intel.com/apd_proj/ppg_lib/epg_masterlib/logical/mstr_discrete/inductor/chips/chips.prt!INDUCTOR!INDUCTOR_SM-0.12UH,IND,D92183-034!INDUCTOR!!!F2111!!VDDQ_GHJ_PWR_VR!!
S!@baseboard_fab2_lib.baseboard_fab2(sch_1):page203_i15@mstr_discrete.inductor(chips)!INDUCTOR_SM-0.12UH,IND,D92183-A!L4D2!//jf4cfls225.pdx.intel.com/apd_proj/ppg_lib/epg_masterlib/logical/mstr_discrete/inductor/chips/chips.prt!INDUCTOR!INDUCTOR_SM-0.12UH,IND,D92183-034!INDUCTOR!!!F2107!!PVCCIN_CPU0_PWR_VR!!
S!@baseboard_fab2_lib.baseboard_fab2(sch_1):page203_i24@mstr_discrete.inductor(chips)!INDUCTOR_SM-0.12UH,IND,D92183-A!L4D1!//jf4cfls225.pdx.intel.com/apd_proj/ppg_lib/epg_masterlib/logical/mstr_discrete/inductor/chips/chips.prt!INDUCTOR!INDUCTOR_SM-0.12UH,IND,D92183-034!INDUCTOR!!!F2108!!PVCCIN_CPU0_PWR_VR!!
S!@baseboard_fab2_lib.baseboard_fab2(sch_1):page204_i5@mstr_discrete.inductor(chips)!INDUCTOR_SM-0.12UH,IND,D92183-A!L4C3!//jf4cfls225.pdx.intel.com/apd_proj/ppg_lib/epg_masterlib/logical/mstr_discrete/inductor/chips/chips.prt!INDUCTOR!INDUCTOR_SM-0.12UH,IND,D92183-034!INDUCTOR!!!F2109!!PVCCIN_CPU0_PWR_VR!!
S!@baseboard_fab2_lib.baseboard_fab2(sch_1):page202_i29@mstr_discrete.inductor(chips)!INDUCTOR_SM-0.12UH,IND,D92183-A!L4D3!//jf4cfls225.pdx.intel.com/apd_proj/ppg_lib/epg_masterlib/logical/mstr_discrete/inductor/chips/chips.prt!INDUCTOR!INDUCTOR_SM-0.12UH,IND,D92183-034!INDUCTOR!!!F2106!!PVCCIN_CPU0_PWR_VR!!
S!@baseboard_fab2_lib.baseboard_fab2(sch_1):page202_i5@mstr_discrete.inductor(chips)!INDUCTOR_SM-0.12UH,IND,D92183-A!L4E1!//jf4cfls225.pdx.intel.com/apd_proj/ppg_lib/epg_masterlib/logical/mstr_discrete/inductor/chips/chips.prt!INDUCTOR!INDUCTOR_SM-0.12UH,IND,D92183-034!INDUCTOR!!!F2105!!PVCCIN_CPU0_PWR_VR!!
S!@baseboard_fab2_lib.baseboard_fab2(sch_1):page207_i16@mstr_discrete.inductor(chips)!INDUCTOR_SM-0.12UH,IND,D92183-A!L1D3!//jf4cfls225.pdx.intel.com/apd_proj/ppg_lib/epg_masterlib/logical/mstr_discrete/inductor/chips/chips.prt!INDUCTOR!INDUCTOR_SM-0.12UH,IND,D92183-034!INDUCTOR!!!F2113!!PVCCIN_CPU1_PWR_VR!!
S!@baseboard_fab2_lib.baseboard_fab2(sch_1):page207_i10@mstr_discrete.inductor(chips)!INDUCTOR_SM-0.12UH,IND,D92183-A!L1E1!//jf4cfls225.pdx.intel.com/apd_proj/ppg_lib/epg_masterlib/logical/mstr_discrete/inductor/chips/chips.prt!INDUCTOR!INDUCTOR_SM-0.12UH,IND,D92183-034!INDUCTOR!!!F2112!!PVCCIN_CPU1_PWR_VR!!
S!@baseboard_fab2_lib.baseboard_fab2(sch_1):page208_i11@mstr_discrete.inductor(chips)!INDUCTOR_SM-0.12UH,IND,D92183-A!L1D2!//jf4cfls225.pdx.intel.com/apd_proj/ppg_lib/epg_masterlib/logical/mstr_discrete/inductor/chips/chips.prt!INDUCTOR!INDUCTOR_SM-0.12UH,IND,D92183-034!INDUCTOR!!!F2114!!PVCCIN_CPU1_PWR_VR!!
S!@baseboard_fab2_lib.baseboard_fab2(sch_1):page208_i20@mstr_discrete.inductor(chips)!INDUCTOR_SM-0.12UH,IND,D92183-A!L1D1!//jf4cfls225.pdx.intel.com/apd_proj/ppg_lib/epg_masterlib/logical/mstr_discrete/inductor/chips/chips.prt!INDUCTOR!INDUCTOR_SM-0.12UH,IND,D92183-034!INDUCTOR!!!F2115!!PVCCIN_CPU1_PWR_VR!!
S!@baseboard_fab2_lib.baseboard_fab2(sch_1):page209_i40@mstr_discrete.inductor(chips)!INDUCTOR_SM-0.12UH,IND,D92183-A!L1C2!//jf4cfls225.pdx.intel.com/apd_proj/ppg_lib/epg_masterlib/logical/mstr_discrete/inductor/chips/chips.prt!INDUCTOR!INDUCTOR_SM-0.12UH,IND,D92183-034!INDUCTOR!!!F2116!!PVCCIN_CPU1_PWR_VR!!
S!@baseboard_fab2_lib.baseboard_fab2(sch_1):page239_i14@mstr_discrete.res(chips)!RES_0402-12K,1%,1/16W,CHIP,G21A!R9F31!//jf4cfls225.pdx.intel.com/apd_proj/ppg_lib/epg_masterlib/logical/mstr_discrete/res/chips/chips.prt!RES!RES_0402-12K,1%,1/16W,CHIP,G21796-264!RES!!!F1106!!P1V538_BMC_STBY_VR!!
S!@baseboard_fab2_lib.baseboard_fab2(sch_1):page238_i40@mstr_vreg.rt9059(chips)!RT9059_DFN-IC,H65765-001!EU9F1!//jf4cfls225.pdx.intel.com/apd_proj/ppg_lib/epg_masterlib/logical/mstr_vreg/rt9059/chips/chips.prt!RT9059!RT9059_DFN-IC,H65765-001!RT9059_DFN!!!F244!!P1V26_BMC_STBY_VR!!
S!@baseboard_fab2_lib.baseboard_fab2(sch_1):page237_i86@mstr_vreg.rt9059(chips)!RT9059_DFN-IC,H65765-001!EU8A2!//jf4cfls225.pdx.intel.com/apd_proj/ppg_lib/epg_masterlib/logical/mstr_vreg/rt9059/chips/chips.prt!RT9059!RT9059_DFN-IC,H65765-001!RT9059_DFN!!!F245!!P1V8_PCH_STBY_VR!!
S!@baseboard_fab2_lib.baseboard_fab2(sch_1):page239_i70@mstr_vreg.rt9059(chips)!RT9059_DFN-IC,H65765-001!EU9F2!//jf4cfls225.pdx.intel.com/apd_proj/ppg_lib/epg_masterlib/logical/mstr_vreg/rt9059/chips/chips.prt!RT9059!RT9059_DFN-IC,H65765-001!RT9059_DFN!!!F243!!!!
S!@baseboard_fab2_lib.baseboard_fab2(sch_1):page196_i70@mstr_analog.adm1085(chips)!ADM1085_SMT-IC,H46130-001!U7D3!//jf4cfls225.pdx.intel.com/apd_proj/ppg_lib/epg_masterlib/logical/mstr_analog/adm1085/chips/chips.prt!ADM1085!ADM1085_SMT-IC,H46130-001!ADM1085_SMT!!!F4198!!V_SUPER!!
S!@baseboard_fab2_lib.baseboard_fab2(sch_1):page196_i60@mstr_discrete.cap(chips)!CAP_0402-0.047UF,25V,10%,X7R,AA!C3P45!//jf4cfls225.pdx.intel.com/apd_proj/ppg_lib/epg_masterlib/logical/mstr_discrete/cap/chips/chips.prt!CAP!CAP_0402-0.047UF,25V,10%,X7R,A36096-090!CAP_0402!!!F4086!!V_SUPER!!
S!@baseboard_fab2_lib.baseboard_fab2(sch_1):page196_i105@mstr_discrete.cap(chips)!CAP_0402-0.1UF,16V,10%,X7R,A36A!C8D4!//jf4cfls225.pdx.intel.com/apd_proj/ppg_lib/epg_masterlib/logical/mstr_discrete/cap/chips/chips.prt!CAP!CAP_0402-0.1UF,16V,10%,X7R,A36096-030!CAP_0402!!!F4077!!V_SUPER!!
S!@baseboard_fab2_lib.baseboard_fab2(sch_1):page163_i10@mstr_discrete.cap(chips)!CAP_0402-0.1UF,16V,10%,X7R,A36A!C9M8!//jf4cfls225.pdx.intel.com/apd_proj/ppg_lib/epg_masterlib/logical/mstr_discrete/cap/chips/chips.prt!CAP!CAP_0402-0.1UF,16V,10%,X7R,A36096-030!CAP_0402!!!F4078!!SMB_PE_HP_CPU1!!
S!@baseboard_fab2_lib.baseboard_fab2(sch_1):page163_i12@mstr_discrete.cap(chips)!CAP_0402-0.1UF,16V,10%,X7R,A36A!C9M7!//jf4cfls225.pdx.intel.com/apd_proj/ppg_lib/epg_masterlib/logical/mstr_discrete/cap/chips/chips.prt!CAP!CAP_0402-0.1UF,16V,10%,X7R,A36096-030!CAP_0402!!!F4079!!SMB_PE_HP_CPU1!!
S!@baseboard_fab2_lib.baseboard_fab2(sch_1):page196_i94@mstr_discrete.cap(chips)!CAP_0402-0.1UF,16V,10%,X7R,A36A!C8E3!//jf4cfls225.pdx.intel.com/apd_proj/ppg_lib/epg_masterlib/logical/mstr_discrete/cap/chips/chips.prt!CAP!CAP_0402-0.1UF,16V,10%,X7R,A36096-030!CAP_0402!!!F4080!!V_SUPER!!
S!@baseboard_fab2_lib.baseboard_fab2(sch_1):page196_i81@mstr_discrete.cap(chips)!CAP_0402-0.1UF,16V,10%,X7R,A36A!C1L16!//jf4cfls225.pdx.intel.com/apd_proj/ppg_lib/epg_masterlib/logical/mstr_discrete/cap/chips/chips.prt!CAP!CAP_0402-0.1UF,16V,10%,X7R,A36096-030!CAP_0402!!!F4082!!V_SUPER!!
S!@baseboard_fab2_lib.baseboard_fab2(sch_1):page196_i72@mstr_discrete.cap(chips)!CAP_0402-0.1UF,16V,10%,X7R,A36A!C3P46!//jf4cfls225.pdx.intel.com/apd_proj/ppg_lib/epg_masterlib/logical/mstr_discrete/cap/chips/chips.prt!CAP!CAP_0402-0.1UF,16V,10%,X7R,A36096-030!CAP_0402!!!F4081!!V_SUPER!!
S!@baseboard_fab2_lib.baseboard_fab2(sch_1):page156_i331@mstr_discrete.res(chips)!RES_0402-3.32K,1%,1/16W,EMPTY,A!R3P54!//jf4cfls225.pdx.intel.com/apd_proj/ppg_lib/epg_masterlib/logical/mstr_discrete/res/chips/chips.prt!RES!RES_0402-3.32K,1%,1/16W,EMPTY,G21796-027!RES!!!F768!!CPU0!!
S!@baseboard_fab2_lib.baseboard_fab2(sch_1):page156_i336@mstr_discrete.res(chips)!RES_0402-3.32K,1%,1/16W,EMPTY,A!R1C35!//jf4cfls225.pdx.intel.com/apd_proj/ppg_lib/epg_masterlib/logical/mstr_discrete/res/chips/chips.prt!RES!RES_0402-3.32K,1%,1/16W,EMPTY,G21796-027!RES!!!F767!!CPU1!!
S!@baseboard_fab2_lib.baseboard_fab2(sch_1):page140_i14@mstr_discrete.res(chips)!RES_0402-3.32K,1%,1/16W,EMPTY,A!R1R6!//jf4cfls225.pdx.intel.com/apd_proj/ppg_lib/epg_masterlib/logical/mstr_discrete/res/chips/chips.prt!RES!RES_0402-3.32K,1%,1/16W,EMPTY,G21796-027!RES!!!F769!!NIC_SPRV!!
S!@baseboard_fab2_lib.baseboard_fab2(sch_1):page169_i114@mstr_discrete.res(chips)!RES_0402-8.2K,1%,1/16W,CHIP,G2A!R1U38!//jf4cfls225.pdx.intel.com/apd_proj/ppg_lib/epg_masterlib/logical/mstr_discrete/res/chips/chips.prt!RES!RES_0402-8.2K,1%,1/16W,CHIP,G21796-345!RES!!!F293!!BMC_VOLT_MONITOR!!
S!@baseboard_fab2_lib.baseboard_fab2(sch_1):page169_i149@mstr_discrete.res(chips)!RES_0402-8.2K,1%,1/16W,CHIP,G2A!R1U27!//jf4cfls225.pdx.intel.com/apd_proj/ppg_lib/epg_masterlib/logical/mstr_discrete/res/chips/chips.prt!RES!RES_0402-8.2K,1%,1/16W,CHIP,G21796-345!RES!!!F294!!BMC_VOLT_MONITOR!!
S!@baseboard_fab2_lib.baseboard_fab2(sch_1):page144_i461@mstr_discrete.res(chips)!RES_0402-8.2K,1%,1/16W,CHIP,G2A!R1T25!//jf4cfls225.pdx.intel.com/apd_proj/ppg_lib/epg_masterlib/logical/mstr_discrete/res/chips/chips.prt!RES!RES_0402-8.2K,1%,1/16W,CHIP,G21796-345!RES!!!F295!!BMC!!
S!@baseboard_fab2_lib.baseboard_fab2(sch_1):page185_i95@mstr_discrete.cap(chips)!CAP_0402LF-0.01UF,25V,10%,EMPTA!C8F6!//jf4cfls225.pdx.intel.com/apd_proj/ppg_lib/epg_masterlib/logical/mstr_discrete/cap/chips/chips.prt!CAP!CAP_0402LF-0.01UF,25V,10%,EMPTY,A36096-045!CAP!!!F3607!!M_2!!
S!@baseboard_fab2_lib.baseboard_fab2(sch_1):page185_i97@mstr_discrete.cap(chips)!CAP_0402LF-0.01UF,25V,10%,EMPTA!C8F11!//jf4cfls225.pdx.intel.com/apd_proj/ppg_lib/epg_masterlib/logical/mstr_discrete/cap/chips/chips.prt!CAP!CAP_0402LF-0.01UF,25V,10%,EMPTY,A36096-045!CAP!!!F3606!!M_2!!
S!@baseboard_fab2_lib.baseboard_fab2(sch_1):page185_i99@mstr_discrete.cap(chips)!CAP_0402LF-0.01UF,25V,10%,EMPTA!C8F13!//jf4cfls225.pdx.intel.com/apd_proj/ppg_lib/epg_masterlib/logical/mstr_discrete/cap/chips/chips.prt!CAP!CAP_0402LF-0.01UF,25V,10%,EMPTY,A36096-045!CAP!!!F3605!!M_2!!
S!@baseboard_fab2_lib.baseboard_fab2(sch_1):page185_i90@mstr_discrete.cap(chips)!CAP_0402LF-0.01UF,25V,10%,EMPTA!C8F15!//jf4cfls225.pdx.intel.com/apd_proj/ppg_lib/epg_masterlib/logical/mstr_discrete/cap/chips/chips.prt!CAP!CAP_0402LF-0.01UF,25V,10%,EMPTY,A36096-045!CAP!!!F3604!!M_2!!
S!@baseboard_fab2_lib.baseboard_fab2(sch_1):page176_i51@mstr_discrete.choke_4pin(chips)!CHOKE_4PIN_SM_B-67 OHM,EMPTY,7A!L1L1!//jf4cfls225.pdx.intel.com/apd_proj/ppg_lib/epg_masterlib/logical/mstr_discrete/choke_4pin/chips/chips.prt!CHOKE_4PIN!CHOKE_4PIN_SM_B-67 OHM,EMPTY,752402-028!CHOKE_4PIN_SM_B!!!F2260!!USB_REAR!!
S!@baseboard_fab2_lib.baseboard_fab2(sch_1):page176_i62@mstr_discrete.choke_4pin(chips)!CHOKE_4PIN_SM_B-67 OHM,EMPTY,7A!L1M1!//jf4cfls225.pdx.intel.com/apd_proj/ppg_lib/epg_masterlib/logical/mstr_discrete/choke_4pin/chips/chips.prt!CHOKE_4PIN!CHOKE_4PIN_SM_B-67 OHM,EMPTY,752402-028!CHOKE_4PIN_SM_B!!!F2259!!USB_REAR!!
S!@baseboard_fab2_lib.baseboard_fab2(sch_1):page232_i218@mstr_discrete.res(chips)!RES_0402-2.2,5%,1/16W,EMPTY,G2A!R7A15!//jf4cfls225.pdx.intel.com/apd_proj/ppg_lib/epg_masterlib/logical/mstr_discrete/res/chips/chips.prt!RES!RES_0402-2.2,5%,1/16W,EMPTY,G21497-016!RES!!!F1032!!PVPP_KLM_VR!!
S!@baseboard_fab2_lib.baseboard_fab2(sch_1):page233_i208@mstr_discrete.res(chips)!RES_0402-2.2,5%,1/16W,EMPTY,G2A!R4F6!//jf4cfls225.pdx.intel.com/apd_proj/ppg_lib/epg_masterlib/logical/mstr_discrete/res/chips/chips.prt!RES!RES_0402-2.2,5%,1/16W,EMPTY,G21497-016!RES!!!F1033!!PVPP_KLM_VR!!
S!@baseboard_fab2_lib.baseboard_fab2(sch_1):page234_i162@mstr_discrete.res(chips)!RES_0402-2.2,5%,1/16W,EMPTY,G2A!R4A7!//jf4cfls225.pdx.intel.com/apd_proj/ppg_lib/epg_masterlib/logical/mstr_discrete/res/chips/chips.prt!RES!RES_0402-2.2,5%,1/16W,EMPTY,G21497-016!RES!!!F1034!!PVPP_KLM_VR!!
S!@baseboard_fab2_lib.baseboard_fab2(sch_1):page231_i174@mstr_discrete.res(chips)!RES_0402-2.2,5%,1/16W,EMPTY,G2A!R7F7!//jf4cfls225.pdx.intel.com/apd_proj/ppg_lib/epg_masterlib/logical/mstr_discrete/res/chips/chips.prt!RES!RES_0402-2.2,5%,1/16W,EMPTY,G21497-016!RES!!!F1031!!PVPP_KLM_VR!!
S!@baseboard_fab2_lib.baseboard_fab2(sch_1):page240_i148@mstr_discrete.res(chips)!RES_0402-2.2,5%,1/16W,EMPTY,G2A!R8F3!//jf4cfls225.pdx.intel.com/apd_proj/ppg_lib/epg_masterlib/logical/mstr_discrete/res/chips/chips.prt!RES!RES_0402-2.2,5%,1/16W,EMPTY,G21497-016!RES!!!F1030!!P3V3_STBY_VR!!
S!@baseboard_fab2_lib.baseboard_fab2(sch_1):page158_i131@mstr_discrete.res(chips)!RES_0402-330,5%,1/16W,CHIP,G21A!R1L43!//jf4cfls225.pdx.intel.com/apd_proj/ppg_lib/epg_masterlib/logical/mstr_discrete/res/chips/chips.prt!RES!RES_0402-330,5%,1/16W,CHIP,G21497-028!RES!!!F665!!UART_MUX!!
S!@baseboard_fab2_lib.baseboard_fab2(sch_1):page158_i136@mstr_discrete.res(chips)!RES_0402-330,5%,1/16W,CHIP,G21A!R1L44!//jf4cfls225.pdx.intel.com/apd_proj/ppg_lib/epg_masterlib/logical/mstr_discrete/res/chips/chips.prt!RES!RES_0402-330,5%,1/16W,CHIP,G21497-028!RES!!!F664!!UART_MUX!!
S!@baseboard_fab2_lib.baseboard_fab2(sch_1):page240_i152@mstr_discrete.res(chips)!RES_0402-1.0K,0.1%,1/16W,CHIP,A!R2T4!//jf4cfls225.pdx.intel.com/apd_proj/ppg_lib/epg_masterlib/logical/mstr_discrete/res/chips/chips.prt!RES!RES_0402-1.0K,0.1%,1/16W,CHIP,G85996-004!RES!!!F1407!!P3V3_STBY_VR!!
S!@baseboard_fab2_lib.baseboard_fab2(sch_1):page241_i9@mstr_discrete.res(chips)!RES_0402-1.0K,0.1%,1/16W,CHIP,A!R8E18!//jf4cfls225.pdx.intel.com/apd_proj/ppg_lib/epg_masterlib/logical/mstr_discrete/res/chips/chips.prt!RES!RES_0402-1.0K,0.1%,1/16W,CHIP,G85996-004!RES!!!F1402!!P5V_STBY_VR!!
S!@baseboard_fab2_lib.baseboard_fab2(sch_1):page231_i218@mstr_discrete.res(chips)!RES_0402-1.0K,0.1%,1/16W,CHIP,A!R7F17!//jf4cfls225.pdx.intel.com/apd_proj/ppg_lib/epg_masterlib/logical/mstr_discrete/res/chips/chips.prt!RES!RES_0402-1.0K,0.1%,1/16W,CHIP,G85996-004!RES!!!F1403!!PVPP_KLM_VR!!
S!@baseboard_fab2_lib.baseboard_fab2(sch_1):page232_i298@mstr_discrete.res(chips)!RES_0402-1.0K,0.1%,1/16W,CHIP,A!R7B18!//jf4cfls225.pdx.intel.com/apd_proj/ppg_lib/epg_masterlib/logical/mstr_discrete/res/chips/chips.prt!RES!RES_0402-1.0K,0.1%,1/16W,CHIP,G85996-004!RES!!!F1404!!PVPP_KLM_VR!!
S!@baseboard_fab2_lib.baseboard_fab2(sch_1):page233_i266@mstr_discrete.res(chips)!RES_0402-1.0K,0.1%,1/16W,CHIP,A!R4G10!//jf4cfls225.pdx.intel.com/apd_proj/ppg_lib/epg_masterlib/logical/mstr_discrete/res/chips/chips.prt!RES!RES_0402-1.0K,0.1%,1/16W,CHIP,G85996-004!RES!!!F1405!!PVPP_KLM_VR!!
S!@baseboard_fab2_lib.baseboard_fab2(sch_1):page234_i219@mstr_discrete.res(chips)!RES_0402-1.0K,0.1%,1/16W,CHIP,A!R4B9!//jf4cfls225.pdx.intel.com/apd_proj/ppg_lib/epg_masterlib/logical/mstr_discrete/res/chips/chips.prt!RES!RES_0402-1.0K,0.1%,1/16W,CHIP,G85996-004!RES!!!F1406!!PVPP_KLM_VR!!
S!@baseboard_fab2_lib.baseboard_fab2(sch_1):page118_i96@mstr_discrete.res(chips)!RES_0402-1.0K,0.1%,1/16W,CHIP,A!R2N4!//jf4cfls225.pdx.intel.com/apd_proj/ppg_lib/epg_masterlib/logical/mstr_discrete/res/chips/chips.prt!RES!RES_0402-1.0K,0.1%,1/16W,CHIP,G85996-004!RES!!!F1408!!SB!!
S!@baseboard_fab2_lib.baseboard_fab2(sch_1):page118_i99@mstr_discrete.res(chips)!RES_0402-1.0K,0.1%,1/16W,CHIP,A!R2M6!//jf4cfls225.pdx.intel.com/apd_proj/ppg_lib/epg_masterlib/logical/mstr_discrete/res/chips/chips.prt!RES!RES_0402-1.0K,0.1%,1/16W,CHIP,G85996-004!RES!!!F1409!!SB!!
S!@baseboard_fab2_lib.baseboard_fab2(sch_1):page241_i51@mstr_discrete.res(chips)!RES_0402-1.37K,1%,1/16W,CHIP,GA!R7E16!//jf4cfls225.pdx.intel.com/apd_proj/ppg_lib/epg_masterlib/logical/mstr_discrete/res/chips/chips.prt!RES!RES_0402-1.37K,1%,1/16W,CHIP,G21796-095!RES!!!F1395!!P5V_STBY_VR!!
S!@baseboard_fab2_lib.baseboard_fab2(sch_1):page156_i320@mstr_discrete.res(chips)!RES_0402-10.0K,1%,1/16W,CHIP,GA!R1C34!//jf4cfls225.pdx.intel.com/apd_proj/ppg_lib/epg_masterlib/logical/mstr_discrete/res/chips/chips.prt!RES!RES_0402-10.0K,1%,1/16W,CHIP,G21796-016!RES!!!F1233!!CPU1!!
S!@baseboard_fab2_lib.baseboard_fab2(sch_1):page145_i252@mstr_discrete.res(chips)!RES_0402-10.0K,1%,1/16W,CHIP,GA!R9F61!//jf4cfls225.pdx.intel.com/apd_proj/ppg_lib/epg_masterlib/logical/mstr_discrete/res/chips/chips.prt!RES!RES_0402-10.0K,1%,1/16W,CHIP,G21796-016!RES!!!F1234!!BMC!!
S!@baseboard_fab2_lib.baseboard_fab2(sch_1):page176_i111@mstr_discrete.res(chips)!RES_0402-10.0K,1%,1/16W,CHIP,GA!R1M25!//jf4cfls225.pdx.intel.com/apd_proj/ppg_lib/epg_masterlib/logical/mstr_discrete/res/chips/chips.prt!RES!RES_0402-10.0K,1%,1/16W,CHIP,G21796-016!RES!!!F1235!!USB_REAR!!
S!@baseboard_fab2_lib.baseboard_fab2(sch_1):page196_i121@mstr_discrete.res(chips)!RES_0402-10.0K,1%,1/16W,CHIP,GA!R2P18!//jf4cfls225.pdx.intel.com/apd_proj/ppg_lib/epg_masterlib/logical/mstr_discrete/res/chips/chips.prt!RES!RES_0402-10.0K,1%,1/16W,CHIP,G21796-016!RES!!!F1237!!V_SUPER!!
S!@baseboard_fab2_lib.baseboard_fab2(sch_1):page196_i120@mstr_discrete.res(chips)!RES_0402-10.0K,1%,1/16W,CHIP,GA!R8D41!//jf4cfls225.pdx.intel.com/apd_proj/ppg_lib/epg_masterlib/logical/mstr_discrete/res/chips/chips.prt!RES!RES_0402-10.0K,1%,1/16W,CHIP,G21796-016!RES!!!F1238!!V_SUPER!!
S!@baseboard_fab2_lib.baseboard_fab2(sch_1):page196_i122@mstr_discrete.res(chips)!RES_0402-10.0K,1%,1/16W,CHIP,GA!R2P21!//jf4cfls225.pdx.intel.com/apd_proj/ppg_lib/epg_masterlib/logical/mstr_discrete/res/chips/chips.prt!RES!RES_0402-10.0K,1%,1/16W,CHIP,G21796-016!RES!!!F1236!!V_SUPER!!
S!@baseboard_fab2_lib.baseboard_fab2(sch_1):page115_i114@mstr_discrete.res(chips)!RES_0402-10.0K,1%,1/16W,CHIP,GA!R8B32!//jf4cfls225.pdx.intel.com/apd_proj/ppg_lib/epg_masterlib/logical/mstr_discrete/res/chips/chips.prt!RES!RES_0402-10.0K,1%,1/16W,CHIP,G21796-016!RES!!!F1239!!!!
S!@baseboard_fab2_lib.baseboard_fab2(sch_1):page185_i136@mstr_discrete.res(chips)!RES_0402-10.0K,1%,1/16W,CHIP,GA!R8F36!//jf4cfls225.pdx.intel.com/apd_proj/ppg_lib/epg_masterlib/logical/mstr_discrete/res/chips/chips.prt!RES!RES_0402-10.0K,1%,1/16W,CHIP,G21796-016!RES!!!F1332!!M_2!!
S!@baseboard_fab2_lib.baseboard_fab2(sch_1):page139_i213@mstr_discrete.res(chips)!RES_0402-10.0K,1%,1/16W,CHIP,GA!R1R12!//jf4cfls225.pdx.intel.com/apd_proj/ppg_lib/epg_masterlib/logical/mstr_discrete/res/chips/chips.prt!RES!RES_0402-10.0K,1%,1/16W,CHIP,G21796-016!RES!!!F1322!!NIC_SPRV!!
S!@baseboard_fab2_lib.baseboard_fab2(sch_1):page116_i230@mstr_discrete.res(chips)!RES_0402-10.0K,1%,1/16W,CHIP,GA!R7B7!//jf4cfls225.pdx.intel.com/apd_proj/ppg_lib/epg_masterlib/logical/mstr_discrete/res/chips/chips.prt!RES!RES_0402-10.0K,1%,1/16W,CHIP,G21796-016!RES!!!F1293!!SB!!
S!@baseboard_fab2_lib.baseboard_fab2(sch_1):page116_i229@mstr_discrete.res(chips)!RES_0402-10.0K,1%,1/16W,CHIP,GA!R7B8!//jf4cfls225.pdx.intel.com/apd_proj/ppg_lib/epg_masterlib/logical/mstr_discrete/res/chips/chips.prt!RES!RES_0402-10.0K,1%,1/16W,CHIP,G21796-016!RES!!!F1292!!SB!!
S!@baseboard_fab2_lib.baseboard_fab2(sch_1):page121_i73@mstr_discrete.res(chips)!RES_0402-10.0K,1%,1/16W,CHIP,GA!R7C20!//jf4cfls225.pdx.intel.com/apd_proj/ppg_lib/epg_masterlib/logical/mstr_discrete/res/chips/chips.prt!RES!RES_0402-10.0K,1%,1/16W,CHIP,G21796-016!RES!!!F1288!!NIC_SPRV!!
S!@baseboard_fab2_lib.baseboard_fab2(sch_1):page118_i144@mstr_discrete.res(chips)!RES_0402-10.0K,1%,1/16W,CHIP,GA!R7C23!//jf4cfls225.pdx.intel.com/apd_proj/ppg_lib/epg_masterlib/logical/mstr_discrete/res/chips/chips.prt!RES!RES_0402-10.0K,1%,1/16W,CHIP,G21796-016!RES!!!F1286!!SB!!
S!@baseboard_fab2_lib.baseboard_fab2(sch_1):page189_i53@mstr_discrete.res(chips)!RES_0402-10.0K,1%,1/16W,CHIP,GA!R7G22!//jf4cfls225.pdx.intel.com/apd_proj/ppg_lib/epg_masterlib/logical/mstr_discrete/res/chips/chips.prt!RES!RES_0402-10.0K,1%,1/16W,CHIP,G21796-016!RES!!!F1273!!BMC_DEBUG_HEADER!!
S!@baseboard_fab2_lib.baseboard_fab2(sch_1):page189_i51@mstr_discrete.res(chips)!RES_0402-10.0K,1%,1/16W,CHIP,GA!R7G23!//jf4cfls225.pdx.intel.com/apd_proj/ppg_lib/epg_masterlib/logical/mstr_discrete/res/chips/chips.prt!RES!RES_0402-10.0K,1%,1/16W,CHIP,G21796-016!RES!!!F1272!!BMC_DEBUG_HEADER!!
S!@baseboard_fab2_lib.baseboard_fab2(sch_1):page189_i50@mstr_discrete.res(chips)!RES_0402-10.0K,1%,1/16W,CHIP,GA!R8G20!//jf4cfls225.pdx.intel.com/apd_proj/ppg_lib/epg_masterlib/logical/mstr_discrete/res/chips/chips.prt!RES!RES_0402-10.0K,1%,1/16W,CHIP,G21796-016!RES!!!F1258!!BMC_DEBUG_HEADER!!
S!@baseboard_fab2_lib.baseboard_fab2(sch_1):page133_i267@mstr_discrete.res(chips)!RES_0402-10.0K,1%,1/16W,CHIP,GA!R2N9!//jf4cfls225.pdx.intel.com/apd_proj/ppg_lib/epg_masterlib/logical/mstr_discrete/res/chips/chips.prt!RES!RES_0402-10.0K,1%,1/16W,CHIP,G21796-016!RES!!!F1316!!SB!!
S!@baseboard_fab2_lib.baseboard_fab2(sch_1):page89_i34@mstr_discrete.res(chips)!RES_0402-10.0K,1%,1/16W,CHIP,GA!R8D30!//jf4cfls225.pdx.intel.com/apd_proj/ppg_lib/epg_masterlib/logical/mstr_discrete/res/chips/chips.prt!RES!RES_0402-10.0K,1%,1/16W,CHIP,G21796-016!RES!!!F1266!!NV_DIMM!!
S!@baseboard_fab2_lib.baseboard_fab2(sch_1):page89_i7@mstr_discrete.res(chips)!RES_0402-10.0K,1%,1/16W,CHIP,GA!R6F3!//jf4cfls225.pdx.intel.com/apd_proj/ppg_lib/epg_masterlib/logical/mstr_discrete/res/chips/chips.prt!RES!RES_0402-10.0K,1%,1/16W,CHIP,G21796-016!RES!!!F1296!!NV_DIMM!!
S!@baseboard_fab2_lib.baseboard_fab2(sch_1):page145_i127@mstr_discrete.res(chips)!RES_0402-10.0K,1%,1/16W,CHIP,GA!R1U7!//jf4cfls225.pdx.intel.com/apd_proj/ppg_lib/epg_masterlib/logical/mstr_discrete/res/chips/chips.prt!RES!RES_0402-10.0K,1%,1/16W,CHIP,G21796-016!RES!!!F1318!!BMC!!
S!@baseboard_fab2_lib.baseboard_fab2(sch_1):page200_i215@mstr_discrete.res(chips)!RES_0402-10.0K,1%,1/16W,CHIP,GA!R9P5!//jf4cfls225.pdx.intel.com/apd_proj/ppg_lib/epg_masterlib/logical/mstr_discrete/res/chips/chips.prt!RES!RES_0402-10.0K,1%,1/16W,CHIP,G21796-016!RES!!!F1244!!HOT_SWAP!!
S!@baseboard_fab2_lib.baseboard_fab2(sch_1):page134_i34@mstr_discrete.res(chips)!RES_0402-10.0K,1%,1/16W,CHIP,GA!R2P19!//jf4cfls225.pdx.intel.com/apd_proj/ppg_lib/epg_masterlib/logical/mstr_discrete/res/chips/chips.prt!RES!RES_0402-10.0K,1%,1/16W,CHIP,G21796-016!RES!!!F1281!!CPLD!!
S!@baseboard_fab2_lib.baseboard_fab2(sch_1):page177_i9@mstr_discrete.res(chips)!RES_0402-10.0K,1%,1/16W,CHIP,GA!R1M11!//jf4cfls225.pdx.intel.com/apd_proj/ppg_lib/epg_masterlib/logical/mstr_discrete/res/chips/chips.prt!RES!RES_0402-10.0K,1%,1/16W,CHIP,G21796-016!RES!!!F1326!!MIO_CHASSIS!!
S!@baseboard_fab2_lib.baseboard_fab2(sch_1):page177_i8@mstr_discrete.res(chips)!RES_0402-10.0K,1%,1/16W,CHIP,GA!R1M12!//jf4cfls225.pdx.intel.com/apd_proj/ppg_lib/epg_masterlib/logical/mstr_discrete/res/chips/chips.prt!RES!RES_0402-10.0K,1%,1/16W,CHIP,G21796-016!RES!!!F1325!!MIO_CHASSIS!!
S!@baseboard_fab2_lib.baseboard_fab2(sch_1):page97_i80@mstr_discrete.res(chips)!RES_0402-10.0K,1%,1/16W,CHIP,GA!R4P5!//jf4cfls225.pdx.intel.com/apd_proj/ppg_lib/epg_masterlib/logical/mstr_discrete/res/chips/chips.prt!RES!RES_0402-10.0K,1%,1/16W,CHIP,G21796-016!RES!!!F1300!!CPU0!!
S!@baseboard_fab2_lib.baseboard_fab2(sch_1):page97_i81@mstr_discrete.res(chips)!RES_0402-10.0K,1%,1/16W,CHIP,GA!R7P13!//jf4cfls225.pdx.intel.com/apd_proj/ppg_lib/epg_masterlib/logical/mstr_discrete/res/chips/chips.prt!RES!RES_0402-10.0K,1%,1/16W,CHIP,G21796-016!RES!!!F1271!!CPU1!!
S!@baseboard_fab2_lib.baseboard_fab2(sch_1):page154_i128@mstr_discrete.res(chips)!RES_0402-10.0K,1%,1/16W,CHIP,GA!R1U6!//jf4cfls225.pdx.intel.com/apd_proj/ppg_lib/epg_masterlib/logical/mstr_discrete/res/chips/chips.prt!RES!RES_0402-10.0K,1%,1/16W,CHIP,G21796-016!RES!!!F1319!!SB_BMC_BPI_MUX!!
S!@baseboard_fab2_lib.baseboard_fab2(sch_1):page147_i142@mstr_discrete.res(chips)!RES_0402-10.0K,1%,1/16W,CHIP,GA!R2N13!//jf4cfls225.pdx.intel.com/apd_proj/ppg_lib/epg_masterlib/logical/mstr_discrete/res/chips/chips.prt!RES!RES_0402-10.0K,1%,1/16W,CHIP,G21796-016!RES!!!F1315!!BMC!!
S!@baseboard_fab2_lib.baseboard_fab2(sch_1):page153_i178@mstr_discrete.res(chips)!RES_0402-10.0K,1%,1/16W,CHIP,GA!R3T12!//jf4cfls225.pdx.intel.com/apd_proj/ppg_lib/epg_masterlib/logical/mstr_discrete/res/chips/chips.prt!RES!RES_0402-10.0K,1%,1/16W,CHIP,G21796-016!RES!!!F1305!!SB_SPI!!
S!@baseboard_fab2_lib.baseboard_fab2(sch_1):page153_i174@mstr_discrete.res(chips)!RES_0402-10.0K,1%,1/16W,CHIP,GA!R3T4!//jf4cfls225.pdx.intel.com/apd_proj/ppg_lib/epg_masterlib/logical/mstr_discrete/res/chips/chips.prt!RES!RES_0402-10.0K,1%,1/16W,CHIP,G21796-016!RES!!!F1306!!SB_SPI!!
S!@baseboard_fab2_lib.baseboard_fab2(sch_1):page200_i191@mstr_discrete.res(chips)!RES_0402-10.0K,1%,1/16W,CHIP,GA!R1D23!//jf4cfls225.pdx.intel.com/apd_proj/ppg_lib/epg_masterlib/logical/mstr_discrete/res/chips/chips.prt!RES!RES_0402-10.0K,1%,1/16W,CHIP,G21796-016!RES!!!F1327!!HOT_SWAP!!
S!@baseboard_fab2_lib.baseboard_fab2(sch_1):page200_i189@mstr_discrete.res(chips)!RES_0402-10.0K,1%,1/16W,CHIP,GA!R1D10!//jf4cfls225.pdx.intel.com/apd_proj/ppg_lib/epg_masterlib/logical/mstr_discrete/res/chips/chips.prt!RES!RES_0402-10.0K,1%,1/16W,CHIP,G21796-016!RES!!!F1331!!HOT_SWAP!!
S!@baseboard_fab2_lib.baseboard_fab2(sch_1):page200_i192@mstr_discrete.res(chips)!RES_0402-10.0K,1%,1/16W,CHIP,GA!R9P10!//jf4cfls225.pdx.intel.com/apd_proj/ppg_lib/epg_masterlib/logical/mstr_discrete/res/chips/chips.prt!RES!RES_0402-10.0K,1%,1/16W,CHIP,G21796-016!RES!!!F1241!!HOT_SWAP!!
S!@baseboard_fab2_lib.baseboard_fab2(sch_1):page200_i108@mstr_discrete.res(chips)!RES_0402-10.0K,1%,1/16W,CHIP,GA!R9P11!//jf4cfls225.pdx.intel.com/apd_proj/ppg_lib/epg_masterlib/logical/mstr_discrete/res/chips/chips.prt!RES!RES_0402-10.0K,1%,1/16W,CHIP,G21796-016!RES!!!F1240!!HOT_SWAP!!
S!@baseboard_fab2_lib.baseboard_fab2(sch_1):page200_i174@mstr_discrete.res(chips)!RES_0402-10.0K,1%,1/16W,CHIP,GA!R1D12!//jf4cfls225.pdx.intel.com/apd_proj/ppg_lib/epg_masterlib/logical/mstr_discrete/res/chips/chips.prt!RES!RES_0402-10.0K,1%,1/16W,CHIP,G21796-016!RES!!!F1330!!HOT_SWAP!!
S!@baseboard_fab2_lib.baseboard_fab2(sch_1):page200_i175@mstr_discrete.res(chips)!RES_0402-10.0K,1%,1/16W,CHIP,GA!R1D19!//jf4cfls225.pdx.intel.com/apd_proj/ppg_lib/epg_masterlib/logical/mstr_discrete/res/chips/chips.prt!RES!RES_0402-10.0K,1%,1/16W,CHIP,G21796-016!RES!!!F1329!!HOT_SWAP!!
S!@baseboard_fab2_lib.baseboard_fab2(sch_1):page200_i146@mstr_discrete.res(chips)!RES_0402-10.0K,1%,1/16W,CHIP,GA!R9P9!//jf4cfls225.pdx.intel.com/apd_proj/ppg_lib/epg_masterlib/logical/mstr_discrete/res/chips/chips.prt!RES!RES_0402-10.0K,1%,1/16W,CHIP,G21796-016!RES!!!F1242!!HOT_SWAP!!
S!@baseboard_fab2_lib.baseboard_fab2(sch_1):page200_i158@mstr_discrete.res(chips)!RES_0402-10.0K,1%,1/16W,CHIP,GA!R1D22!//jf4cfls225.pdx.intel.com/apd_proj/ppg_lib/epg_masterlib/logical/mstr_discrete/res/chips/chips.prt!RES!RES_0402-10.0K,1%,1/16W,CHIP,G21796-016!RES!!!F1328!!HOT_SWAP!!
S!@baseboard_fab2_lib.baseboard_fab2(sch_1):page136_i156@mstr_discrete.res(chips)!RES_0402-10.0K,1%,1/16W,CHIP,GA!R3T14!//jf4cfls225.pdx.intel.com/apd_proj/ppg_lib/epg_masterlib/logical/mstr_discrete/res/chips/chips.prt!RES!RES_0402-10.0K,1%,1/16W,CHIP,G21796-016!RES!!!F1280!!SB!!
S!@baseboard_fab2_lib.baseboard_fab2(sch_1):page233_i182@mstr_discrete.res(chips)!RES_0402-10.0K,1%,1/16W,CHIP,GA!R4G5!//jf4cfls225.pdx.intel.com/apd_proj/ppg_lib/epg_masterlib/logical/mstr_discrete/res/chips/chips.prt!RES!RES_0402-10.0K,1%,1/16W,CHIP,G21796-016!RES!!!F1303!!PVPP_KLM_VR!!
S!@baseboard_fab2_lib.baseboard_fab2(sch_1):page176_i105@mstr_discrete.res(chips)!RES_0402-10.0K,1%,1/16W,CHIP,GA!R1M24!//jf4cfls225.pdx.intel.com/apd_proj/ppg_lib/epg_masterlib/logical/mstr_discrete/res/chips/chips.prt!RES!RES_0402-10.0K,1%,1/16W,CHIP,G21796-016!RES!!!F1254!!USB_REAR!!
S!@baseboard_fab2_lib.baseboard_fab2(sch_1):page231_i136@mstr_discrete.res(chips)!RES_0402-10.0K,1%,1/16W,CHIP,GA!R7F14!//jf4cfls225.pdx.intel.com/apd_proj/ppg_lib/epg_masterlib/logical/mstr_discrete/res/chips/chips.prt!RES!RES_0402-10.0K,1%,1/16W,CHIP,G21796-016!RES!!!F1276!!PVPP_KLM_VR!!
S!@baseboard_fab2_lib.baseboard_fab2(sch_1):page240_i142@mstr_discrete.res(chips)!RES_0402-10.0K,1%,1/16W,CHIP,GA!R8E34!//jf4cfls225.pdx.intel.com/apd_proj/ppg_lib/epg_masterlib/logical/mstr_discrete/res/chips/chips.prt!RES!RES_0402-10.0K,1%,1/16W,CHIP,G21796-016!RES!!!F1262!!P3V3_STBY_VR!!
S!@baseboard_fab2_lib.baseboard_fab2(sch_1):page192_i41@mstr_discrete.res(chips)!RES_0402-10.0K,1%,1/16W,CHIP,GA!R2R3!//jf4cfls225.pdx.intel.com/apd_proj/ppg_lib/epg_masterlib/logical/mstr_discrete/res/chips/chips.prt!RES!RES_0402-10.0K,1%,1/16W,CHIP,G21796-016!RES!!!F1311!!CPLD!!
S!@baseboard_fab2_lib.baseboard_fab2(sch_1):page192_i38@mstr_discrete.res(chips)!RES_0402-10.0K,1%,1/16W,CHIP,GA!R7E5!//jf4cfls225.pdx.intel.com/apd_proj/ppg_lib/epg_masterlib/logical/mstr_discrete/res/chips/chips.prt!RES!RES_0402-10.0K,1%,1/16W,CHIP,G21796-016!RES!!!F1279!!CPLD!!
S!@baseboard_fab2_lib.baseboard_fab2(sch_1):page118_i128@mstr_discrete.res(chips)!RES_0402-10.0K,1%,1/16W,CHIP,GA!R2N6!//jf4cfls225.pdx.intel.com/apd_proj/ppg_lib/epg_masterlib/logical/mstr_discrete/res/chips/chips.prt!RES!RES_0402-10.0K,1%,1/16W,CHIP,G21796-016!RES!!!F1317!!SB!!
S!@baseboard_fab2_lib.baseboard_fab2(sch_1):page192_i33@mstr_discrete.res(chips)!RES_0402-10.0K,1%,1/16W,CHIP,GA!R7E6!//jf4cfls225.pdx.intel.com/apd_proj/ppg_lib/epg_masterlib/logical/mstr_discrete/res/chips/chips.prt!RES!RES_0402-10.0K,1%,1/16W,CHIP,G21796-016!RES!!!F1278!!CPLD!!
S!@baseboard_fab2_lib.baseboard_fab2(sch_1):page192_i34@mstr_discrete.res(chips)!RES_0402-10.0K,1%,1/16W,CHIP,GA!R2R1!//jf4cfls225.pdx.intel.com/apd_proj/ppg_lib/epg_masterlib/logical/mstr_discrete/res/chips/chips.prt!RES!RES_0402-10.0K,1%,1/16W,CHIP,G21796-016!RES!!!F1312!!CPLD!!
S!@baseboard_fab2_lib.baseboard_fab2(sch_1):page200_i149@mstr_discrete.res(chips)!RES_0402-10.0K,1%,1/16W,CHIP,GA!R9P6!//jf4cfls225.pdx.intel.com/apd_proj/ppg_lib/epg_masterlib/logical/mstr_discrete/res/chips/chips.prt!RES!RES_0402-10.0K,1%,1/16W,CHIP,G21796-016!RES!!!F1243!!HOT_SWAP!!
S!@baseboard_fab2_lib.baseboard_fab2(sch_1):page133_i297@mstr_discrete.res(chips)!RES_0402-10.0K,1%,1/16W,CHIP,GA!R7C5!//jf4cfls225.pdx.intel.com/apd_proj/ppg_lib/epg_masterlib/logical/mstr_discrete/res/chips/chips.prt!RES!RES_0402-10.0K,1%,1/16W,CHIP,G21796-016!RES!!!F1291!!SB_PU_PD!!
S!@baseboard_fab2_lib.baseboard_fab2(sch_1):page133_i296@mstr_discrete.res(chips)!RES_0402-10.0K,1%,1/16W,CHIP,GA!R7C8!//jf4cfls225.pdx.intel.com/apd_proj/ppg_lib/epg_masterlib/logical/mstr_discrete/res/chips/chips.prt!RES!RES_0402-10.0K,1%,1/16W,CHIP,G21796-016!RES!!!F1290!!SB_PU_PD!!
S!@baseboard_fab2_lib.baseboard_fab2(sch_1):page133_i295@mstr_discrete.res(chips)!RES_0402-10.0K,1%,1/16W,CHIP,GA!R7B6!//jf4cfls225.pdx.intel.com/apd_proj/ppg_lib/epg_masterlib/logical/mstr_discrete/res/chips/chips.prt!RES!RES_0402-10.0K,1%,1/16W,CHIP,G21796-016!RES!!!F1294!!SB_PU_PD!!
S!@baseboard_fab2_lib.baseboard_fab2(sch_1):page133_i237@mstr_discrete.res(chips)!RES_0402-10.0K,1%,1/16W,CHIP,GA!R7D12!//jf4cfls225.pdx.intel.com/apd_proj/ppg_lib/epg_masterlib/logical/mstr_discrete/res/chips/chips.prt!RES!RES_0402-10.0K,1%,1/16W,CHIP,G21796-016!RES!!!F1282!!SB!!
S!@baseboard_fab2_lib.baseboard_fab2(sch_1):page137_i67@mstr_discrete.res(chips)!RES_0402-10.0K,1%,1/16W,CHIP,GA!R7C13!//jf4cfls225.pdx.intel.com/apd_proj/ppg_lib/epg_masterlib/logical/mstr_discrete/res/chips/chips.prt!RES!RES_0402-10.0K,1%,1/16W,CHIP,G21796-016!RES!!!F1289!!SB!!
S!@baseboard_fab2_lib.baseboard_fab2(sch_1):page136_i147@mstr_discrete.res(chips)!RES_0402-10.0K,1%,1/16W,CHIP,GA!R2N28!//jf4cfls225.pdx.intel.com/apd_proj/ppg_lib/epg_masterlib/logical/mstr_discrete/res/chips/chips.prt!RES!RES_0402-10.0K,1%,1/16W,CHIP,G21796-016!RES!!!F1270!!SB!!
S!@baseboard_fab2_lib.baseboard_fab2(sch_1):page133_i355@mstr_discrete.res(chips)!RES_0402-10.0K,1%,1/16W,CHIP,GA!R8E3!//jf4cfls225.pdx.intel.com/apd_proj/ppg_lib/epg_masterlib/logical/mstr_discrete/res/chips/chips.prt!RES!RES_0402-10.0K,1%,1/16W,CHIP,G21796-016!RES!!!F1265!!SB!!
S!@baseboard_fab2_lib.baseboard_fab2(sch_1):page134_i17@mstr_discrete.res(chips)!RES_0402-10.0K,1%,1/16W,CHIP,GA!R2N23!//jf4cfls225.pdx.intel.com/apd_proj/ppg_lib/epg_masterlib/logical/mstr_discrete/res/chips/chips.prt!RES!RES_0402-10.0K,1%,1/16W,CHIP,G21796-016!RES!!!F1313!!SB!!
S!@baseboard_fab2_lib.baseboard_fab2(sch_1):page136_i101@mstr_discrete.res(chips)!RES_0402-10.0K,1%,1/16W,CHIP,GA!R7G26!//jf4cfls225.pdx.intel.com/apd_proj/ppg_lib/epg_masterlib/logical/mstr_discrete/res/chips/chips.prt!RES!RES_0402-10.0K,1%,1/16W,CHIP,G21796-016!RES!!!F1307!!SB!!
S!@baseboard_fab2_lib.baseboard_fab2(sch_1):page142_i28@mstr_discrete.res(chips)!RES_0402-10.0K,1%,1/16W,CHIP,GA!R8E36!//jf4cfls225.pdx.intel.com/apd_proj/ppg_lib/epg_masterlib/logical/mstr_discrete/res/chips/chips.prt!RES!RES_0402-10.0K,1%,1/16W,CHIP,G21796-016!RES!!!F1261!!PCIE_WAKE_BUFFER!!
S!@baseboard_fab2_lib.baseboard_fab2(sch_1):page239_i6@mstr_discrete.res(chips)!RES_0402-10.0K,1%,1/16W,CHIP,GA!R9F12!//jf4cfls225.pdx.intel.com/apd_proj/ppg_lib/epg_masterlib/logical/mstr_discrete/res/chips/chips.prt!RES!RES_0402-10.0K,1%,1/16W,CHIP,G21796-016!RES!!!F1246!!P1V538_BMC_STBY_VR!!
S!@baseboard_fab2_lib.baseboard_fab2(sch_1):page133_i247@mstr_discrete.res(chips)!RES_0402-10.0K,1%,1/16W,CHIP,GA!R2N16!//jf4cfls225.pdx.intel.com/apd_proj/ppg_lib/epg_masterlib/logical/mstr_discrete/res/chips/chips.prt!RES!RES_0402-10.0K,1%,1/16W,CHIP,G21796-016!RES!!!F1314!!SB!!
S!@baseboard_fab2_lib.baseboard_fab2(sch_1):page135_i58@mstr_discrete.res(chips)!RES_0402-10.0K,1%,1/16W,CHIP,GA!R7C21!//jf4cfls225.pdx.intel.com/apd_proj/ppg_lib/epg_masterlib/logical/mstr_discrete/res/chips/chips.prt!RES!RES_0402-10.0K,1%,1/16W,CHIP,G21796-016!RES!!!F1287!!THERMTRIP_PCH!!
S!@baseboard_fab2_lib.baseboard_fab2(sch_1):page136_i140@mstr_discrete.res(chips)!RES_0402-10.0K,1%,1/16W,CHIP,GA!R8E16!//jf4cfls225.pdx.intel.com/apd_proj/ppg_lib/epg_masterlib/logical/mstr_discrete/res/chips/chips.prt!RES!RES_0402-10.0K,1%,1/16W,CHIP,G21796-016!RES!!!F1264!!SB!!
S!@baseboard_fab2_lib.baseboard_fab2(sch_1):page21_i240@mstr_discrete.res(chips)!RES_0402-10.0K,1%,1/16W,CHIP,GA!R5N3!//jf4cfls225.pdx.intel.com/apd_proj/ppg_lib/epg_masterlib/logical/mstr_discrete/res/chips/chips.prt!RES!RES_0402-10.0K,1%,1/16W,CHIP,G21796-016!RES!!!F1298!!CPU0!!
S!@baseboard_fab2_lib.baseboard_fab2(sch_1):page21_i239@mstr_discrete.res(chips)!RES_0402-10.0K,1%,1/16W,CHIP,GA!R5N5!//jf4cfls225.pdx.intel.com/apd_proj/ppg_lib/epg_masterlib/logical/mstr_discrete/res/chips/chips.prt!RES!RES_0402-10.0K,1%,1/16W,CHIP,G21796-016!RES!!!F1297!!CPU0!!
S!@baseboard_fab2_lib.baseboard_fab2(sch_1):page21_i238@mstr_discrete.res(chips)!RES_0402-10.0K,1%,1/16W,CHIP,GA!R5N1!//jf4cfls225.pdx.intel.com/apd_proj/ppg_lib/epg_masterlib/logical/mstr_discrete/res/chips/chips.prt!RES!RES_0402-10.0K,1%,1/16W,CHIP,G21796-016!RES!!!F1299!!CPU0!!
S!@baseboard_fab2_lib.baseboard_fab2(sch_1):page55_i159@mstr_discrete.res(chips)!RES_0402-10.0K,1%,1/16W,CHIP,GA!R8N3!//jf4cfls225.pdx.intel.com/apd_proj/ppg_lib/epg_masterlib/logical/mstr_discrete/res/chips/chips.prt!RES!RES_0402-10.0K,1%,1/16W,CHIP,G21796-016!RES!!!F1256!!CPU1!!
S!@baseboard_fab2_lib.baseboard_fab2(sch_1):page55_i160@mstr_discrete.res(chips)!RES_0402-10.0K,1%,1/16W,CHIP,GA!R8N5!//jf4cfls225.pdx.intel.com/apd_proj/ppg_lib/epg_masterlib/logical/mstr_discrete/res/chips/chips.prt!RES!RES_0402-10.0K,1%,1/16W,CHIP,G21796-016!RES!!!F1255!!CPU1!!
S!@baseboard_fab2_lib.baseboard_fab2(sch_1):page55_i161@mstr_discrete.res(chips)!RES_0402-10.0K,1%,1/16W,CHIP,GA!R8N2!//jf4cfls225.pdx.intel.com/apd_proj/ppg_lib/epg_masterlib/logical/mstr_discrete/res/chips/chips.prt!RES!RES_0402-10.0K,1%,1/16W,CHIP,G21796-016!RES!!!F1257!!CPU1!!
S!@baseboard_fab2_lib.baseboard_fab2(sch_1):page139_i179@mstr_discrete.res(chips)!RES_0402-10.0K,1%,1/16W,CHIP,GA!R9E1!//jf4cfls225.pdx.intel.com/apd_proj/ppg_lib/epg_masterlib/logical/mstr_discrete/res/chips/chips.prt!RES!RES_0402-10.0K,1%,1/16W,CHIP,G21796-016!RES!!!F1253!!NIC_SPRV!!
S!@baseboard_fab2_lib.baseboard_fab2(sch_1):page139_i178@mstr_discrete.res(chips)!RES_0402-10.0K,1%,1/16W,CHIP,GA!R9E3!//jf4cfls225.pdx.intel.com/apd_proj/ppg_lib/epg_masterlib/logical/mstr_discrete/res/chips/chips.prt!RES!RES_0402-10.0K,1%,1/16W,CHIP,G21796-016!RES!!!F1251!!NIC_SPRV!!
S!@baseboard_fab2_lib.baseboard_fab2(sch_1):page139_i177@mstr_discrete.res(chips)!RES_0402-10.0K,1%,1/16W,CHIP,GA!R9E2!//jf4cfls225.pdx.intel.com/apd_proj/ppg_lib/epg_masterlib/logical/mstr_discrete/res/chips/chips.prt!RES!RES_0402-10.0K,1%,1/16W,CHIP,G21796-016!RES!!!F1252!!NIC_SPRV!!
S!@baseboard_fab2_lib.baseboard_fab2(sch_1):page139_i181@mstr_discrete.res(chips)!RES_0402-10.0K,1%,1/16W,CHIP,GA!R9E22!//jf4cfls225.pdx.intel.com/apd_proj/ppg_lib/epg_masterlib/logical/mstr_discrete/res/chips/chips.prt!RES!RES_0402-10.0K,1%,1/16W,CHIP,G21796-016!RES!!!F1248!!NIC_SPRV!!
S!@baseboard_fab2_lib.baseboard_fab2(sch_1):page238_i21@mstr_discrete.res(chips)!RES_0402-10.0K,1%,1/16W,CHIP,GA!R9F13!//jf4cfls225.pdx.intel.com/apd_proj/ppg_lib/epg_masterlib/logical/mstr_discrete/res/chips/chips.prt!RES!RES_0402-10.0K,1%,1/16W,CHIP,G21796-016!RES!!!F1245!!P1V26_BMC_STBY_VR!!
S!@baseboard_fab2_lib.baseboard_fab2(sch_1):page238_i14@mstr_discrete.res(chips)!RES_0402-10.0K,1%,1/16W,CHIP,GA!R9F8!//jf4cfls225.pdx.intel.com/apd_proj/ppg_lib/epg_masterlib/logical/mstr_discrete/res/chips/chips.prt!RES!RES_0402-10.0K,1%,1/16W,CHIP,G21796-016!RES!!!F1247!!P1V26_BMC_STBY_VR!!
S!@baseboard_fab2_lib.baseboard_fab2(sch_1):page125_i52@mstr_discrete.res(chips)!RES_0402-10.0K,1%,1/16W,CHIP,GA!R8D13!//jf4cfls225.pdx.intel.com/apd_proj/ppg_lib/epg_masterlib/logical/mstr_discrete/res/chips/chips.prt!RES!RES_0402-10.0K,1%,1/16W,CHIP,G21796-016!RES!!!F1268!!SB_HEADERS!!
S!@baseboard_fab2_lib.baseboard_fab2(sch_1):page221_i45@mstr_discrete.res(chips)!RES_0402-10.0K,1%,1/16W,CHIP,GA!R4G18!//jf4cfls225.pdx.intel.com/apd_proj/ppg_lib/epg_masterlib/logical/mstr_discrete/res/chips/chips.prt!RES!RES_0402-10.0K,1%,1/16W,CHIP,G21796-016!RES!!!F1301!!VTT_ABC_PWR_VR!!
S!@baseboard_fab2_lib.baseboard_fab2(sch_1):page133_i200@mstr_discrete.res(chips)!RES_0402-10.0K,1%,1/16W,CHIP,GA!R7D8!//jf4cfls225.pdx.intel.com/apd_proj/ppg_lib/epg_masterlib/logical/mstr_discrete/res/chips/chips.prt!RES!RES_0402-10.0K,1%,1/16W,CHIP,G21796-016!RES!!!F1284!!SB!!
S!@baseboard_fab2_lib.baseboard_fab2(sch_1):page133_i245@mstr_discrete.res(chips)!RES_0402-10.0K,1%,1/16W,CHIP,GA!R7D4!//jf4cfls225.pdx.intel.com/apd_proj/ppg_lib/epg_masterlib/logical/mstr_discrete/res/chips/chips.prt!RES!RES_0402-10.0K,1%,1/16W,CHIP,G21796-016!RES!!!F1285!!SB!!
S!@baseboard_fab2_lib.baseboard_fab2(sch_1):page133_i202@mstr_discrete.res(chips)!RES_0402-10.0K,1%,1/16W,CHIP,GA!R7D10!//jf4cfls225.pdx.intel.com/apd_proj/ppg_lib/epg_masterlib/logical/mstr_discrete/res/chips/chips.prt!RES!RES_0402-10.0K,1%,1/16W,CHIP,G21796-016!RES!!!F1283!!SB!!
S!@baseboard_fab2_lib.baseboard_fab2(sch_1):page156_i211@mstr_discrete.res(chips)!RES_0402-10.0K,1%,1/16W,CHIP,GA!R8F26!//jf4cfls225.pdx.intel.com/apd_proj/ppg_lib/epg_masterlib/logical/mstr_discrete/res/chips/chips.prt!RES!RES_0402-10.0K,1%,1/16W,CHIP,G21796-016!RES!!!F1260!!BMC_MISC!!
S!@baseboard_fab2_lib.baseboard_fab2(sch_1):page156_i210@mstr_discrete.res(chips)!RES_0402-10.0K,1%,1/16W,CHIP,GA!R2T22!//jf4cfls225.pdx.intel.com/apd_proj/ppg_lib/epg_masterlib/logical/mstr_discrete/res/chips/chips.prt!RES!RES_0402-10.0K,1%,1/16W,CHIP,G21796-016!RES!!!F1309!!BMC_MISC!!
S!@baseboard_fab2_lib.baseboard_fab2(sch_1):page153_i140@mstr_discrete.res(chips)!RES_0402-10.0K,1%,1/16W,CHIP,GA!R7F32!//jf4cfls225.pdx.intel.com/apd_proj/ppg_lib/epg_masterlib/logical/mstr_discrete/res/chips/chips.prt!RES!RES_0402-10.0K,1%,1/16W,CHIP,G21796-016!RES!!!F1274!!SB_SPI!!
S!@baseboard_fab2_lib.baseboard_fab2(sch_1):page153_i168@mstr_discrete.res(chips)!RES_0402-10.0K,1%,1/16W,CHIP,GA!R7F28!//jf4cfls225.pdx.intel.com/apd_proj/ppg_lib/epg_masterlib/logical/mstr_discrete/res/chips/chips.prt!RES!RES_0402-10.0K,1%,1/16W,CHIP,G21796-016!RES!!!F1275!!SB_SPI!!
S!@baseboard_fab2_lib.baseboard_fab2(sch_1):page154_i106@mstr_discrete.res(chips)!RES_0402-10.0K,1%,1/16W,CHIP,GA!R2T8!//jf4cfls225.pdx.intel.com/apd_proj/ppg_lib/epg_masterlib/logical/mstr_discrete/res/chips/chips.prt!RES!RES_0402-10.0K,1%,1/16W,CHIP,G21796-016!RES!!!F1310!!SB_BMC_SPI_MUX!!
S!@baseboard_fab2_lib.baseboard_fab2(sch_1):page222_i19@mstr_discrete.res(chips)!RES_0402-10.0K,1%,1/16W,CHIP,GA!R6L9!//jf4cfls225.pdx.intel.com/apd_proj/ppg_lib/epg_masterlib/logical/mstr_discrete/res/chips/chips.prt!RES!RES_0402-10.0K,1%,1/16W,CHIP,G21796-016!RES!!!F1295!!VTT_DEF_PWR_VR!!
S!@baseboard_fab2_lib.baseboard_fab2(sch_1):page229_i14@mstr_discrete.res(chips)!RES_0402-10.0K,1%,1/16W,CHIP,GA!R4G17!//jf4cfls225.pdx.intel.com/apd_proj/ppg_lib/epg_masterlib/logical/mstr_discrete/res/chips/chips.prt!RES!RES_0402-10.0K,1%,1/16W,CHIP,G21796-016!RES!!!F1302!!VTT_GHJ_PWR_VR!!
S!@baseboard_fab2_lib.baseboard_fab2(sch_1):page230_i17@mstr_discrete.res(chips)!RES_0402-10.0K,1%,1/16W,CHIP,GA!R4A5!//jf4cfls225.pdx.intel.com/apd_proj/ppg_lib/epg_masterlib/logical/mstr_discrete/res/chips/chips.prt!RES!RES_0402-10.0K,1%,1/16W,CHIP,G21796-016!RES!!!F1304!!VTT_KLM_PWR_VR!!
S!@baseboard_fab2_lib.baseboard_fab2(sch_1):page185_i111@mstr_discrete.res(chips)!RES_0402-10.0K,1%,1/16W,CHIP,GA!R2P15!//jf4cfls225.pdx.intel.com/apd_proj/ppg_lib/epg_masterlib/logical/mstr_discrete/res/chips/chips.prt!RES!RES_0402-10.0K,1%,1/16W,CHIP,G21796-016!RES!!!F1267!!M_2!!
S!@baseboard_fab2_lib.baseboard_fab2(sch_1):page185_i113@mstr_discrete.res(chips)!RES_0402-10.0K,1%,1/16W,CHIP,GA!R2P16!//jf4cfls225.pdx.intel.com/apd_proj/ppg_lib/epg_masterlib/logical/mstr_discrete/res/chips/chips.prt!RES!RES_0402-10.0K,1%,1/16W,CHIP,G21796-016!RES!!!F1269!!M_2!!
S!@baseboard_fab2_lib.baseboard_fab2(sch_1):page139_i200@mstr_discrete.res(chips)!RES_0402-10.0K,1%,1/16W,CHIP,GA!R9E4!//jf4cfls225.pdx.intel.com/apd_proj/ppg_lib/epg_masterlib/logical/mstr_discrete/res/chips/chips.prt!RES!RES_0402-10.0K,1%,1/16W,CHIP,G21796-016!RES!!!F1250!!NIC_SPRV!!
S!@baseboard_fab2_lib.baseboard_fab2(sch_1):page142_i23@mstr_discrete.res(chips)!RES_0402-10.0K,1%,1/16W,CHIP,GA!R8E30!//jf4cfls225.pdx.intel.com/apd_proj/ppg_lib/epg_masterlib/logical/mstr_discrete/res/chips/chips.prt!RES!RES_0402-10.0K,1%,1/16W,CHIP,G21796-016!RES!!!F1263!!PCIE_WAKE_BUFFER!!
S!@baseboard_fab2_lib.baseboard_fab2(sch_1):page147_i109@mstr_discrete.res(chips)!RES_0402-10.0K,1%,1/16W,CHIP,GA!R1R13!//jf4cfls225.pdx.intel.com/apd_proj/ppg_lib/epg_masterlib/logical/mstr_discrete/res/chips/chips.prt!RES!RES_0402-10.0K,1%,1/16W,CHIP,G21796-016!RES!!!F1321!!BMC!!
S!@baseboard_fab2_lib.baseboard_fab2(sch_1):page147_i108@mstr_discrete.res(chips)!RES_0402-10.0K,1%,1/16W,CHIP,GA!R1R10!//jf4cfls225.pdx.intel.com/apd_proj/ppg_lib/epg_masterlib/logical/mstr_discrete/res/chips/chips.prt!RES!RES_0402-10.0K,1%,1/16W,CHIP,G21796-016!RES!!!F1323!!BMC!!
S!@baseboard_fab2_lib.baseboard_fab2(sch_1):page147_i118@mstr_discrete.res(chips)!RES_0402-10.0K,1%,1/16W,CHIP,GA!R8F32!//jf4cfls225.pdx.intel.com/apd_proj/ppg_lib/epg_masterlib/logical/mstr_discrete/res/chips/chips.prt!RES!RES_0402-10.0K,1%,1/16W,CHIP,G21796-016!RES!!!F1259!!BMC!!
S!@baseboard_fab2_lib.baseboard_fab2(sch_1):page147_i119@mstr_discrete.res(chips)!RES_0402-10.0K,1%,1/16W,CHIP,GA!R1R4!//jf4cfls225.pdx.intel.com/apd_proj/ppg_lib/epg_masterlib/logical/mstr_discrete/res/chips/chips.prt!RES!RES_0402-10.0K,1%,1/16W,CHIP,G21796-016!RES!!!F1324!!BMC!!
S!@baseboard_fab2_lib.baseboard_fab2(sch_1):page139_i212@mstr_discrete.res(chips)!RES_0402-10.0K,1%,1/16W,CHIP,GA!R9E13!//jf4cfls225.pdx.intel.com/apd_proj/ppg_lib/epg_masterlib/logical/mstr_discrete/res/chips/chips.prt!RES!RES_0402-10.0K,1%,1/16W,CHIP,G21796-016!RES!!!F1249!!NIC_SPRV!!
S!@baseboard_fab2_lib.baseboard_fab2(sch_1):page139_i214@mstr_discrete.res(chips)!RES_0402-10.0K,1%,1/16W,CHIP,GA!R1T1!//jf4cfls225.pdx.intel.com/apd_proj/ppg_lib/epg_masterlib/logical/mstr_discrete/res/chips/chips.prt!RES!RES_0402-10.0K,1%,1/16W,CHIP,G21796-016!RES!!!F1320!!NIC_SPRV!!
S!@baseboard_fab2_lib.baseboard_fab2(sch_1):page121_i37@mstr_discrete.res(chips)!RES_0402-10.0K,1%,1/16W,CHIP,GA!R3N10!//jf4cfls225.pdx.intel.com/apd_proj/ppg_lib/epg_masterlib/logical/mstr_discrete/res/chips/chips.prt!RES!RES_0402-10.0K,1%,1/16W,CHIP,G21796-016!RES!!!F1308!!SB!!
S!@baseboard_fab2_lib.baseboard_fab2(sch_1):page241_i50@mstr_discrete.res(chips)!RES_0402-10.0K,1%,1/16W,CHIP,GA!R7F1!//jf4cfls225.pdx.intel.com/apd_proj/ppg_lib/epg_masterlib/logical/mstr_discrete/res/chips/chips.prt!RES!RES_0402-10.0K,1%,1/16W,CHIP,G21796-016!RES!!!F1277!!P5V_STBY_VR!!
S!@baseboard_fab2_lib.baseboard_fab2(sch_1):page196_i114@mstr_discrete.res(chips)!RES_0402-49.9K,1%,1/16W,CHIP,GA!R8D39!//jf4cfls225.pdx.intel.com/apd_proj/ppg_lib/epg_masterlib/logical/mstr_discrete/res/chips/chips.prt!RES!RES_0402-49.9K,1%,1/16W,CHIP,G21796-048!RES!!!F396!!V_SUPER!!
S!@baseboard_fab2_lib.baseboard_fab2(sch_1):page147_i78@mstr_discrete.res(chips)!RES_0402-49.9K,1%,1/16W,CHIP,GA!R9G7!//jf4cfls225.pdx.intel.com/apd_proj/ppg_lib/epg_masterlib/logical/mstr_discrete/res/chips/chips.prt!RES!RES_0402-49.9K,1%,1/16W,CHIP,G21796-048!RES!!!F397!!BMC!!
S!@baseboard_fab2_lib.baseboard_fab2(sch_1):page237_i80@mstr_discrete.res(chips)!RES_0402-49.9K,1%,1/16W,CHIP,GA!R2L19!//jf4cfls225.pdx.intel.com/apd_proj/ppg_lib/epg_masterlib/logical/mstr_discrete/res/chips/chips.prt!RES!RES_0402-49.9K,1%,1/16W,CHIP,G21796-048!RES!!!F398!!P1V8_PCH_STBY_VR!!
S!@baseboard_fab2_lib.baseboard_fab2(sch_1):page241_i18@mstr_discrete.res(chips)!RES_0402-75K,1%,1/16W,CHIP,G21A!R7E14!//jf4cfls225.pdx.intel.com/apd_proj/ppg_lib/epg_masterlib/logical/mstr_discrete/res/chips/chips.prt!RES!RES_0402-75K,1%,1/16W,CHIP,G21796-224!RES!!!F299!!P5V_STBY_VR!!
S!@baseboard_fab2_lib.baseboard_fab2(sch_1):page241_i83@mstr_vreg.tps54821(chips)!TPS54821_LCC-IC,H63269-001!EU7E2!//jf4cfls225.pdx.intel.com/apd_proj/ppg_lib/epg_masterlib/logical/mstr_vreg/tps54821/chips/chips.prt!TPS54821!TPS54821_LCC-IC,H63269-001!TPS54821_LCC!!!F46!!P5V_STBY_VR!!
S!@baseboard_fab2_lib.baseboard_fab2(sch_1):page165_i52@mstr_digital.adc128d818(chips)!ADC128D818_SM-IC,H63642-001!EU9G1!//jf4cfls225.pdx.intel.com/apd_proj/ppg_lib/epg_masterlib/logical/mstr_digital/adc128d818/chips/chips.prt!ADC128D818!ADC128D818_SM-IC,H63642-001!ADC128D818_SM!!!F4199!!HEC_VOLT_MONITOR!!
S!@baseboard_fab2_lib.baseboard_fab2(sch_1):page114_i50@mstr_discrete.cap(chips)!CAP_0402LF-15.0PF,50V,5%,COG,AA!C7C4!//jf4cfls225.pdx.intel.com/apd_proj/ppg_lib/epg_masterlib/logical/mstr_discrete/cap/chips/chips.prt!CAP!CAP_0402LF-15.0PF,50V,5%,COG,A36095-047!CAP!!!F3157!!SB!!
S!@baseboard_fab2_lib.baseboard_fab2(sch_1):page114_i47@mstr_discrete.cap(chips)!CAP_0402LF-15.0PF,50V,5%,COG,AA!C7C5!//jf4cfls225.pdx.intel.com/apd_proj/ppg_lib/epg_masterlib/logical/mstr_discrete/cap/chips/chips.prt!CAP!CAP_0402LF-15.0PF,50V,5%,COG,A36095-047!CAP!!!F3156!!SB!!
S!@baseboard_fab2_lib.baseboard_fab2(sch_1):page118_i79@mstr_discrete.cap(chips)!CAP_0402LF-33.0PF,50V,5%,COG,AA!C8C1!//jf4cfls225.pdx.intel.com/apd_proj/ppg_lib/epg_masterlib/logical/mstr_discrete/cap/chips/chips.prt!CAP!CAP_0402LF-33.0PF,50V,5%,COG,A36095-031!CAP!!!F3119!!SB!!
S!@baseboard_fab2_lib.baseboard_fab2(sch_1):page118_i77@mstr_discrete.cap(chips)!CAP_0402LF-33.0PF,50V,5%,COG,AA!C8C2!//jf4cfls225.pdx.intel.com/apd_proj/ppg_lib/epg_masterlib/logical/mstr_discrete/cap/chips/chips.prt!CAP!CAP_0402LF-33.0PF,50V,5%,COG,A36095-031!CAP!!!F3118!!SB!!
S!@baseboard_fab2_lib.baseboard_fab2(sch_1):page118_i76@mstr_discrete.crystal(chips)!CRYSTAL_2013-25.000MHZ,IC,H196A!Y8C1!//jf4cfls225.pdx.intel.com/apd_proj/ppg_lib/epg_masterlib/logical/mstr_discrete/crystal/chips/chips.prt!CRYSTAL!CRYSTAL_2013-25.000MHZ,IC,H19611-001!CRYSTAL_2013!!!F2231!!SB!!
S!@baseboard_fab2_lib.baseboard_fab2(sch_1):page91_i35@mstr_discrete.res(chips)!RES_0402-1.8K,1%,1/16W,CHIP,G2A!R8B11!//jf4cfls225.pdx.intel.com/apd_proj/ppg_lib/epg_masterlib/logical/mstr_discrete/res/chips/chips.prt!RES!RES_0402-1.8K,1%,1/16W,CHIP,G21796-336!RES!!!F1380!!SMBUS_CPU0_STL!!
S!@baseboard_fab2_lib.baseboard_fab2(sch_1):page91_i36@mstr_discrete.res(chips)!RES_0402-1.8K,1%,1/16W,CHIP,G2A!R8B7!//jf4cfls225.pdx.intel.com/apd_proj/ppg_lib/epg_masterlib/logical/mstr_discrete/res/chips/chips.prt!RES!RES_0402-1.8K,1%,1/16W,CHIP,G21796-336!RES!!!F1381!!SMBUS_CPU0_STL!!
S!@baseboard_fab2_lib.baseboard_fab2(sch_1):page91_i37@mstr_discrete.res(chips)!RES_0402-1.8K,1%,1/16W,CHIP,G2A!R8B6!//jf4cfls225.pdx.intel.com/apd_proj/ppg_lib/epg_masterlib/logical/mstr_discrete/res/chips/chips.prt!RES!RES_0402-1.8K,1%,1/16W,CHIP,G21796-336!RES!!!F1382!!SMBUS_CPU0_STL!!
S!@baseboard_fab2_lib.baseboard_fab2(sch_1):page91_i34@mstr_discrete.res(chips)!RES_0402-1.8K,1%,1/16W,CHIP,G2A!R8B13!//jf4cfls225.pdx.intel.com/apd_proj/ppg_lib/epg_masterlib/logical/mstr_discrete/res/chips/chips.prt!RES!RES_0402-1.8K,1%,1/16W,CHIP,G21796-336!RES!!!F1379!!SMBUS_CPU0_STL!!
S!@baseboard_fab2_lib.baseboard_fab2(sch_1):page21_i227@mstr_discrete.res(chips)!RES_0402-1.8K,1%,1/16W,CHIP,G2A!R5N2!//jf4cfls225.pdx.intel.com/apd_proj/ppg_lib/epg_masterlib/logical/mstr_discrete/res/chips/chips.prt!RES!RES_0402-1.8K,1%,1/16W,CHIP,G21796-336!RES!!!F1384!!CPU0!!
S!@baseboard_fab2_lib.baseboard_fab2(sch_1):page55_i157@mstr_discrete.res(chips)!RES_0402-1.8K,1%,1/16W,CHIP,G2A!R8N1!//jf4cfls225.pdx.intel.com/apd_proj/ppg_lib/epg_masterlib/logical/mstr_discrete/res/chips/chips.prt!RES!RES_0402-1.8K,1%,1/16W,CHIP,G21796-336!RES!!!F1378!!CPU1!!
S!@baseboard_fab2_lib.baseboard_fab2(sch_1):page21_i241@mstr_discrete.res(chips)!RES_0402-1.8K,1%,1/16W,CHIP,G2A!R5N4!//jf4cfls225.pdx.intel.com/apd_proj/ppg_lib/epg_masterlib/logical/mstr_discrete/res/chips/chips.prt!RES!RES_0402-1.8K,1%,1/16W,CHIP,G21796-336!RES!!!F1383!!CPU0!!
S!@baseboard_fab2_lib.baseboard_fab2(sch_1):page55_i158@mstr_discrete.res(chips)!RES_0402-1.8K,1%,1/16W,CHIP,G2A!R8N4!//jf4cfls225.pdx.intel.com/apd_proj/ppg_lib/epg_masterlib/logical/mstr_discrete/res/chips/chips.prt!RES!RES_0402-1.8K,1%,1/16W,CHIP,G21796-336!RES!!!F1377!!CPU1!!
S!@baseboard_fab2_lib.baseboard_fab2(sch_1):page114_i149@mstr_discrete.res(chips)!RES_0402-169,1.0%,1/16W,CHIP,GA!R3N1!//jf4cfls225.pdx.intel.com/apd_proj/ppg_lib/epg_masterlib/logical/mstr_discrete/res/chips/chips.prt!RES!RES_0402-169,1.0%,1/16W,CHIP,G21796-276!RES!!!F1065!!SB!!
S!@baseboard_fab2_lib.baseboard_fab2(sch_1):page114_i48@mstr_discrete.res(chips)!RES_0603-200K,0.1%,1/10W,CHIP,A!R7C1!//jf4cfls225.pdx.intel.com/apd_proj/ppg_lib/epg_masterlib/logical/mstr_discrete/res/chips/chips.prt!RES!RES_0603-200K,0.1%,1/10W,CHIP,G22369-010!RES!!!F257!!SB!!
S!@baseboard_fab2_lib.baseboard_fab2(sch_1):page161_i120@mstr_discrete.res(chips)!RES_0402-10.0K,1%,1/16W,EMPTY,A!R1E11!//jf4cfls225.pdx.intel.com/apd_proj/ppg_lib/epg_masterlib/logical/mstr_discrete/res/chips/chips.prt!RES!RES_0402-10.0K,1%,1/16W,EMPTY,G21796-016!RES!!!F1232!!CPU_FANS!!
S!@baseboard_fab2_lib.baseboard_fab2(sch_1):page240_i111@mstr_discrete.res(chips)!RES_0402-10.0K,1%,1/16W,EMPTY,A!R8F1!//jf4cfls225.pdx.intel.com/apd_proj/ppg_lib/epg_masterlib/logical/mstr_discrete/res/chips/chips.prt!RES!RES_0402-10.0K,1%,1/16W,EMPTY,G21796-016!RES!!!F1222!!P3V3_STBY_VR!!
S!@baseboard_fab2_lib.baseboard_fab2(sch_1):page133_i122@mstr_discrete.res(chips)!RES_0402-10.0K,1%,1/16W,EMPTY,A!R2N12!//jf4cfls225.pdx.intel.com/apd_proj/ppg_lib/epg_masterlib/logical/mstr_discrete/res/chips/chips.prt!RES!RES_0402-10.0K,1%,1/16W,EMPTY,G21796-016!RES!!!F1231!!SB!!
S!@baseboard_fab2_lib.baseboard_fab2(sch_1):page189_i45@mstr_discrete.res(chips)!RES_0402-10.0K,1%,1/16W,EMPTY,A!R3R11!//jf4cfls225.pdx.intel.com/apd_proj/ppg_lib/epg_masterlib/logical/mstr_discrete/res/chips/chips.prt!RES!RES_0402-10.0K,1%,1/16W,EMPTY,G21796-016!RES!!!F1228!!BMC_DEBUG_HEADER!!
S!@baseboard_fab2_lib.baseboard_fab2(sch_1):page153_i170@mstr_discrete.res(chips)!RES_0402-10.0K,1%,1/16W,EMPTY,A!R7F30!//jf4cfls225.pdx.intel.com/apd_proj/ppg_lib/epg_masterlib/logical/mstr_discrete/res/chips/chips.prt!RES!RES_0402-10.0K,1%,1/16W,EMPTY,G21796-016!RES!!!F1224!!SB_SPI!!
S!@baseboard_fab2_lib.baseboard_fab2(sch_1):page153_i179@mstr_discrete.res(chips)!RES_0402-10.0K,1%,1/16W,EMPTY,A!R3T9!//jf4cfls225.pdx.intel.com/apd_proj/ppg_lib/epg_masterlib/logical/mstr_discrete/res/chips/chips.prt!RES!RES_0402-10.0K,1%,1/16W,EMPTY,G21796-016!RES!!!F1227!!SB_SPI!!
S!@baseboard_fab2_lib.baseboard_fab2(sch_1):page196_i71@mstr_discrete.res(chips)!RES_0402-10.0K,1%,1/16W,EMPTY,A!R3P50!//jf4cfls225.pdx.intel.com/apd_proj/ppg_lib/epg_masterlib/logical/mstr_discrete/res/chips/chips.prt!RES!RES_0402-10.0K,1%,1/16W,EMPTY,G21796-016!RES!!!F1229!!V_SUPER!!
S!@baseboard_fab2_lib.baseboard_fab2(sch_1):page125_i71@mstr_discrete.res(chips)!RES_0402-10.0K,1%,1/16W,EMPTY,A!R8D16!//jf4cfls225.pdx.intel.com/apd_proj/ppg_lib/epg_masterlib/logical/mstr_discrete/res/chips/chips.prt!RES!RES_0402-10.0K,1%,1/16W,EMPTY,G21796-016!RES!!!F1223!!SB!!
S!@baseboard_fab2_lib.baseboard_fab2(sch_1):page102_i38@mstr_discrete.res(chips)!RES_0402-10.0K,1%,1/16W,EMPTY,A!R4D35!//jf4cfls225.pdx.intel.com/apd_proj/ppg_lib/epg_masterlib/logical/mstr_discrete/res/chips/chips.prt!RES!RES_0402-10.0K,1%,1/16W,EMPTY,G21796-016!RES!!!F1226!!DB1200ZL!!
S!@baseboard_fab2_lib.baseboard_fab2(sch_1):page102_i37@mstr_discrete.res(chips)!RES_0402-10.0K,1%,1/16W,EMPTY,A!R4D38!//jf4cfls225.pdx.intel.com/apd_proj/ppg_lib/epg_masterlib/logical/mstr_discrete/res/chips/chips.prt!RES!RES_0402-10.0K,1%,1/16W,EMPTY,G21796-016!RES!!!F1225!!DB1200ZL!!
S!@baseboard_fab2_lib.baseboard_fab2(sch_1):page200_i70@mstr_discrete.res(chips)!RES_0402-10.0K,1%,1/16W,EMPTY,A!R9P19!//jf4cfls225.pdx.intel.com/apd_proj/ppg_lib/epg_masterlib/logical/mstr_discrete/res/chips/chips.prt!RES!RES_0402-10.0K,1%,1/16W,EMPTY,G21796-016!RES!!!F1221!!HOT_SWAP!!
S!@baseboard_fab2_lib.baseboard_fab2(sch_1):page145_i205@mstr_discrete.res(chips)!RES_0402-10.0K,1%,1/16W,EMPTY,A!R2T12!//jf4cfls225.pdx.intel.com/apd_proj/ppg_lib/epg_masterlib/logical/mstr_discrete/res/chips/chips.prt!RES!RES_0402-10.0K,1%,1/16W,EMPTY,G21796-016!RES!!!F1230!!BMC!!
S!@baseboard_fab2_lib.baseboard_fab2(sch_1):page37_i303@mstr_discrete.res(chips)!RES_0402-249,0.1%,1/16W,CHIP,GA!R5D5!//jf4cfls225.pdx.intel.com/apd_proj/ppg_lib/epg_masterlib/logical/mstr_discrete/res/chips/chips.prt!RES!RES_0402-249,0.1%,1/16W,CHIP,G85996-031!RES!!!F807!!CPU0!!
S!@baseboard_fab2_lib.baseboard_fab2(sch_1):page71_i43@mstr_discrete.res(chips)!RES_0402-249,0.1%,1/16W,CHIP,GA!R3D27!//jf4cfls225.pdx.intel.com/apd_proj/ppg_lib/epg_masterlib/logical/mstr_discrete/res/chips/chips.prt!RES!RES_0402-249,0.1%,1/16W,CHIP,G85996-031!RES!!!F808!!CPU1!!
S!@baseboard_fab2_lib.baseboard_fab2(sch_1):page238_i17@mstr_discrete.res(chips)!RES_0402-5.76K,1%,1/16W,CHIP,GA!R9F6!//jf4cfls225.pdx.intel.com/apd_proj/ppg_lib/epg_masterlib/logical/mstr_discrete/res/chips/chips.prt!RES!RES_0402-5.76K,1%,1/16W,CHIP,G21796-143!RES!!!F387!!P1V26_BMC_STBY_VR!!
S!@baseboard_fab2_lib.baseboard_fab2(sch_1):page103_i9@mstr_discrete.res(chips)!RES_0402-27.4,1%,1/16W,CHIP,G2A!R4D23!//jf4cfls225.pdx.intel.com/apd_proj/ppg_lib/epg_masterlib/logical/mstr_discrete/res/chips/chips.prt!RES!RES_0402-27.4,1%,1/16W,CHIP,G21796-182!RES!!!F785!!DB1200Z!!
S!@baseboard_fab2_lib.baseboard_fab2(sch_1):page103_i14@mstr_discrete.res(chips)!RES_0402-27.4,1%,1/16W,CHIP,G2A!R4D28!//jf4cfls225.pdx.intel.com/apd_proj/ppg_lib/epg_masterlib/logical/mstr_discrete/res/chips/chips.prt!RES!RES_0402-27.4,1%,1/16W,CHIP,G21796-182!RES!!!F783!!DB1200Z!!
S!@baseboard_fab2_lib.baseboard_fab2(sch_1):page103_i19@mstr_discrete.res(chips)!RES_0402-27.4,1%,1/16W,CHIP,G2A!R4D19!//jf4cfls225.pdx.intel.com/apd_proj/ppg_lib/epg_masterlib/logical/mstr_discrete/res/chips/chips.prt!RES!RES_0402-27.4,1%,1/16W,CHIP,G21796-182!RES!!!F789!!DB1200Z!!
S!@baseboard_fab2_lib.baseboard_fab2(sch_1):page103_i24@mstr_discrete.res(chips)!RES_0402-27.4,1%,1/16W,CHIP,G2A!R4D21!//jf4cfls225.pdx.intel.com/apd_proj/ppg_lib/epg_masterlib/logical/mstr_discrete/res/chips/chips.prt!RES!RES_0402-27.4,1%,1/16W,CHIP,G21796-182!RES!!!F787!!DB1200Z!!
S!@baseboard_fab2_lib.baseboard_fab2(sch_1):page103_i29@mstr_discrete.res(chips)!RES_0402-27.4,1%,1/16W,CHIP,G2A!R4D13!//jf4cfls225.pdx.intel.com/apd_proj/ppg_lib/epg_masterlib/logical/mstr_discrete/res/chips/chips.prt!RES!RES_0402-27.4,1%,1/16W,CHIP,G21796-182!RES!!!F793!!DB1200Z!!
S!@baseboard_fab2_lib.baseboard_fab2(sch_1):page103_i34@mstr_discrete.res(chips)!RES_0402-27.4,1%,1/16W,CHIP,G2A!R4D16!//jf4cfls225.pdx.intel.com/apd_proj/ppg_lib/epg_masterlib/logical/mstr_discrete/res/chips/chips.prt!RES!RES_0402-27.4,1%,1/16W,CHIP,G21796-182!RES!!!F791!!DB1200Z!!
S!@baseboard_fab2_lib.baseboard_fab2(sch_1):page103_i39@mstr_discrete.res(chips)!RES_0402-27.4,1%,1/16W,CHIP,G2A!R4D9!//jf4cfls225.pdx.intel.com/apd_proj/ppg_lib/epg_masterlib/logical/mstr_discrete/res/chips/chips.prt!RES!RES_0402-27.4,1%,1/16W,CHIP,G21796-182!RES!!!F797!!DB1200Z!!
S!@baseboard_fab2_lib.baseboard_fab2(sch_1):page103_i44@mstr_discrete.res(chips)!RES_0402-27.4,1%,1/16W,CHIP,G2A!R4D11!//jf4cfls225.pdx.intel.com/apd_proj/ppg_lib/epg_masterlib/logical/mstr_discrete/res/chips/chips.prt!RES!RES_0402-27.4,1%,1/16W,CHIP,G21796-182!RES!!!F795!!DB1200Z!!
S!@baseboard_fab2_lib.baseboard_fab2(sch_1):page103_i54@mstr_discrete.res(chips)!RES_0402-27.4,1%,1/16W,CHIP,G2A!R4D1!//jf4cfls225.pdx.intel.com/apd_proj/ppg_lib/epg_masterlib/logical/mstr_discrete/res/chips/chips.prt!RES!RES_0402-27.4,1%,1/16W,CHIP,G21796-182!RES!!!F805!!DB1200Z!!
S!@baseboard_fab2_lib.baseboard_fab2(sch_1):page103_i59@mstr_discrete.res(chips)!RES_0402-27.4,1%,1/16W,CHIP,G2A!R4D4!//jf4cfls225.pdx.intel.com/apd_proj/ppg_lib/epg_masterlib/logical/mstr_discrete/res/chips/chips.prt!RES!RES_0402-27.4,1%,1/16W,CHIP,G21796-182!RES!!!F802!!DB1200Z!!
S!@baseboard_fab2_lib.baseboard_fab2(sch_1):page103_i64@mstr_discrete.res(chips)!RES_0402-27.4,1%,1/16W,CHIP,G2A!R4D3!//jf4cfls225.pdx.intel.com/apd_proj/ppg_lib/epg_masterlib/logical/mstr_discrete/res/chips/chips.prt!RES!RES_0402-27.4,1%,1/16W,CHIP,G21796-182!RES!!!F803!!DB1200Z!!
S!@baseboard_fab2_lib.baseboard_fab2(sch_1):page103_i74@mstr_discrete.res(chips)!RES_0402-27.4,1%,1/16W,CHIP,G2A!R4D6!//jf4cfls225.pdx.intel.com/apd_proj/ppg_lib/epg_masterlib/logical/mstr_discrete/res/chips/chips.prt!RES!RES_0402-27.4,1%,1/16W,CHIP,G21796-182!RES!!!F800!!DB1200Z!!
S!@baseboard_fab2_lib.baseboard_fab2(sch_1):page103_i79@mstr_discrete.res(chips)!RES_0402-27.4,1%,1/16W,CHIP,G2A!R4D5!//jf4cfls225.pdx.intel.com/apd_proj/ppg_lib/epg_masterlib/logical/mstr_discrete/res/chips/chips.prt!RES!RES_0402-27.4,1%,1/16W,CHIP,G21796-182!RES!!!F801!!DB1200Z!!
S!@baseboard_fab2_lib.baseboard_fab2(sch_1):page103_i84@mstr_discrete.res(chips)!RES_0402-27.4,1%,1/16W,CHIP,G2A!R4D8!//jf4cfls225.pdx.intel.com/apd_proj/ppg_lib/epg_masterlib/logical/mstr_discrete/res/chips/chips.prt!RES!RES_0402-27.4,1%,1/16W,CHIP,G21796-182!RES!!!F798!!DB1200Z!!
S!@baseboard_fab2_lib.baseboard_fab2(sch_1):page103_i89@mstr_discrete.res(chips)!RES_0402-27.4,1%,1/16W,CHIP,G2A!R4D7!//jf4cfls225.pdx.intel.com/apd_proj/ppg_lib/epg_masterlib/logical/mstr_discrete/res/chips/chips.prt!RES!RES_0402-27.4,1%,1/16W,CHIP,G21796-182!RES!!!F799!!DB1200Z!!
S!@baseboard_fab2_lib.baseboard_fab2(sch_1):page103_i94@mstr_discrete.res(chips)!RES_0402-27.4,1%,1/16W,CHIP,G2A!R4D12!//jf4cfls225.pdx.intel.com/apd_proj/ppg_lib/epg_masterlib/logical/mstr_discrete/res/chips/chips.prt!RES!RES_0402-27.4,1%,1/16W,CHIP,G21796-182!RES!!!F794!!DB1200Z!!
S!@baseboard_fab2_lib.baseboard_fab2(sch_1):page103_i99@mstr_discrete.res(chips)!RES_0402-27.4,1%,1/16W,CHIP,G2A!R4D10!//jf4cfls225.pdx.intel.com/apd_proj/ppg_lib/epg_masterlib/logical/mstr_discrete/res/chips/chips.prt!RES!RES_0402-27.4,1%,1/16W,CHIP,G21796-182!RES!!!F796!!DB1200Z!!
S!@baseboard_fab2_lib.baseboard_fab2(sch_1):page103_i104@mstr_discrete.res(chips)!RES_0402-27.4,1%,1/16W,CHIP,G2A!R4D17!//jf4cfls225.pdx.intel.com/apd_proj/ppg_lib/epg_masterlib/logical/mstr_discrete/res/chips/chips.prt!RES!RES_0402-27.4,1%,1/16W,CHIP,G21796-182!RES!!!F790!!DB1200Z!!
S!@baseboard_fab2_lib.baseboard_fab2(sch_1):page103_i109@mstr_discrete.res(chips)!RES_0402-27.4,1%,1/16W,CHIP,G2A!R4D14!//jf4cfls225.pdx.intel.com/apd_proj/ppg_lib/epg_masterlib/logical/mstr_discrete/res/chips/chips.prt!RES!RES_0402-27.4,1%,1/16W,CHIP,G21796-182!RES!!!F792!!DB1200Z!!
S!@baseboard_fab2_lib.baseboard_fab2(sch_1):page103_i114@mstr_discrete.res(chips)!RES_0402-27.4,1%,1/16W,CHIP,G2A!R4D22!//jf4cfls225.pdx.intel.com/apd_proj/ppg_lib/epg_masterlib/logical/mstr_discrete/res/chips/chips.prt!RES!RES_0402-27.4,1%,1/16W,CHIP,G21796-182!RES!!!F786!!DB1200Z!!
S!@baseboard_fab2_lib.baseboard_fab2(sch_1):page103_i119@mstr_discrete.res(chips)!RES_0402-27.4,1%,1/16W,CHIP,G2A!R4D20!//jf4cfls225.pdx.intel.com/apd_proj/ppg_lib/epg_masterlib/logical/mstr_discrete/res/chips/chips.prt!RES!RES_0402-27.4,1%,1/16W,CHIP,G21796-182!RES!!!F788!!DB1200Z!!
S!@baseboard_fab2_lib.baseboard_fab2(sch_1):page103_i69@mstr_discrete.res(chips)!RES_0402-27.4,1%,1/16W,CHIP,G2A!R4D29!//jf4cfls225.pdx.intel.com/apd_proj/ppg_lib/epg_masterlib/logical/mstr_discrete/res/chips/chips.prt!RES!RES_0402-27.4,1%,1/16W,CHIP,G21796-182!RES!!!F782!!DB1200Z!!
S!@baseboard_fab2_lib.baseboard_fab2(sch_1):page103_i1@mstr_discrete.res(chips)!RES_0402-27.4,1%,1/16W,CHIP,G2A!R4D25!//jf4cfls225.pdx.intel.com/apd_proj/ppg_lib/epg_masterlib/logical/mstr_discrete/res/chips/chips.prt!RES!RES_0402-27.4,1%,1/16W,CHIP,G21796-182!RES!!!F784!!DB1200Z!!
S!@baseboard_fab2_lib.baseboard_fab2(sch_1):page103_i49@mstr_discrete.res(chips)!RES_0402-27.4,1%,1/16W,CHIP,G2A!R4D2!//jf4cfls225.pdx.intel.com/apd_proj/ppg_lib/epg_masterlib/logical/mstr_discrete/res/chips/chips.prt!RES!RES_0402-27.4,1%,1/16W,CHIP,G21796-182!RES!!!F804!!DB1200Z!!
S!@baseboard_fab2_lib.baseboard_fab2(sch_1):page204_i46@mstr_discrete.inductor(chips)!INDUCTOR_SM-100NH,IND,D92183-0A!L4C1!//jf4cfls225.pdx.intel.com/apd_proj/ppg_lib/epg_masterlib/logical/mstr_discrete/inductor/chips/chips.prt!INDUCTOR!INDUCTOR_SM-100NH,IND,D92183-019!INDUCTOR!!!F2090!!PVCCIN_CPU0_FILTER_VR!!
S!@baseboard_fab2_lib.baseboard_fab2(sch_1):page209_i32@mstr_discrete.inductor(chips)!INDUCTOR_SM-100NH,IND,D92183-0A!L1B2!//jf4cfls225.pdx.intel.com/apd_proj/ppg_lib/epg_masterlib/logical/mstr_discrete/inductor/chips/chips.prt!INDUCTOR!INDUCTOR_SM-100NH,IND,D92183-019!INDUCTOR!!!F2091!!PVCCIN_CPU1_FILTER_VR!!
S!@baseboard_fab2_lib.baseboard_fab2(sch_1):page217_i124@mstr_discrete.inductor(chips)!INDUCTOR_SM-100NH,IND,D92183-0B!L7F2!//jf4cfls225.pdx.intel.com/apd_proj/ppg_lib/epg_masterlib/logical/mstr_discrete/inductor/chips/chips.prt!INDUCTOR!INDUCTOR_SM-100NH,IND,D92183-020!INDUCTOR!!!F2085!!VDDQ_ABC_PWR_VR!!
S!@baseboard_fab2_lib.baseboard_fab2(sch_1):page225_i124@mstr_discrete.inductor(chips)!INDUCTOR_SM-100NH,IND,D92183-0B!L1F1!//jf4cfls225.pdx.intel.com/apd_proj/ppg_lib/epg_masterlib/logical/mstr_discrete/inductor/chips/chips.prt!INDUCTOR!INDUCTOR_SM-100NH,IND,D92183-020!INDUCTOR!!!F2088!!VDDQ_GHJ_PWR_VR!!
S!@baseboard_fab2_lib.baseboard_fab2(sch_1):page228_i124@mstr_discrete.inductor(chips)!INDUCTOR_SM-100NH,IND,D92183-0B!L1B1!//jf4cfls225.pdx.intel.com/apd_proj/ppg_lib/epg_masterlib/logical/mstr_discrete/inductor/chips/chips.prt!INDUCTOR!INDUCTOR_SM-100NH,IND,D92183-020!INDUCTOR!!!F2089!!VDDQ_KLM_PWR_VR!!
S!@baseboard_fab2_lib.baseboard_fab2(sch_1):page220_i124@mstr_discrete.inductor(chips)!INDUCTOR_SM-100NH,IND,D92183-0B!L7A5!//jf4cfls225.pdx.intel.com/apd_proj/ppg_lib/epg_masterlib/logical/mstr_discrete/inductor/chips/chips.prt!INDUCTOR!INDUCTOR_SM-100NH,IND,D92183-020!INDUCTOR!!!F2087!!VDDQ_DEF_PWR_VR!!
S!@baseboard_fab2_lib.baseboard_fab2(sch_1):page212_i56@mstr_discrete.inductor(chips)!INDUCTOR_SM-100NH,IND,D92183-0B!L7C1!//jf4cfls225.pdx.intel.com/apd_proj/ppg_lib/epg_masterlib/logical/mstr_discrete/inductor/chips/chips.prt!INDUCTOR!INDUCTOR_SM-100NH,IND,D92183-020!INDUCTOR!!!F2086!!PVCCIO_CPU1!!
S!@baseboard_fab2_lib.baseboard_fab2(sch_1):page102_i1@mstr_clock.nb3w1200l(chips)!NB3W1200L_LCC-IC,H13585-001!EU4D2!//jf4cfls225.pdx.intel.com/apd_proj/ppg_lib/epg_masterlib/logical/mstr_clock/nb3w1200l/chips/chips.prt!NB3W1200L!NB3W1200L_LCC-IC,H13585-001!NB3W1200L_LCC!!!F2006!!DB1200ZL!!
S!@baseboard_fab2_lib.baseboard_fab2(sch_1):page168_i19@mstr_discrete.fet_n_dual(chips)!FET_N_DUAL_SMLF-2N7002DW,FET,DA!Q1L4!//jf4cfls225.pdx.intel.com/apd_proj/ppg_lib/epg_masterlib/logical/mstr_discrete/fet_n_dual/chips/chips.prt!FET_N_DUAL!FET_N_DUAL_SMLF-2N7002DW,FET,D24280-001!FET_N_DUAL_SMLF!1!!F2180!!UART_MUX!!
S!@baseboard_fab2_lib.baseboard_fab2(sch_1):page168_i18@mstr_discrete.fet_n_dual(chips)!FET_N_DUAL_SMLF-2N7002DW,FET,DA!Q1L4!//jf4cfls225.pdx.intel.com/apd_proj/ppg_lib/epg_masterlib/logical/mstr_discrete/fet_n_dual/chips/chips.prt!FET_N_DUAL!FET_N_DUAL_SMLF-2N7002DW,FET,D24280-001!FET_N_DUAL_SMLF!1!!F2179!!UART_MUX!!
S!@baseboard_fab2_lib.baseboard_fab2(sch_1):page199_i86@mstr_discrete.fet_n_dual(chips)!FET_N_DUAL_SMLF-2N7002DW,FET,DA!Q1D1!//jf4cfls225.pdx.intel.com/apd_proj/ppg_lib/epg_masterlib/logical/mstr_discrete/fet_n_dual/chips/chips.prt!FET_N_DUAL!FET_N_DUAL_SMLF-2N7002DW,FET,D24280-001!FET_N_DUAL_SMLF!1!!F2182!!HOT_SWAP!!
S!@baseboard_fab2_lib.baseboard_fab2(sch_1):page199_i82@mstr_discrete.fet_n_dual(chips)!FET_N_DUAL_SMLF-2N7002DW,FET,DA!Q1D1!//jf4cfls225.pdx.intel.com/apd_proj/ppg_lib/epg_masterlib/logical/mstr_discrete/fet_n_dual/chips/chips.prt!FET_N_DUAL!FET_N_DUAL_SMLF-2N7002DW,FET,D24280-001!FET_N_DUAL_SMLF!1!!F2181!!HOT_SWAP!!
S!@baseboard_fab2_lib.baseboard_fab2(sch_1):page200_i196@mstr_discrete.fet_n_dual(chips)!FET_N_DUAL_SMLF-2N7002DW,FET,DA!Q9P1!//jf4cfls225.pdx.intel.com/apd_proj/ppg_lib/epg_masterlib/logical/mstr_discrete/fet_n_dual/chips/chips.prt!FET_N_DUAL!FET_N_DUAL_SMLF-2N7002DW,FET,D24280-001!FET_N_DUAL_SMLF!1!!F2178!!HOT_SWAP!!
S!@baseboard_fab2_lib.baseboard_fab2(sch_1):page200_i199@mstr_discrete.fet_n_dual(chips)!FET_N_DUAL_SMLF-2N7002DW,FET,DA!Q9P1!//jf4cfls225.pdx.intel.com/apd_proj/ppg_lib/epg_masterlib/logical/mstr_discrete/fet_n_dual/chips/chips.prt!FET_N_DUAL!FET_N_DUAL_SMLF-2N7002DW,FET,D24280-001!FET_N_DUAL_SMLF!1!!F2177!!HOT_SWAP!!
S!@baseboard_fab2_lib.baseboard_fab2(sch_1):page235_i217@mstr_discrete.res(chips)!RES_0402-2.67K,1%,1/16W,CHIP,GA!R8A2!//jf4cfls225.pdx.intel.com/apd_proj/ppg_lib/epg_masterlib/logical/mstr_discrete/res/chips/chips.prt!RES!RES_0402-2.67K,1%,1/16W,CHIP,G21796-180!RES!!!F995!!!!
S!@baseboard_fab2_lib.baseboard_fab2(sch_1):page174_i26@mstr_conn.conn36_g97614001(chips)!CONN36_G97614001_CP-CONN,G9761A!J8A2!//jf4cfls225.pdx.intel.com/apd_proj/ppg_lib/epg_masterlib/logical/mstr_conn/conn36_g97614001/chips/chips.prt!CONN36_G97614001!CONN36_G97614001_CP-CONN,G97614-001!CONN36_G97614001_CP!!!F2251!!ST_SATA!!
S!@baseboard_fab2_lib.baseboard_fab2(sch_1):page173_i163@mstr_conn.conn72_g97614002_a(chips)!CONN72_G97614002_A_CP-CONN,G97A!J8A1!//jf4cfls225.pdx.intel.com/apd_proj/ppg_lib/epg_masterlib/logical/mstr_conn/conn72_g97614002_a/chips/chips.prt!CONN72_G97614002_A!CONN72_G97614002_A_CP-CONN,G97614-002!CONN72_G97614002_A_CP!!!F2240!!ST_SATA!!
S!@baseboard_fab2_lib.baseboard_fab2(sch_1):page153_i146@mstr_memory.w25q256(chips)!W25Q256_XSOI-IC,H25002-001!U7F1!//jf4cfls225.pdx.intel.com/apd_proj/ppg_lib/epg_masterlib/logical/mstr_memory/w25q256/chips/chips.prt!W25Q256!W25Q256_XSOI-IC,H25002-001!W25Q256_XSOI!!!F1!!SB_SPI!!
S!@baseboard_fab2_lib.baseboard_fab2(sch_1):page153_i165@mstr_memory.w25q256(chips)!W25Q256_XSOI-IC,H25002-001!U3T1!//jf4cfls225.pdx.intel.com/apd_proj/ppg_lib/epg_masterlib/logical/mstr_memory/w25q256/chips/chips.prt!W25Q256!W25Q256_XSOI-IC,H25002-001!W25Q256_XSOI!!!F2!!SB_SPI!!
S!@baseboard_fab2_lib.baseboard_fab2(sch_1):page175_i58@mstr_discrete.res(chips)!RES_0402-470.0,5%,1/16W,CHIP,GA!R1L8!//jf4cfls225.pdx.intel.com/apd_proj/ppg_lib/epg_masterlib/logical/mstr_discrete/res/chips/chips.prt!RES!RES_0402-470.0,5%,1/16W,CHIP,G21497-024!RES!!!F468!!MIO_CHASSIS!!
S!@baseboard_fab2_lib.baseboard_fab2(sch_1):page157_i357@mstr_ttl.ttl2g14(chips)!TTL2G14_SMLF-74LVC2G14,IC,D184B!U2R1!//jf4cfls225.pdx.intel.com/apd_proj/ppg_lib/epg_masterlib/logical/mstr_ttl/ttl2g14/chips/chips.prt!TTL2G14!TTL2G14_SMLF-74LVC2G14,IC,D18476-001!TTL2G14!1!!F18!!MIO_CHASSIS!!
S!@baseboard_fab2_lib.baseboard_fab2(sch_1):page157_i356@mstr_ttl.ttl2g14(chips)!TTL2G14_SMLF-74LVC2G14,IC,D184B!U2R1!//jf4cfls225.pdx.intel.com/apd_proj/ppg_lib/epg_masterlib/logical/mstr_ttl/ttl2g14/chips/chips.prt!TTL2G14!TTL2G14_SMLF-74LVC2G14,IC,D18476-001!TTL2G14!1!!F17!!MIO_CHASSIS!!
S!@baseboard_fab2_lib.baseboard_fab2(sch_1):page175_i9@mstr_ttl.ttl2g14(chips)!TTL2G14_SMLF-74LVC2G14,IC,D184B!U9A4!//jf4cfls225.pdx.intel.com/apd_proj/ppg_lib/epg_masterlib/logical/mstr_ttl/ttl2g14/chips/chips.prt!TTL2G14!TTL2G14_SMLF-74LVC2G14,IC,D18476-001!TTL2G14!1!!F14!!MIO_CHASSIS!!
S!@baseboard_fab2_lib.baseboard_fab2(sch_1):page175_i10@mstr_ttl.ttl2g14(chips)!TTL2G14_SMLF-74LVC2G14,IC,D184B!U9A4!//jf4cfls225.pdx.intel.com/apd_proj/ppg_lib/epg_masterlib/logical/mstr_ttl/ttl2g14/chips/chips.prt!TTL2G14!TTL2G14_SMLF-74LVC2G14,IC,D18476-001!TTL2G14!1!!F13!!MIO_CHASSIS!!
S!@baseboard_fab2_lib.baseboard_fab2(sch_1):page175_i18@mstr_ttl.ttl2g14(chips)!TTL2G14_SMLF-74LVC2G14,IC,D184B!U9A3!//jf4cfls225.pdx.intel.com/apd_proj/ppg_lib/epg_masterlib/logical/mstr_ttl/ttl2g14/chips/chips.prt!TTL2G14!TTL2G14_SMLF-74LVC2G14,IC,D18476-001!TTL2G14!1!!F16!!MIO_CHASSIS!!
S!@baseboard_fab2_lib.baseboard_fab2(sch_1):page175_i15@mstr_ttl.ttl2g14(chips)!TTL2G14_SMLF-74LVC2G14,IC,D184B!U9A3!//jf4cfls225.pdx.intel.com/apd_proj/ppg_lib/epg_masterlib/logical/mstr_ttl/ttl2g14/chips/chips.prt!TTL2G14!TTL2G14_SMLF-74LVC2G14,IC,D18476-001!TTL2G14!1!!F15!!MIO_CHASSIS!!
S!@baseboard_fab2_lib.baseboard_fab2(sch_1):page195_i76@mstr_misc.captive_screw(chips)!CAPTIVE_SCREW_TH-HDW,H57868-001!RM1G1!//jf4cfls225.pdx.intel.com/apd_proj/ppg_lib/epg_masterlib/logical/mstr_misc/captive_screw/chips/chips.prt!CAPTIVE_SCREW!CAPTIVE_SCREW_TH-HDW,H57868-001!CAPTIVE_SCREW_TH!!!TF-10868!!MOUNTING_HOLES!!
S!@baseboard_fab2_lib.baseboard_fab2(sch_1):page156_i269@mstr_ttl.ttl2g07(chips)!TTL2G07_SOT23LF-74LVC2G07,IC,DB!U8G1!//jf4cfls225.pdx.intel.com/apd_proj/ppg_lib/epg_masterlib/logical/mstr_ttl/ttl2g07/chips/chips.prt!TTL2G07!TTL2G07_SOT23LF-74LVC2G07,IC,D22707-001!TTL2G07_SOT23LF!!!F19!!BMC_MISC!!
S!@baseboard_fab2_lib.baseboard_fab2(sch_1):page156_i201@mstr_ttl.ttl2g07(chips)!TTL2G07_SOT23LF-74LVC2G07,IC,DB!U8F3!//jf4cfls225.pdx.intel.com/apd_proj/ppg_lib/epg_masterlib/logical/mstr_ttl/ttl2g07/chips/chips.prt!TTL2G07!TTL2G07_SOT23LF-74LVC2G07,IC,D22707-001!TTL2G07_SOT23LF!!!F20!!BMC_MISC!!
S!@baseboard_fab2_lib.baseboard_fab2(sch_1):page165_i79@mstr_discrete.ferrite(chips)!FERRITE_SMLF-60,FB,693286-001!FB1U2!//jf4cfls225.pdx.intel.com/apd_proj/ppg_lib/epg_masterlib/logical/mstr_discrete/ferrite/chips/chips.prt!FERRITE!FERRITE_SMLF-60,FB,693286-001!FERRITE!!!F2185!!HEC_VOLT_MONITOR!!
S!@baseboard_fab2_lib.baseboard_fab2(sch_1):page185_i53@mstr_sconn.sconn75k_h17033002(chips)!SCONN75K_H17033002_SMT1-SCONN,A!J8F1!//jf4cfls225.pdx.intel.com/apd_proj/ppg_lib/epg_masterlib/logical/mstr_sconn/sconn75k_h17033002/chips/chips.prt!SCONN75K_H17033002!SCONN75K_H17033002_SMT1-SCONN,H17033-002!SCONN75K_H17033002_SMT1!!!F133!!M_2!!
S!@baseboard_fab2_lib.baseboard_fab2(sch_1):page157_i374@mstr_ttl.ttl1g07_a(chips)!TTL1G07_A_SOP-74LVC1G07,IC,C88B!U8D2!//jf4cfls225.pdx.intel.com/apd_proj/ppg_lib/epg_masterlib/logical/mstr_ttl/ttl1g07_a/chips/chips.prt!TTL1G07_A!TTL1G07_A_SOP-74LVC1G07,IC,C88419-001!TTL1G07_A_SOP!!!F38!!!!
S!@baseboard_fab2_lib.baseboard_fab2(sch_1):page155_i178@mstr_ttl.ttl1g07_a(chips)!TTL1G07_A_SOP-74LVC1G07,IC,C88B!U9A1!//jf4cfls225.pdx.intel.com/apd_proj/ppg_lib/epg_masterlib/logical/mstr_ttl/ttl1g07_a/chips/chips.prt!TTL1G07_A!TTL1G07_A_SOP-74LVC1G07,IC,C88419-001!TTL1G07_A_SOP!!!F34!!BMC_DEBUG_HEADER!!
S!@baseboard_fab2_lib.baseboard_fab2(sch_1):page111_i85@mstr_ttl.ttl1g07_a(chips)!TTL1G07_A_SOP-74LVC1G07,IC,C88B!U1L4!//jf4cfls225.pdx.intel.com/apd_proj/ppg_lib/epg_masterlib/logical/mstr_ttl/ttl1g07_a/chips/chips.prt!TTL1G07_A!TTL1G07_A_SOP-74LVC1G07,IC,C88419-001!TTL1G07_A_SOP!!!F41!!M-SATA!!
S!@baseboard_fab2_lib.baseboard_fab2(sch_1):page170_i46@mstr_ttl.ttl1g07_a(chips)!TTL1G07_A_SOP-74LVC1G07,IC,C88B!U1R1!//jf4cfls225.pdx.intel.com/apd_proj/ppg_lib/epg_masterlib/logical/mstr_ttl/ttl1g07_a/chips/chips.prt!TTL1G07_A!TTL1G07_A_SOP-74LVC1G07,IC,C88419-001!TTL1G07_A_SOP!!!F40!!FAST_PROCHOT!!
S!@baseboard_fab2_lib.baseboard_fab2(sch_1):page170_i4@mstr_ttl.ttl1g07_a(chips)!TTL1G07_A_SOP-74LVC1G07,IC,C88B!U8D3!//jf4cfls225.pdx.intel.com/apd_proj/ppg_lib/epg_masterlib/logical/mstr_ttl/ttl1g07_a/chips/chips.prt!TTL1G07_A!TTL1G07_A_SOP-74LVC1G07,IC,C88419-001!TTL1G07_A_SOP!!!F37!!FAST_PROCHOT!!
S!@baseboard_fab2_lib.baseboard_fab2(sch_1):page185_i110@mstr_ttl.ttl1g07_a(chips)!TTL1G07_A_SOP-74LVC1G07,IC,C88B!U2P1!//jf4cfls225.pdx.intel.com/apd_proj/ppg_lib/epg_masterlib/logical/mstr_ttl/ttl1g07_a/chips/chips.prt!TTL1G07_A!TTL1G07_A_SOP-74LVC1G07,IC,C88419-001!TTL1G07_A_SOP!!!F39!!M_2!!
S!@baseboard_fab2_lib.baseboard_fab2(sch_1):page161_i88@mstr_ttl.ttl1g07_a(chips)!TTL1G07_A_SOP-74LVC1G07,IC,C88B!U8G2!//jf4cfls225.pdx.intel.com/apd_proj/ppg_lib/epg_masterlib/logical/mstr_ttl/ttl1g07_a/chips/chips.prt!TTL1G07_A!TTL1G07_A_SOP-74LVC1G07,IC,C88419-001!TTL1G07_A_SOP!!!F36!!CPU_FANS!!
S!@baseboard_fab2_lib.baseboard_fab2(sch_1):page161_i92@mstr_ttl.ttl1g07_a(chips)!TTL1G07_A_SOP-74LVC1G07,IC,C88B!U8G3!//jf4cfls225.pdx.intel.com/apd_proj/ppg_lib/epg_masterlib/logical/mstr_ttl/ttl1g07_a/chips/chips.prt!TTL1G07_A!TTL1G07_A_SOP-74LVC1G07,IC,C88419-001!TTL1G07_A_SOP!!!F35!!CPU_FANS!!
S!@baseboard_fab2_lib.baseboard_fab2(sch_1):page151_i69@mstr_ttl.ttl1g07_a(chips)!TTL1G07_A_SOP-74LVC1G07,IC,C88B!U9F3!//jf4cfls225.pdx.intel.com/apd_proj/ppg_lib/epg_masterlib/logical/mstr_ttl/ttl1g07_a/chips/chips.prt!TTL1G07_A!TTL1G07_A_SOP-74LVC1G07,IC,C88419-001!TTL1G07_A_SOP!!!F33!!BMC_MEMORY!!
S!@baseboard_fab2_lib.baseboard_fab2(sch_1):page196_i128@mstr_discrete.diode(chips)!DIODE_SMLF-BAT54WS,IC,C73510-0A!CR8E1!//jf4cfls225.pdx.intel.com/apd_proj/ppg_lib/epg_masterlib/logical/mstr_discrete/diode/chips/chips.prt!DIODE!DIODE_SMLF-BAT54WS,IC,C73510-001!DIODE_SMLF!!!F2208!!!!
S!@baseboard_fab2_lib.baseboard_fab2(sch_1):page196_i103@mstr_discrete.diode(chips)!DIODE_SMLF-BAT54WS,IC,C73510-0A!CR7E1!//jf4cfls225.pdx.intel.com/apd_proj/ppg_lib/epg_masterlib/logical/mstr_discrete/diode/chips/chips.prt!DIODE!DIODE_SMLF-BAT54WS,IC,C73510-001!DIODE_SMLF!!!F2207!!!!
S!@baseboard_fab2_lib.baseboard_fab2(sch_1):page200_i213@mstr_discrete.diode(chips)!DIODE_SMLF-BAT54WS,IC,C73510-0A!CR9P2!//jf4cfls225.pdx.intel.com/apd_proj/ppg_lib/epg_masterlib/logical/mstr_discrete/diode/chips/chips.prt!DIODE!DIODE_SMLF-BAT54WS,IC,C73510-001!DIODE_SMLF!!!F2205!!!!
S!@baseboard_fab2_lib.baseboard_fab2(sch_1):page200_i214@mstr_discrete.diode(chips)!DIODE_SMLF-BAT54WS,IC,C73510-0A!CR9P1!//jf4cfls225.pdx.intel.com/apd_proj/ppg_lib/epg_masterlib/logical/mstr_discrete/diode/chips/chips.prt!DIODE!DIODE_SMLF-BAT54WS,IC,C73510-001!DIODE_SMLF!!!F2206!!!!
S!@baseboard_fab2_lib.baseboard_fab2(sch_1):page199_i100@mstr_discrete.res(chips)!RES_0402-40.2K,1%,1/16W,CHIP,GA!R1D40!//jf4cfls225.pdx.intel.com/apd_proj/ppg_lib/epg_masterlib/logical/mstr_discrete/res/chips/chips.prt!RES!RES_0402-40.2K,1%,1/16W,CHIP,G21796-133!RES!!!F494!!HOT_SWAP!!
S!@baseboard_fab2_lib.baseboard_fab2(sch_1):page168_i7@mstr_discrete.res(chips)!RES_0402-40.2K,1%,1/16W,CHIP,GA!R1L4!//jf4cfls225.pdx.intel.com/apd_proj/ppg_lib/epg_masterlib/logical/mstr_discrete/res/chips/chips.prt!RES!RES_0402-40.2K,1%,1/16W,CHIP,G21796-133!RES!!!F493!!UART_MUX!!
S!@baseboard_fab2_lib.baseboard_fab2(sch_1):page223_i77@mstr_discrete.res(chips)!RES_0402-4.02K,1%,1/16W,CHIP,GA!R1G23!//jf4cfls225.pdx.intel.com/apd_proj/ppg_lib/epg_masterlib/logical/mstr_discrete/res/chips/chips.prt!RES!RES_0402-4.02K,1%,1/16W,CHIP,G21796-082!RES!!!F658!!VDDQ_GHJ_PWR_VR!!
S!@baseboard_fab2_lib.baseboard_fab2(sch_1):page235_i176@mstr_discrete.res(chips)!RES_0402-4.02K,1%,1/16W,CHIP,GA!R2L9!//jf4cfls225.pdx.intel.com/apd_proj/ppg_lib/epg_masterlib/logical/mstr_discrete/res/chips/chips.prt!RES!RES_0402-4.02K,1%,1/16W,CHIP,G21796-082!RES!!!F657!!PVNN_PCH_STBY!!
S!@baseboard_fab2_lib.baseboard_fab2(sch_1):page211_i65@mstr_discrete.res(chips)!RES_0402-4.02K,1%,1/16W,CHIP,GA!R3N22!//jf4cfls225.pdx.intel.com/apd_proj/ppg_lib/epg_masterlib/logical/mstr_discrete/res/chips/chips.prt!RES!RES_0402-4.02K,1%,1/16W,CHIP,G21796-082!RES!!!F656!!!!
S!@baseboard_fab2_lib.baseboard_fab2(sch_1):page201_i120@mstr_discrete.res(chips)!RES_0402-4.02K,1%,1/16W,CHIP,GA!R6P27!//jf4cfls225.pdx.intel.com/apd_proj/ppg_lib/epg_masterlib/logical/mstr_discrete/res/chips/chips.prt!RES!RES_0402-4.02K,1%,1/16W,CHIP,G21796-082!RES!!!F655!!PVCCIN_CPU0_VR!!
S!@baseboard_fab2_lib.baseboard_fab2(sch_1):page201_i121@mstr_discrete.res(chips)!RES_0402-4.02K,1%,1/16W,CHIP,GA!R6P28!//jf4cfls225.pdx.intel.com/apd_proj/ppg_lib/epg_masterlib/logical/mstr_discrete/res/chips/chips.prt!RES!RES_0402-4.02K,1%,1/16W,CHIP,G21796-082!RES!!!F654!!PVCCIN_CPU0_VR!!
S!@baseboard_fab2_lib.baseboard_fab2(sch_1):page215_i321@mstr_discrete.res(chips)!RES_0402-4.02K,1%,1/16W,CHIP,GA!R7G8!//jf4cfls225.pdx.intel.com/apd_proj/ppg_lib/epg_masterlib/logical/mstr_discrete/res/chips/chips.prt!RES!RES_0402-4.02K,1%,1/16W,CHIP,G21796-082!RES!!!F653!!VDDQ_ABC_PWR_VR!!
S!@baseboard_fab2_lib.baseboard_fab2(sch_1):page206_i112@mstr_discrete.res(chips)!RES_0402-4.02K,1%,1/16W,CHIP,GA!R9N8!//jf4cfls225.pdx.intel.com/apd_proj/ppg_lib/epg_masterlib/logical/mstr_discrete/res/chips/chips.prt!RES!RES_0402-4.02K,1%,1/16W,CHIP,G21796-082!RES!!!F652!!PVCCIN_CPU1_VR!!
S!@baseboard_fab2_lib.baseboard_fab2(sch_1):page194_i155@mstr_discrete.res(chips)!RES_0402-4.02K,1%,1/16W,CHIP,GA!R7C24!//jf4cfls225.pdx.intel.com/apd_proj/ppg_lib/epg_masterlib/logical/mstr_discrete/res/chips/chips.prt!RES!RES_0402-4.02K,1%,1/16W,CHIP,G21796-082!RES!!!F651!!PVCCIN_CPU1_VR!!
S!@baseboard_fab2_lib.baseboard_fab2(sch_1):page218_i37@mstr_discrete.res(chips)!RES_0402-8.06K,1%,1/16W,CHIP,GA!R7A8!//jf4cfls225.pdx.intel.com/apd_proj/ppg_lib/epg_masterlib/logical/mstr_discrete/res/chips/chips.prt!RES!RES_0402-8.06K,1%,1/16W,CHIP,G21796-078!RES!!!F298!!VDDQ_DEF_PWR_VR!!
S!@baseboard_fab2_lib.baseboard_fab2(sch_1):page215_i317@mstr_discrete.res(chips)!RES_0402-8.06K,1%,1/16W,CHIP,GA!R7G10!//jf4cfls225.pdx.intel.com/apd_proj/ppg_lib/epg_masterlib/logical/mstr_discrete/res/chips/chips.prt!RES!RES_0402-8.06K,1%,1/16W,CHIP,G21796-078!RES!!!F297!!VDDQ_ABC_PWR_VR!!
S!@baseboard_fab2_lib.baseboard_fab2(sch_1):page193_i169@mstr_discrete.res(chips)!RES_0402-8.06K,1%,1/16W,CHIP,GA!R4C12!//jf4cfls225.pdx.intel.com/apd_proj/ppg_lib/epg_masterlib/logical/mstr_discrete/res/chips/chips.prt!RES!RES_0402-8.06K,1%,1/16W,CHIP,G21796-078!RES!!!F296!!PVCCIN_CPU0_VR!!
S!@baseboard_fab2_lib.baseboard_fab2(sch_1):page217_i250@mstr_discrete.cap(chips)!CAP_0603-22.0UF,4V,20%,X6S,E15A!C5G11!//jf4cfls225.pdx.intel.com/apd_proj/ppg_lib/epg_masterlib/logical/mstr_discrete/cap/chips/chips.prt!CAP!CAP_0603-22.0UF,4V,20%,X6S,E15431-004!CAP!!!F2864!!PVDDQ_ABC!!
S!@baseboard_fab2_lib.baseboard_fab2(sch_1):page217_i240@mstr_discrete.cap(chips)!CAP_0603-22.0UF,4V,20%,X6S,E15A!C5G13!//jf4cfls225.pdx.intel.com/apd_proj/ppg_lib/epg_masterlib/logical/mstr_discrete/cap/chips/chips.prt!CAP!CAP_0603-22.0UF,4V,20%,X6S,E15431-004!CAP!!!F2862!!PVDDQ_ABC!!
S!@baseboard_fab2_lib.baseboard_fab2(sch_1):page225_i236@mstr_discrete.cap(chips)!CAP_0603-22.0UF,4V,20%,X6S,E15A!C8U3!//jf4cfls225.pdx.intel.com/apd_proj/ppg_lib/epg_masterlib/logical/mstr_discrete/cap/chips/chips.prt!CAP!CAP_0603-22.0UF,4V,20%,X6S,E15431-004!CAP!!!F2758!!PVDDQ_ABC!!
S!@baseboard_fab2_lib.baseboard_fab2(sch_1):page217_i231@mstr_discrete.cap(chips)!CAP_0603-22.0UF,4V,20%,X6S,E15A!C5G1!//jf4cfls225.pdx.intel.com/apd_proj/ppg_lib/epg_masterlib/logical/mstr_discrete/cap/chips/chips.prt!CAP!CAP_0603-22.0UF,4V,20%,X6S,E15431-004!CAP!!!F2872!!PVDDQ_ABC!!
S!@baseboard_fab2_lib.baseboard_fab2(sch_1):page217_i223@mstr_discrete.cap(chips)!CAP_0603-22.0UF,4V,20%,X6S,E15A!C5G14!//jf4cfls225.pdx.intel.com/apd_proj/ppg_lib/epg_masterlib/logical/mstr_discrete/cap/chips/chips.prt!CAP!CAP_0603-22.0UF,4V,20%,X6S,E15431-004!CAP!!!F2861!!PVDDQ_ABC!!
S!@baseboard_fab2_lib.baseboard_fab2(sch_1):page220_i219@mstr_discrete.cap(chips)!CAP_0603-22.0UF,4V,20%,X6S,E15A!C5A1!//jf4cfls225.pdx.intel.com/apd_proj/ppg_lib/epg_masterlib/logical/mstr_discrete/cap/chips/chips.prt!CAP!CAP_0603-22.0UF,4V,20%,X6S,E15431-004!CAP!!!F2938!!PVDDQ_DEF!!
S!@baseboard_fab2_lib.baseboard_fab2(sch_1):page220_i214@mstr_discrete.cap(chips)!CAP_0603-22.0UF,4V,20%,X6S,E15A!C5A2!//jf4cfls225.pdx.intel.com/apd_proj/ppg_lib/epg_masterlib/logical/mstr_discrete/cap/chips/chips.prt!CAP!CAP_0603-22.0UF,4V,20%,X6S,E15431-004!CAP!!!F2937!!PVDDQ_DEF!!
S!@baseboard_fab2_lib.baseboard_fab2(sch_1):page220_i210@mstr_discrete.cap(chips)!CAP_0603-22.0UF,4V,20%,X6S,E15A!C5A3!//jf4cfls225.pdx.intel.com/apd_proj/ppg_lib/epg_masterlib/logical/mstr_discrete/cap/chips/chips.prt!CAP!CAP_0603-22.0UF,4V,20%,X6S,E15431-004!CAP!!!F2936!!PVDDQ_DEF!!
S!@baseboard_fab2_lib.baseboard_fab2(sch_1):page220_i206@mstr_discrete.cap(chips)!CAP_0603-22.0UF,4V,20%,X6S,E15A!C5A4!//jf4cfls225.pdx.intel.com/apd_proj/ppg_lib/epg_masterlib/logical/mstr_discrete/cap/chips/chips.prt!CAP!CAP_0603-22.0UF,4V,20%,X6S,E15431-004!CAP!!!F2935!!PVDDQ_DEF!!
S!@baseboard_fab2_lib.baseboard_fab2(sch_1):page225_i241@mstr_discrete.cap(chips)!CAP_0603-22.0UF,4V,20%,X6S,E15A!C8U7!//jf4cfls225.pdx.intel.com/apd_proj/ppg_lib/epg_masterlib/logical/mstr_discrete/cap/chips/chips.prt!CAP!CAP_0603-22.0UF,4V,20%,X6S,E15431-004!CAP!!!F2754!!PVDDQ_GHJ!!
S!@baseboard_fab2_lib.baseboard_fab2(sch_1):page225_i232@mstr_discrete.cap(chips)!CAP_0603-22.0UF,4V,20%,X6S,E15A!C8U6!//jf4cfls225.pdx.intel.com/apd_proj/ppg_lib/epg_masterlib/logical/mstr_discrete/cap/chips/chips.prt!CAP!CAP_0603-22.0UF,4V,20%,X6S,E15431-004!CAP!!!F2755!!PVDDQ_GHJ!!
S!@baseboard_fab2_lib.baseboard_fab2(sch_1):page225_i228@mstr_discrete.cap(chips)!CAP_0603-22.0UF,4V,20%,X6S,E15A!C8U5!//jf4cfls225.pdx.intel.com/apd_proj/ppg_lib/epg_masterlib/logical/mstr_discrete/cap/chips/chips.prt!CAP!CAP_0603-22.0UF,4V,20%,X6S,E15431-004!CAP!!!F2756!!PVDDQ_GHJ!!
S!@baseboard_fab2_lib.baseboard_fab2(sch_1):page228_i243@mstr_discrete.cap(chips)!CAP_0603-22.0UF,4V,20%,X6S,E15A!C8M1!//jf4cfls225.pdx.intel.com/apd_proj/ppg_lib/epg_masterlib/logical/mstr_discrete/cap/chips/chips.prt!CAP!CAP_0603-22.0UF,4V,20%,X6S,E15431-004!CAP!!!F2770!!PVDDQ_KLM!!
S!@baseboard_fab2_lib.baseboard_fab2(sch_1):page228_i238@mstr_discrete.cap(chips)!CAP_0603-22.0UF,4V,20%,X6S,E15A!C7L4!//jf4cfls225.pdx.intel.com/apd_proj/ppg_lib/epg_masterlib/logical/mstr_discrete/cap/chips/chips.prt!CAP!CAP_0603-22.0UF,4V,20%,X6S,E15431-004!CAP!!!F2796!!PVDDQ_KLM!!
S!@baseboard_fab2_lib.baseboard_fab2(sch_1):page228_i234@mstr_discrete.cap(chips)!CAP_0603-22.0UF,4V,20%,X6S,E15A!C2A4!//jf4cfls225.pdx.intel.com/apd_proj/ppg_lib/epg_masterlib/logical/mstr_discrete/cap/chips/chips.prt!CAP!CAP_0603-22.0UF,4V,20%,X6S,E15431-004!CAP!!!F3057!!PVDDQ_KLM!!
S!@baseboard_fab2_lib.baseboard_fab2(sch_1):page228_i230@mstr_discrete.cap(chips)!CAP_0603-22.0UF,4V,20%,X6S,E15A!C2A3!//jf4cfls225.pdx.intel.com/apd_proj/ppg_lib/epg_masterlib/logical/mstr_discrete/cap/chips/chips.prt!CAP!CAP_0603-22.0UF,4V,20%,X6S,E15431-004!CAP!!!F3058!!PVDDQ_KLM!!
S!@baseboard_fab2_lib.baseboard_fab2(sch_1):page217_i246@mstr_discrete.cap(chips)!CAP_0603-22.0UF,4V,20%,X6S,E15A!C5G12!//jf4cfls225.pdx.intel.com/apd_proj/ppg_lib/epg_masterlib/logical/mstr_discrete/cap/chips/chips.prt!CAP!CAP_0603-22.0UF,4V,20%,X6S,E15431-004!CAP!!!F2863!!PVDDQ_ABC!!
S!@baseboard_fab2_lib.baseboard_fab2(sch_1):page217_i245@mstr_discrete.cap(chips)!CAP_0603-22.0UF,4V,20%,X6S,E15A!C5G2!//jf4cfls225.pdx.intel.com/apd_proj/ppg_lib/epg_masterlib/logical/mstr_discrete/cap/chips/chips.prt!CAP!CAP_0603-22.0UF,4V,20%,X6S,E15431-004!CAP!!!F2871!!PVDDQ_ABC!!
S!@baseboard_fab2_lib.baseboard_fab2(sch_1):page217_i241@mstr_discrete.cap(chips)!CAP_0603-22.0UF,4V,20%,X6S,E15A!C5G4!//jf4cfls225.pdx.intel.com/apd_proj/ppg_lib/epg_masterlib/logical/mstr_discrete/cap/chips/chips.prt!CAP!CAP_0603-22.0UF,4V,20%,X6S,E15431-004!CAP!!!F2869!!PVDDQ_ABC!!
S!@baseboard_fab2_lib.baseboard_fab2(sch_1):page217_i237@mstr_discrete.cap(chips)!CAP_0603-22.0UF,4V,20%,X6S,E15A!C5G6!//jf4cfls225.pdx.intel.com/apd_proj/ppg_lib/epg_masterlib/logical/mstr_discrete/cap/chips/chips.prt!CAP!CAP_0603-22.0UF,4V,20%,X6S,E15431-004!CAP!!!F2867!!PVDDQ_ABC!!
S!@baseboard_fab2_lib.baseboard_fab2(sch_1):page217_i235@mstr_discrete.cap(chips)!CAP_0603-22.0UF,4V,20%,X6S,E15A!C5G5!//jf4cfls225.pdx.intel.com/apd_proj/ppg_lib/epg_masterlib/logical/mstr_discrete/cap/chips/chips.prt!CAP!CAP_0603-22.0UF,4V,20%,X6S,E15431-004!CAP!!!F2868!!PVDDQ_ABC!!
S!@baseboard_fab2_lib.baseboard_fab2(sch_1):page217_i234@mstr_discrete.cap(chips)!CAP_0603-22.0UF,4V,20%,X6S,E15A!C5G7!//jf4cfls225.pdx.intel.com/apd_proj/ppg_lib/epg_masterlib/logical/mstr_discrete/cap/chips/chips.prt!CAP!CAP_0603-22.0UF,4V,20%,X6S,E15431-004!CAP!!!F2866!!PVDDQ_ABC!!
S!@baseboard_fab2_lib.baseboard_fab2(sch_1):page217_i230@mstr_discrete.cap(chips)!CAP_0603-22.0UF,4V,20%,X6S,E15A!C5G8!//jf4cfls225.pdx.intel.com/apd_proj/ppg_lib/epg_masterlib/logical/mstr_discrete/cap/chips/chips.prt!CAP!CAP_0603-22.0UF,4V,20%,X6S,E15431-004!CAP!!!F2865!!PVDDQ_ABC!!
S!@baseboard_fab2_lib.baseboard_fab2(sch_1):page217_i227@mstr_discrete.cap(chips)!CAP_0603-22.0UF,4V,20%,X6S,E15A!C5G18!//jf4cfls225.pdx.intel.com/apd_proj/ppg_lib/epg_masterlib/logical/mstr_discrete/cap/chips/chips.prt!CAP!CAP_0603-22.0UF,4V,20%,X6S,E15431-004!CAP!!!F2857!!PVDDQ_ABC!!
S!@baseboard_fab2_lib.baseboard_fab2(sch_1):page217_i226@mstr_discrete.cap(chips)!CAP_0603-22.0UF,4V,20%,X6S,E15A!C5G17!//jf4cfls225.pdx.intel.com/apd_proj/ppg_lib/epg_masterlib/logical/mstr_discrete/cap/chips/chips.prt!CAP!CAP_0603-22.0UF,4V,20%,X6S,E15431-004!CAP!!!F2858!!PVDDQ_ABC!!
S!@baseboard_fab2_lib.baseboard_fab2(sch_1):page217_i221@mstr_discrete.cap(chips)!CAP_0603-22.0UF,4V,20%,X6S,E15A!C5G16!//jf4cfls225.pdx.intel.com/apd_proj/ppg_lib/epg_masterlib/logical/mstr_discrete/cap/chips/chips.prt!CAP!CAP_0603-22.0UF,4V,20%,X6S,E15431-004!CAP!!!F2859!!PVDDQ_ABC!!
S!@baseboard_fab2_lib.baseboard_fab2(sch_1):page217_i220@mstr_discrete.cap(chips)!CAP_0603-22.0UF,4V,20%,X6S,E15A!C5G15!//jf4cfls225.pdx.intel.com/apd_proj/ppg_lib/epg_masterlib/logical/mstr_discrete/cap/chips/chips.prt!CAP!CAP_0603-22.0UF,4V,20%,X6S,E15431-004!CAP!!!F2860!!PVDDQ_ABC!!
S!@baseboard_fab2_lib.baseboard_fab2(sch_1):page217_i217@mstr_discrete.cap(chips)!CAP_0603-22.0UF,4V,20%,X6S,E15A!C5G3!//jf4cfls225.pdx.intel.com/apd_proj/ppg_lib/epg_masterlib/logical/mstr_discrete/cap/chips/chips.prt!CAP!CAP_0603-22.0UF,4V,20%,X6S,E15431-004!CAP!!!F2870!!PVDDQ_ABC!!
S!@baseboard_fab2_lib.baseboard_fab2(sch_1):page220_i217@mstr_discrete.cap(chips)!CAP_0603-22.0UF,4V,20%,X6S,E15A!C5A15!//jf4cfls225.pdx.intel.com/apd_proj/ppg_lib/epg_masterlib/logical/mstr_discrete/cap/chips/chips.prt!CAP!CAP_0603-22.0UF,4V,20%,X6S,E15431-004!CAP!!!F2926!!PVDDQ_DEF!!
S!@baseboard_fab2_lib.baseboard_fab2(sch_1):page220_i216@mstr_discrete.cap(chips)!CAP_0603-22.0UF,4V,20%,X6S,E15A!C5A12!//jf4cfls225.pdx.intel.com/apd_proj/ppg_lib/epg_masterlib/logical/mstr_discrete/cap/chips/chips.prt!CAP!CAP_0603-22.0UF,4V,20%,X6S,E15431-004!CAP!!!F2929!!PVDDQ_DEF!!
S!@baseboard_fab2_lib.baseboard_fab2(sch_1):page220_i215@mstr_discrete.cap(chips)!CAP_0603-22.0UF,4V,20%,X6S,E15A!C5A13!//jf4cfls225.pdx.intel.com/apd_proj/ppg_lib/epg_masterlib/logical/mstr_discrete/cap/chips/chips.prt!CAP!CAP_0603-22.0UF,4V,20%,X6S,E15431-004!CAP!!!F2928!!PVDDQ_DEF!!
S!@baseboard_fab2_lib.baseboard_fab2(sch_1):page220_i213@mstr_discrete.cap(chips)!CAP_0603-22.0UF,4V,20%,X6S,E15A!C5A14!//jf4cfls225.pdx.intel.com/apd_proj/ppg_lib/epg_masterlib/logical/mstr_discrete/cap/chips/chips.prt!CAP!CAP_0603-22.0UF,4V,20%,X6S,E15431-004!CAP!!!F2927!!PVDDQ_DEF!!
S!@baseboard_fab2_lib.baseboard_fab2(sch_1):page220_i212@mstr_discrete.cap(chips)!CAP_0603-22.0UF,4V,20%,X6S,E15A!C5A6!//jf4cfls225.pdx.intel.com/apd_proj/ppg_lib/epg_masterlib/logical/mstr_discrete/cap/chips/chips.prt!CAP!CAP_0603-22.0UF,4V,20%,X6S,E15431-004!CAP!!!F2934!!PVDDQ_DEF!!
S!@baseboard_fab2_lib.baseboard_fab2(sch_1):page220_i211@mstr_discrete.cap(chips)!CAP_0603-22.0UF,4V,20%,X6S,E15A!C5A7!//jf4cfls225.pdx.intel.com/apd_proj/ppg_lib/epg_masterlib/logical/mstr_discrete/cap/chips/chips.prt!CAP!CAP_0603-22.0UF,4V,20%,X6S,E15431-004!CAP!!!F2933!!PVDDQ_DEF!!
S!@baseboard_fab2_lib.baseboard_fab2(sch_1):page220_i209@mstr_discrete.cap(chips)!CAP_0603-22.0UF,4V,20%,X6S,E15A!C5A8!//jf4cfls225.pdx.intel.com/apd_proj/ppg_lib/epg_masterlib/logical/mstr_discrete/cap/chips/chips.prt!CAP!CAP_0603-22.0UF,4V,20%,X6S,E15431-004!CAP!!!F2932!!PVDDQ_DEF!!
S!@baseboard_fab2_lib.baseboard_fab2(sch_1):page220_i208@mstr_discrete.cap(chips)!CAP_0603-22.0UF,4V,20%,X6S,E15A!C5A9!//jf4cfls225.pdx.intel.com/apd_proj/ppg_lib/epg_masterlib/logical/mstr_discrete/cap/chips/chips.prt!CAP!CAP_0603-22.0UF,4V,20%,X6S,E15431-004!CAP!!!F2931!!PVDDQ_DEF!!
S!@baseboard_fab2_lib.baseboard_fab2(sch_1):page220_i207@mstr_discrete.cap(chips)!CAP_0603-22.0UF,4V,20%,X6S,E15A!C5A16!//jf4cfls225.pdx.intel.com/apd_proj/ppg_lib/epg_masterlib/logical/mstr_discrete/cap/chips/chips.prt!CAP!CAP_0603-22.0UF,4V,20%,X6S,E15431-004!CAP!!!F2925!!PVDDQ_DEF!!
S!@baseboard_fab2_lib.baseboard_fab2(sch_1):page220_i205@mstr_discrete.cap(chips)!CAP_0603-22.0UF,4V,20%,X6S,E15A!C5A17!//jf4cfls225.pdx.intel.com/apd_proj/ppg_lib/epg_masterlib/logical/mstr_discrete/cap/chips/chips.prt!CAP!CAP_0603-22.0UF,4V,20%,X6S,E15431-004!CAP!!!F2924!!PVDDQ_DEF!!
S!@baseboard_fab2_lib.baseboard_fab2(sch_1):page220_i204@mstr_discrete.cap(chips)!CAP_0603-22.0UF,4V,20%,X6S,E15A!C5A18!//jf4cfls225.pdx.intel.com/apd_proj/ppg_lib/epg_masterlib/logical/mstr_discrete/cap/chips/chips.prt!CAP!CAP_0603-22.0UF,4V,20%,X6S,E15431-004!CAP!!!F2923!!PVDDQ_DEF!!
S!@baseboard_fab2_lib.baseboard_fab2(sch_1):page220_i203@mstr_discrete.cap(chips)!CAP_0603-22.0UF,4V,20%,X6S,E15A!C5A19!//jf4cfls225.pdx.intel.com/apd_proj/ppg_lib/epg_masterlib/logical/mstr_discrete/cap/chips/chips.prt!CAP!CAP_0603-22.0UF,4V,20%,X6S,E15431-004!CAP!!!F2922!!PVDDQ_DEF!!
S!@baseboard_fab2_lib.baseboard_fab2(sch_1):page225_i239@mstr_discrete.cap(chips)!CAP_0603-22.0UF,4V,20%,X6S,E15A!C8U2!//jf4cfls225.pdx.intel.com/apd_proj/ppg_lib/epg_masterlib/logical/mstr_discrete/cap/chips/chips.prt!CAP!CAP_0603-22.0UF,4V,20%,X6S,E15431-004!CAP!!!F2759!!PVDDQ_GHJ!!
S!@baseboard_fab2_lib.baseboard_fab2(sch_1):page225_i238@mstr_discrete.cap(chips)!CAP_0603-22.0UF,4V,20%,X6S,E15A!C7U2!//jf4cfls225.pdx.intel.com/apd_proj/ppg_lib/epg_masterlib/logical/mstr_discrete/cap/chips/chips.prt!CAP!CAP_0603-22.0UF,4V,20%,X6S,E15431-004!CAP!!!F2786!!PVDDQ_GHJ!!
S!@baseboard_fab2_lib.baseboard_fab2(sch_1):page225_i237@mstr_discrete.cap(chips)!CAP_0603-22.0UF,4V,20%,X6S,E15A!C7U1!//jf4cfls225.pdx.intel.com/apd_proj/ppg_lib/epg_masterlib/logical/mstr_discrete/cap/chips/chips.prt!CAP!CAP_0603-22.0UF,4V,20%,X6S,E15431-004!CAP!!!F2787!!PVDDQ_GHJ!!
S!@baseboard_fab2_lib.baseboard_fab2(sch_1):page225_i235@mstr_discrete.cap(chips)!CAP_0603-22.0UF,4V,20%,X6S,E15A!C7T4!//jf4cfls225.pdx.intel.com/apd_proj/ppg_lib/epg_masterlib/logical/mstr_discrete/cap/chips/chips.prt!CAP!CAP_0603-22.0UF,4V,20%,X6S,E15431-004!CAP!!!F2789!!PVDDQ_GHJ!!
S!@baseboard_fab2_lib.baseboard_fab2(sch_1):page225_i234@mstr_discrete.cap(chips)!CAP_0603-22.0UF,4V,20%,X6S,E15A!C7T5!//jf4cfls225.pdx.intel.com/apd_proj/ppg_lib/epg_masterlib/logical/mstr_discrete/cap/chips/chips.prt!CAP!CAP_0603-22.0UF,4V,20%,X6S,E15431-004!CAP!!!F2788!!PVDDQ_GHJ!!
S!@baseboard_fab2_lib.baseboard_fab2(sch_1):page225_i233@mstr_discrete.cap(chips)!CAP_0603-22.0UF,4V,20%,X6S,E15A!C8T5!//jf4cfls225.pdx.intel.com/apd_proj/ppg_lib/epg_masterlib/logical/mstr_discrete/cap/chips/chips.prt!CAP!CAP_0603-22.0UF,4V,20%,X6S,E15431-004!CAP!!!F2765!!PVDDQ_GHJ!!
S!@baseboard_fab2_lib.baseboard_fab2(sch_1):page225_i231@mstr_discrete.cap(chips)!CAP_0603-22.0UF,4V,20%,X6S,E15A!C8T6!//jf4cfls225.pdx.intel.com/apd_proj/ppg_lib/epg_masterlib/logical/mstr_discrete/cap/chips/chips.prt!CAP!CAP_0603-22.0UF,4V,20%,X6S,E15431-004!CAP!!!F2764!!PVDDQ_GHJ!!
S!@baseboard_fab2_lib.baseboard_fab2(sch_1):page225_i230@mstr_discrete.cap(chips)!CAP_0603-22.0UF,4V,20%,X6S,E15A!C8T7!//jf4cfls225.pdx.intel.com/apd_proj/ppg_lib/epg_masterlib/logical/mstr_discrete/cap/chips/chips.prt!CAP!CAP_0603-22.0UF,4V,20%,X6S,E15431-004!CAP!!!F2763!!PVDDQ_GHJ!!
S!@baseboard_fab2_lib.baseboard_fab2(sch_1):page225_i229@mstr_discrete.cap(chips)!CAP_0603-22.0UF,4V,20%,X6S,E15A!C8T8!//jf4cfls225.pdx.intel.com/apd_proj/ppg_lib/epg_masterlib/logical/mstr_discrete/cap/chips/chips.prt!CAP!CAP_0603-22.0UF,4V,20%,X6S,E15431-004!CAP!!!F2762!!PVDDQ_GHJ!!
S!@baseboard_fab2_lib.baseboard_fab2(sch_1):page225_i227@mstr_discrete.cap(chips)!CAP_0603-22.0UF,4V,20%,X6S,E15A!C8T9!//jf4cfls225.pdx.intel.com/apd_proj/ppg_lib/epg_masterlib/logical/mstr_discrete/cap/chips/chips.prt!CAP!CAP_0603-22.0UF,4V,20%,X6S,E15431-004!CAP!!!F2761!!PVDDQ_GHJ!!
S!@baseboard_fab2_lib.baseboard_fab2(sch_1):page225_i226@mstr_discrete.cap(chips)!CAP_0603-22.0UF,4V,20%,X6S,E15A!C8T10!//jf4cfls225.pdx.intel.com/apd_proj/ppg_lib/epg_masterlib/logical/mstr_discrete/cap/chips/chips.prt!CAP!CAP_0603-22.0UF,4V,20%,X6S,E15431-004!CAP!!!F2760!!PVDDQ_GHJ!!
S!@baseboard_fab2_lib.baseboard_fab2(sch_1):page225_i225@mstr_discrete.cap(chips)!CAP_0603-22.0UF,4V,20%,X6S,E15A!C8U4!//jf4cfls225.pdx.intel.com/apd_proj/ppg_lib/epg_masterlib/logical/mstr_discrete/cap/chips/chips.prt!CAP!CAP_0603-22.0UF,4V,20%,X6S,E15431-004!CAP!!!F2757!!PVDDQ_GHJ!!
S!@baseboard_fab2_lib.baseboard_fab2(sch_1):page228_i241@mstr_discrete.cap(chips)!CAP_0603-22.0UF,4V,20%,X6S,E15A!C8L5!//jf4cfls225.pdx.intel.com/apd_proj/ppg_lib/epg_masterlib/logical/mstr_discrete/cap/chips/chips.prt!CAP!CAP_0603-22.0UF,4V,20%,X6S,E15431-004!CAP!!!F2776!!PVDDQ_KLM!!
S!@baseboard_fab2_lib.baseboard_fab2(sch_1):page228_i240@mstr_discrete.cap(chips)!CAP_0603-22.0UF,4V,20%,X6S,E15A!C8L6!//jf4cfls225.pdx.intel.com/apd_proj/ppg_lib/epg_masterlib/logical/mstr_discrete/cap/chips/chips.prt!CAP!CAP_0603-22.0UF,4V,20%,X6S,E15431-004!CAP!!!F2775!!PVDDQ_KLM!!
S!@baseboard_fab2_lib.baseboard_fab2(sch_1):page228_i239@mstr_discrete.cap(chips)!CAP_0603-22.0UF,4V,20%,X6S,E15A!C8L7!//jf4cfls225.pdx.intel.com/apd_proj/ppg_lib/epg_masterlib/logical/mstr_discrete/cap/chips/chips.prt!CAP!CAP_0603-22.0UF,4V,20%,X6S,E15431-004!CAP!!!F2774!!PVDDQ_KLM!!
S!@baseboard_fab2_lib.baseboard_fab2(sch_1):page228_i237@mstr_discrete.cap(chips)!CAP_0603-22.0UF,4V,20%,X6S,E15A!C8L8!//jf4cfls225.pdx.intel.com/apd_proj/ppg_lib/epg_masterlib/logical/mstr_discrete/cap/chips/chips.prt!CAP!CAP_0603-22.0UF,4V,20%,X6S,E15431-004!CAP!!!F2773!!PVDDQ_KLM!!
S!@baseboard_fab2_lib.baseboard_fab2(sch_1):page228_i236@mstr_discrete.cap(chips)!CAP_0603-22.0UF,4V,20%,X6S,E15A!C8L9!//jf4cfls225.pdx.intel.com/apd_proj/ppg_lib/epg_masterlib/logical/mstr_discrete/cap/chips/chips.prt!CAP!CAP_0603-22.0UF,4V,20%,X6S,E15431-004!CAP!!!F2772!!PVDDQ_KLM!!
S!@baseboard_fab2_lib.baseboard_fab2(sch_1):page228_i235@mstr_discrete.cap(chips)!CAP_0603-22.0UF,4V,20%,X6S,E15A!C8M6!//jf4cfls225.pdx.intel.com/apd_proj/ppg_lib/epg_masterlib/logical/mstr_discrete/cap/chips/chips.prt!CAP!CAP_0603-22.0UF,4V,20%,X6S,E15431-004!CAP!!!F2766!!PVDDQ_KLM!!
S!@baseboard_fab2_lib.baseboard_fab2(sch_1):page228_i233@mstr_discrete.cap(chips)!CAP_0603-22.0UF,4V,20%,X6S,E15A!C8M4!//jf4cfls225.pdx.intel.com/apd_proj/ppg_lib/epg_masterlib/logical/mstr_discrete/cap/chips/chips.prt!CAP!CAP_0603-22.0UF,4V,20%,X6S,E15431-004!CAP!!!F2768!!PVDDQ_KLM!!
S!@baseboard_fab2_lib.baseboard_fab2(sch_1):page228_i232@mstr_discrete.cap(chips)!CAP_0603-22.0UF,4V,20%,X6S,E15A!C7M2!//jf4cfls225.pdx.intel.com/apd_proj/ppg_lib/epg_masterlib/logical/mstr_discrete/cap/chips/chips.prt!CAP!CAP_0603-22.0UF,4V,20%,X6S,E15431-004!CAP!!!F2793!!PVDDQ_KLM!!
S!@baseboard_fab2_lib.baseboard_fab2(sch_1):page228_i231@mstr_discrete.cap(chips)!CAP_0603-22.0UF,4V,20%,X6S,E15A!C7M1!//jf4cfls225.pdx.intel.com/apd_proj/ppg_lib/epg_masterlib/logical/mstr_discrete/cap/chips/chips.prt!CAP!CAP_0603-22.0UF,4V,20%,X6S,E15431-004!CAP!!!F2794!!PVDDQ_KLM!!
S!@baseboard_fab2_lib.baseboard_fab2(sch_1):page228_i229@mstr_discrete.cap(chips)!CAP_0603-22.0UF,4V,20%,X6S,E15A!C8L10!//jf4cfls225.pdx.intel.com/apd_proj/ppg_lib/epg_masterlib/logical/mstr_discrete/cap/chips/chips.prt!CAP!CAP_0603-22.0UF,4V,20%,X6S,E15431-004!CAP!!!F2771!!PVDDQ_KLM!!
S!@baseboard_fab2_lib.baseboard_fab2(sch_1):page228_i228@mstr_discrete.cap(chips)!CAP_0603-22.0UF,4V,20%,X6S,E15A!C8M5!//jf4cfls225.pdx.intel.com/apd_proj/ppg_lib/epg_masterlib/logical/mstr_discrete/cap/chips/chips.prt!CAP!CAP_0603-22.0UF,4V,20%,X6S,E15431-004!CAP!!!F2767!!PVDDQ_KLM!!
S!@baseboard_fab2_lib.baseboard_fab2(sch_1):page228_i227@mstr_discrete.cap(chips)!CAP_0603-22.0UF,4V,20%,X6S,E15A!C8M3!//jf4cfls225.pdx.intel.com/apd_proj/ppg_lib/epg_masterlib/logical/mstr_discrete/cap/chips/chips.prt!CAP!CAP_0603-22.0UF,4V,20%,X6S,E15431-004!CAP!!!F2769!!PVDDQ_KLM!!
S!@baseboard_fab2_lib.baseboard_fab2(sch_1):page225_i218@mstr_discrete.cap(chips)!CAP_0603-22.0UF,4V,20%,X6S,E15A!C2G9!//jf4cfls225.pdx.intel.com/apd_proj/ppg_lib/epg_masterlib/logical/mstr_discrete/cap/chips/chips.prt!CAP!CAP_0603-22.0UF,4V,20%,X6S,E15431-004!CAP!!!F3006!!PVDDQ_ABC!!
S!@baseboard_fab2_lib.baseboard_fab2(sch_1):page225_i223@mstr_discrete.cap(chips)!CAP_0603-22.0UF,4V,20%,X6S,E15A!C2G10!//jf4cfls225.pdx.intel.com/apd_proj/ppg_lib/epg_masterlib/logical/mstr_discrete/cap/chips/chips.prt!CAP!CAP_0603-22.0UF,4V,20%,X6S,E15431-004!CAP!!!F3005!!PVDDQ_GHJ!!
S!@baseboard_fab2_lib.baseboard_fab2(sch_1):page225_i221@mstr_discrete.cap(chips)!CAP_0603-22.0UF,4V,20%,X6S,E15A!C2G11!//jf4cfls225.pdx.intel.com/apd_proj/ppg_lib/epg_masterlib/logical/mstr_discrete/cap/chips/chips.prt!CAP!CAP_0603-22.0UF,4V,20%,X6S,E15431-004!CAP!!!F3004!!PVDDQ_GHJ!!
S!@baseboard_fab2_lib.baseboard_fab2(sch_1):page225_i220@mstr_discrete.cap(chips)!CAP_0603-22.0UF,4V,20%,X6S,E15A!C2G12!//jf4cfls225.pdx.intel.com/apd_proj/ppg_lib/epg_masterlib/logical/mstr_discrete/cap/chips/chips.prt!CAP!CAP_0603-22.0UF,4V,20%,X6S,E15431-004!CAP!!!F3003!!PVDDQ_GHJ!!
S!@baseboard_fab2_lib.baseboard_fab2(sch_1):page225_i219@mstr_discrete.cap(chips)!CAP_0603-22.0UF,4V,20%,X6S,E15A!C2G1!//jf4cfls225.pdx.intel.com/apd_proj/ppg_lib/epg_masterlib/logical/mstr_discrete/cap/chips/chips.prt!CAP!CAP_0603-22.0UF,4V,20%,X6S,E15431-004!CAP!!!F3012!!PVDDQ_GHJ!!
S!@baseboard_fab2_lib.baseboard_fab2(sch_1):page225_i217@mstr_discrete.cap(chips)!CAP_0603-22.0UF,4V,20%,X6S,E15A!C2G2!//jf4cfls225.pdx.intel.com/apd_proj/ppg_lib/epg_masterlib/logical/mstr_discrete/cap/chips/chips.prt!CAP!CAP_0603-22.0UF,4V,20%,X6S,E15431-004!CAP!!!F3011!!PVDDQ_GHJ!!
S!@baseboard_fab2_lib.baseboard_fab2(sch_1):page225_i216@mstr_discrete.cap(chips)!CAP_0603-22.0UF,4V,20%,X6S,E15A!C2G3!//jf4cfls225.pdx.intel.com/apd_proj/ppg_lib/epg_masterlib/logical/mstr_discrete/cap/chips/chips.prt!CAP!CAP_0603-22.0UF,4V,20%,X6S,E15431-004!CAP!!!F3010!!PVDDQ_GHJ!!
S!@baseboard_fab2_lib.baseboard_fab2(sch_1):page225_i215@mstr_discrete.cap(chips)!CAP_0603-22.0UF,4V,20%,X6S,E15A!C2G4!//jf4cfls225.pdx.intel.com/apd_proj/ppg_lib/epg_masterlib/logical/mstr_discrete/cap/chips/chips.prt!CAP!CAP_0603-22.0UF,4V,20%,X6S,E15431-004!CAP!!!F3009!!PVDDQ_GHJ!!
S!@baseboard_fab2_lib.baseboard_fab2(sch_1):page225_i214@mstr_discrete.cap(chips)!CAP_0603-22.0UF,4V,20%,X6S,E15A!C2G5!//jf4cfls225.pdx.intel.com/apd_proj/ppg_lib/epg_masterlib/logical/mstr_discrete/cap/chips/chips.prt!CAP!CAP_0603-22.0UF,4V,20%,X6S,E15431-004!CAP!!!F3008!!PVDDQ_GHJ!!
S!@baseboard_fab2_lib.baseboard_fab2(sch_1):page225_i213@mstr_discrete.cap(chips)!CAP_0603-22.0UF,4V,20%,X6S,E15A!C2G6!//jf4cfls225.pdx.intel.com/apd_proj/ppg_lib/epg_masterlib/logical/mstr_discrete/cap/chips/chips.prt!CAP!CAP_0603-22.0UF,4V,20%,X6S,E15431-004!CAP!!!F3007!!PVDDQ_GHJ!!
S!@baseboard_fab2_lib.baseboard_fab2(sch_1):page225_i212@mstr_discrete.cap(chips)!CAP_0603-22.0UF,4V,20%,X6S,E15A!C3G1!//jf4cfls225.pdx.intel.com/apd_proj/ppg_lib/epg_masterlib/logical/mstr_discrete/cap/chips/chips.prt!CAP!CAP_0603-22.0UF,4V,20%,X6S,E15431-004!CAP!!!F2967!!PVDDQ_GHJ!!
S!@baseboard_fab2_lib.baseboard_fab2(sch_1):page225_i211@mstr_discrete.cap(chips)!CAP_0603-22.0UF,4V,20%,X6S,E15A!C3G2!//jf4cfls225.pdx.intel.com/apd_proj/ppg_lib/epg_masterlib/logical/mstr_discrete/cap/chips/chips.prt!CAP!CAP_0603-22.0UF,4V,20%,X6S,E15431-004!CAP!!!F2966!!PVDDQ_GHJ!!
S!@baseboard_fab2_lib.baseboard_fab2(sch_1):page225_i210@mstr_discrete.cap(chips)!CAP_0603-22.0UF,4V,20%,X6S,E15A!C2G13!//jf4cfls225.pdx.intel.com/apd_proj/ppg_lib/epg_masterlib/logical/mstr_discrete/cap/chips/chips.prt!CAP!CAP_0603-22.0UF,4V,20%,X6S,E15431-004!CAP!!!F3002!!PVDDQ_GHJ!!
S!@baseboard_fab2_lib.baseboard_fab2(sch_1):page225_i209@mstr_discrete.cap(chips)!CAP_0603-22.0UF,4V,20%,X6S,E15A!C2G14!//jf4cfls225.pdx.intel.com/apd_proj/ppg_lib/epg_masterlib/logical/mstr_discrete/cap/chips/chips.prt!CAP!CAP_0603-22.0UF,4V,20%,X6S,E15431-004!CAP!!!F3001!!PVDDQ_GHJ!!
S!@baseboard_fab2_lib.baseboard_fab2(sch_1):page225_i208@mstr_discrete.cap(chips)!CAP_0603-22.0UF,4V,20%,X6S,E15A!C3G5!//jf4cfls225.pdx.intel.com/apd_proj/ppg_lib/epg_masterlib/logical/mstr_discrete/cap/chips/chips.prt!CAP!CAP_0603-22.0UF,4V,20%,X6S,E15431-004!CAP!!!F2965!!PVDDQ_GHJ!!
S!@baseboard_fab2_lib.baseboard_fab2(sch_1):page225_i207@mstr_discrete.cap(chips)!CAP_0603-22.0UF,4V,20%,X6S,E15A!C3G6!//jf4cfls225.pdx.intel.com/apd_proj/ppg_lib/epg_masterlib/logical/mstr_discrete/cap/chips/chips.prt!CAP!CAP_0603-22.0UF,4V,20%,X6S,E15431-004!CAP!!!F2964!!PVDDQ_GHJ!!
S!@baseboard_fab2_lib.baseboard_fab2(sch_1):page228_i225@mstr_discrete.cap(chips)!CAP_0603-22.0UF,4V,20%,X6S,E15A!C7L5!//jf4cfls225.pdx.intel.com/apd_proj/ppg_lib/epg_masterlib/logical/mstr_discrete/cap/chips/chips.prt!CAP!CAP_0603-22.0UF,4V,20%,X6S,E15431-004!CAP!!!F2795!!PVDDQ_KLM!!
S!@baseboard_fab2_lib.baseboard_fab2(sch_1):page228_i223@mstr_discrete.cap(chips)!CAP_0603-22.0UF,4V,20%,X6S,E15A!C3A6!//jf4cfls225.pdx.intel.com/apd_proj/ppg_lib/epg_masterlib/logical/mstr_discrete/cap/chips/chips.prt!CAP!CAP_0603-22.0UF,4V,20%,X6S,E15431-004!CAP!!!F2992!!PVDDQ_KLM!!
S!@baseboard_fab2_lib.baseboard_fab2(sch_1):page228_i222@mstr_discrete.cap(chips)!CAP_0603-22.0UF,4V,20%,X6S,E15A!C3A5!//jf4cfls225.pdx.intel.com/apd_proj/ppg_lib/epg_masterlib/logical/mstr_discrete/cap/chips/chips.prt!CAP!CAP_0603-22.0UF,4V,20%,X6S,E15431-004!CAP!!!F2993!!PVDDQ_KLM!!
S!@baseboard_fab2_lib.baseboard_fab2(sch_1):page228_i221@mstr_discrete.cap(chips)!CAP_0603-22.0UF,4V,20%,X6S,E15A!C2A15!//jf4cfls225.pdx.intel.com/apd_proj/ppg_lib/epg_masterlib/logical/mstr_discrete/cap/chips/chips.prt!CAP!CAP_0603-22.0UF,4V,20%,X6S,E15431-004!CAP!!!F3048!!PVDDQ_KLM!!
S!@baseboard_fab2_lib.baseboard_fab2(sch_1):page228_i220@mstr_discrete.cap(chips)!CAP_0603-22.0UF,4V,20%,X6S,E15A!C2A14!//jf4cfls225.pdx.intel.com/apd_proj/ppg_lib/epg_masterlib/logical/mstr_discrete/cap/chips/chips.prt!CAP!CAP_0603-22.0UF,4V,20%,X6S,E15431-004!CAP!!!F3049!!PVDDQ_KLM!!
S!@baseboard_fab2_lib.baseboard_fab2(sch_1):page228_i219@mstr_discrete.cap(chips)!CAP_0603-22.0UF,4V,20%,X6S,E15A!C2A6!//jf4cfls225.pdx.intel.com/apd_proj/ppg_lib/epg_masterlib/logical/mstr_discrete/cap/chips/chips.prt!CAP!CAP_0603-22.0UF,4V,20%,X6S,E15431-004!CAP!!!F3056!!PVDDQ_KLM!!
S!@baseboard_fab2_lib.baseboard_fab2(sch_1):page228_i218@mstr_discrete.cap(chips)!CAP_0603-22.0UF,4V,20%,X6S,E15A!C2A7!//jf4cfls225.pdx.intel.com/apd_proj/ppg_lib/epg_masterlib/logical/mstr_discrete/cap/chips/chips.prt!CAP!CAP_0603-22.0UF,4V,20%,X6S,E15431-004!CAP!!!F3055!!PVDDQ_KLM!!
S!@baseboard_fab2_lib.baseboard_fab2(sch_1):page228_i217@mstr_discrete.cap(chips)!CAP_0603-22.0UF,4V,20%,X6S,E15A!C3A1!//jf4cfls225.pdx.intel.com/apd_proj/ppg_lib/epg_masterlib/logical/mstr_discrete/cap/chips/chips.prt!CAP!CAP_0603-22.0UF,4V,20%,X6S,E15431-004!CAP!!!F2995!!PVDDQ_KLM!!
S!@baseboard_fab2_lib.baseboard_fab2(sch_1):page228_i216@mstr_discrete.cap(chips)!CAP_0603-22.0UF,4V,20%,X6S,E15A!C3A2!//jf4cfls225.pdx.intel.com/apd_proj/ppg_lib/epg_masterlib/logical/mstr_discrete/cap/chips/chips.prt!CAP!CAP_0603-22.0UF,4V,20%,X6S,E15431-004!CAP!!!F2994!!PVDDQ_KLM!!
S!@baseboard_fab2_lib.baseboard_fab2(sch_1):page228_i215@mstr_discrete.cap(chips)!CAP_0603-22.0UF,4V,20%,X6S,E15A!C2A9!//jf4cfls225.pdx.intel.com/apd_proj/ppg_lib/epg_masterlib/logical/mstr_discrete/cap/chips/chips.prt!CAP!CAP_0603-22.0UF,4V,20%,X6S,E15431-004!CAP!!!F3054!!PVDDQ_KLM!!
S!@baseboard_fab2_lib.baseboard_fab2(sch_1):page228_i214@mstr_discrete.cap(chips)!CAP_0603-22.0UF,4V,20%,X6S,E15A!C2A10!//jf4cfls225.pdx.intel.com/apd_proj/ppg_lib/epg_masterlib/logical/mstr_discrete/cap/chips/chips.prt!CAP!CAP_0603-22.0UF,4V,20%,X6S,E15431-004!CAP!!!F3053!!PVDDQ_KLM!!
S!@baseboard_fab2_lib.baseboard_fab2(sch_1):page228_i213@mstr_discrete.cap(chips)!CAP_0603-22.0UF,4V,20%,X6S,E15A!C2A11!//jf4cfls225.pdx.intel.com/apd_proj/ppg_lib/epg_masterlib/logical/mstr_discrete/cap/chips/chips.prt!CAP!CAP_0603-22.0UF,4V,20%,X6S,E15431-004!CAP!!!F3052!!PVDDQ_KLM!!
S!@baseboard_fab2_lib.baseboard_fab2(sch_1):page228_i212@mstr_discrete.cap(chips)!CAP_0603-22.0UF,4V,20%,X6S,E15A!C2A13!//jf4cfls225.pdx.intel.com/apd_proj/ppg_lib/epg_masterlib/logical/mstr_discrete/cap/chips/chips.prt!CAP!CAP_0603-22.0UF,4V,20%,X6S,E15431-004!CAP!!!F3050!!PVDDQ_KLM!!
S!@baseboard_fab2_lib.baseboard_fab2(sch_1):page228_i211@mstr_discrete.cap(chips)!CAP_0603-22.0UF,4V,20%,X6S,E15A!C2A12!//jf4cfls225.pdx.intel.com/apd_proj/ppg_lib/epg_masterlib/logical/mstr_discrete/cap/chips/chips.prt!CAP!CAP_0603-22.0UF,4V,20%,X6S,E15431-004!CAP!!!F3051!!PVDDQ_KLM!!
S!@baseboard_fab2_lib.baseboard_fab2(sch_1):page228_i210@mstr_discrete.cap(chips)!CAP_0603-22.0UF,4V,20%,X6S,E15A!C2A1!//jf4cfls225.pdx.intel.com/apd_proj/ppg_lib/epg_masterlib/logical/mstr_discrete/cap/chips/chips.prt!CAP!CAP_0603-22.0UF,4V,20%,X6S,E15431-004!CAP!!!F3060!!PVDDQ_KLM!!
S!@baseboard_fab2_lib.baseboard_fab2(sch_1):page228_i209@mstr_discrete.cap(chips)!CAP_0603-22.0UF,4V,20%,X6S,E15A!C2A2!//jf4cfls225.pdx.intel.com/apd_proj/ppg_lib/epg_masterlib/logical/mstr_discrete/cap/chips/chips.prt!CAP!CAP_0603-22.0UF,4V,20%,X6S,E15431-004!CAP!!!F3059!!PVDDQ_KLM!!
S!@baseboard_fab2_lib.baseboard_fab2(sch_1):page217_i247@mstr_discrete.cap(chips)!CAP_0603-22.0UF,4V,20%,X6S,E15A!C5U2!//jf4cfls225.pdx.intel.com/apd_proj/ppg_lib/epg_masterlib/logical/mstr_discrete/cap/chips/chips.prt!CAP!CAP_0603-22.0UF,4V,20%,X6S,E15431-004!CAP!!!F2834!!PVDDQ_ABC!!
S!@baseboard_fab2_lib.baseboard_fab2(sch_1):page217_i244@mstr_discrete.cap(chips)!CAP_0603-22.0UF,4V,20%,X6S,E15A!C5U3!//jf4cfls225.pdx.intel.com/apd_proj/ppg_lib/epg_masterlib/logical/mstr_discrete/cap/chips/chips.prt!CAP!CAP_0603-22.0UF,4V,20%,X6S,E15431-004!CAP!!!F2833!!PVDDQ_ABC!!
S!@baseboard_fab2_lib.baseboard_fab2(sch_1):page217_i243@mstr_discrete.cap(chips)!CAP_0603-22.0UF,4V,20%,X6S,E15A!C5U4!//jf4cfls225.pdx.intel.com/apd_proj/ppg_lib/epg_masterlib/logical/mstr_discrete/cap/chips/chips.prt!CAP!CAP_0603-22.0UF,4V,20%,X6S,E15431-004!CAP!!!F2832!!PVDDQ_ABC!!
S!@baseboard_fab2_lib.baseboard_fab2(sch_1):page217_i239@mstr_discrete.cap(chips)!CAP_0603-22.0UF,4V,20%,X6S,E15A!C5U5!//jf4cfls225.pdx.intel.com/apd_proj/ppg_lib/epg_masterlib/logical/mstr_discrete/cap/chips/chips.prt!CAP!CAP_0603-22.0UF,4V,20%,X6S,E15431-004!CAP!!!F2831!!PVDDQ_ABC!!
S!@baseboard_fab2_lib.baseboard_fab2(sch_1):page217_i238@mstr_discrete.cap(chips)!CAP_0603-22.0UF,4V,20%,X6S,E15A!C5U6!//jf4cfls225.pdx.intel.com/apd_proj/ppg_lib/epg_masterlib/logical/mstr_discrete/cap/chips/chips.prt!CAP!CAP_0603-22.0UF,4V,20%,X6S,E15431-004!CAP!!!F2830!!PVDDQ_ABC!!
S!@baseboard_fab2_lib.baseboard_fab2(sch_1):page217_i236@mstr_discrete.cap(chips)!CAP_0603-22.0UF,4V,20%,X6S,E15A!C5U7!//jf4cfls225.pdx.intel.com/apd_proj/ppg_lib/epg_masterlib/logical/mstr_discrete/cap/chips/chips.prt!CAP!CAP_0603-22.0UF,4V,20%,X6S,E15431-004!CAP!!!F2829!!PVDDQ_ABC!!
S!@baseboard_fab2_lib.baseboard_fab2(sch_1):page217_i233@mstr_discrete.cap(chips)!CAP_0603-22.0UF,4V,20%,X6S,E15A!C5U8!//jf4cfls225.pdx.intel.com/apd_proj/ppg_lib/epg_masterlib/logical/mstr_discrete/cap/chips/chips.prt!CAP!CAP_0603-22.0UF,4V,20%,X6S,E15431-004!CAP!!!F2828!!PVDDQ_ABC!!
S!@baseboard_fab2_lib.baseboard_fab2(sch_1):page217_i232@mstr_discrete.cap(chips)!CAP_0603-22.0UF,4V,20%,X6S,E15A!C5U9!//jf4cfls225.pdx.intel.com/apd_proj/ppg_lib/epg_masterlib/logical/mstr_discrete/cap/chips/chips.prt!CAP!CAP_0603-22.0UF,4V,20%,X6S,E15431-004!CAP!!!F2827!!PVDDQ_ABC!!
S!@baseboard_fab2_lib.baseboard_fab2(sch_1):page217_i229@mstr_discrete.cap(chips)!CAP_0603-22.0UF,4V,20%,X6S,E15A!C5T12!//jf4cfls225.pdx.intel.com/apd_proj/ppg_lib/epg_masterlib/logical/mstr_discrete/cap/chips/chips.prt!CAP!CAP_0603-22.0UF,4V,20%,X6S,E15431-004!CAP!!!F2835!!PVDDQ_ABC!!
S!@baseboard_fab2_lib.baseboard_fab2(sch_1):page217_i228@mstr_discrete.cap(chips)!CAP_0603-22.0UF,4V,20%,X6S,E15A!C5T11!//jf4cfls225.pdx.intel.com/apd_proj/ppg_lib/epg_masterlib/logical/mstr_discrete/cap/chips/chips.prt!CAP!CAP_0603-22.0UF,4V,20%,X6S,E15431-004!CAP!!!F2836!!PVDDQ_ABC!!
S!@baseboard_fab2_lib.baseboard_fab2(sch_1):page217_i225@mstr_discrete.cap(chips)!CAP_0603-22.0UF,4V,20%,X6S,E15A!C5T10!//jf4cfls225.pdx.intel.com/apd_proj/ppg_lib/epg_masterlib/logical/mstr_discrete/cap/chips/chips.prt!CAP!CAP_0603-22.0UF,4V,20%,X6S,E15431-004!CAP!!!F2837!!PVDDQ_ABC!!
S!@baseboard_fab2_lib.baseboard_fab2(sch_1):page217_i224@mstr_discrete.cap(chips)!CAP_0603-22.0UF,4V,20%,X6S,E15A!C5T9!//jf4cfls225.pdx.intel.com/apd_proj/ppg_lib/epg_masterlib/logical/mstr_discrete/cap/chips/chips.prt!CAP!CAP_0603-22.0UF,4V,20%,X6S,E15431-004!CAP!!!F2838!!PVDDQ_ABC!!
S!@baseboard_fab2_lib.baseboard_fab2(sch_1):page217_i222@mstr_discrete.cap(chips)!CAP_0603-22.0UF,4V,20%,X6S,E15A!C5T8!//jf4cfls225.pdx.intel.com/apd_proj/ppg_lib/epg_masterlib/logical/mstr_discrete/cap/chips/chips.prt!CAP!CAP_0603-22.0UF,4V,20%,X6S,E15431-004!CAP!!!F2839!!PVDDQ_ABC!!
S!@baseboard_fab2_lib.baseboard_fab2(sch_1):page217_i219@mstr_discrete.cap(chips)!CAP_0603-22.0UF,4V,20%,X6S,E15A!C5T7!//jf4cfls225.pdx.intel.com/apd_proj/ppg_lib/epg_masterlib/logical/mstr_discrete/cap/chips/chips.prt!CAP!CAP_0603-22.0UF,4V,20%,X6S,E15431-004!CAP!!!F2840!!PVDDQ_ABC!!
S!@baseboard_fab2_lib.baseboard_fab2(sch_1):page217_i218@mstr_discrete.cap(chips)!CAP_0603-22.0UF,4V,20%,X6S,E15A!C5T6!//jf4cfls225.pdx.intel.com/apd_proj/ppg_lib/epg_masterlib/logical/mstr_discrete/cap/chips/chips.prt!CAP!CAP_0603-22.0UF,4V,20%,X6S,E15431-004!CAP!!!F2841!!PVDDQ_ABC!!
S!@baseboard_fab2_lib.baseboard_fab2(sch_1):page217_i216@mstr_discrete.cap(chips)!CAP_0603-22.0UF,4V,20%,X6S,E15A!C5T5!//jf4cfls225.pdx.intel.com/apd_proj/ppg_lib/epg_masterlib/logical/mstr_discrete/cap/chips/chips.prt!CAP!CAP_0603-22.0UF,4V,20%,X6S,E15431-004!CAP!!!F2842!!PVDDQ_ABC!!
S!@baseboard_fab2_lib.baseboard_fab2(sch_1):page220_i237@mstr_discrete.cap(chips)!CAP_0603-22.0UF,4V,20%,X6S,E15A!C5L6!//jf4cfls225.pdx.intel.com/apd_proj/ppg_lib/epg_masterlib/logical/mstr_discrete/cap/chips/chips.prt!CAP!CAP_0603-22.0UF,4V,20%,X6S,E15431-004!CAP!!!F2856!!PVDDQ_DEF!!
S!@baseboard_fab2_lib.baseboard_fab2(sch_1):page220_i236@mstr_discrete.cap(chips)!CAP_0603-22.0UF,4V,20%,X6S,E15A!C5L7!//jf4cfls225.pdx.intel.com/apd_proj/ppg_lib/epg_masterlib/logical/mstr_discrete/cap/chips/chips.prt!CAP!CAP_0603-22.0UF,4V,20%,X6S,E15431-004!CAP!!!F2855!!PVDDQ_DEF!!
S!@baseboard_fab2_lib.baseboard_fab2(sch_1):page220_i234@mstr_discrete.cap(chips)!CAP_0603-22.0UF,4V,20%,X6S,E15A!C5L8!//jf4cfls225.pdx.intel.com/apd_proj/ppg_lib/epg_masterlib/logical/mstr_discrete/cap/chips/chips.prt!CAP!CAP_0603-22.0UF,4V,20%,X6S,E15431-004!CAP!!!F2854!!PVDDQ_DEF!!
S!@baseboard_fab2_lib.baseboard_fab2(sch_1):page220_i233@mstr_discrete.cap(chips)!CAP_0603-22.0UF,4V,20%,X6S,E15A!C5L9!//jf4cfls225.pdx.intel.com/apd_proj/ppg_lib/epg_masterlib/logical/mstr_discrete/cap/chips/chips.prt!CAP!CAP_0603-22.0UF,4V,20%,X6S,E15431-004!CAP!!!F2853!!PVDDQ_DEF!!
S!@baseboard_fab2_lib.baseboard_fab2(sch_1):page220_i232@mstr_discrete.cap(chips)!CAP_0603-22.0UF,4V,20%,X6S,E15A!C5L10!//jf4cfls225.pdx.intel.com/apd_proj/ppg_lib/epg_masterlib/logical/mstr_discrete/cap/chips/chips.prt!CAP!CAP_0603-22.0UF,4V,20%,X6S,E15431-004!CAP!!!F2852!!PVDDQ_DEF!!
S!@baseboard_fab2_lib.baseboard_fab2(sch_1):page220_i231@mstr_discrete.cap(chips)!CAP_0603-22.0UF,4V,20%,X6S,E15A!C5L11!//jf4cfls225.pdx.intel.com/apd_proj/ppg_lib/epg_masterlib/logical/mstr_discrete/cap/chips/chips.prt!CAP!CAP_0603-22.0UF,4V,20%,X6S,E15431-004!CAP!!!F2851!!PVDDQ_DEF!!
S!@baseboard_fab2_lib.baseboard_fab2(sch_1):page220_i230@mstr_discrete.cap(chips)!CAP_0603-22.0UF,4V,20%,X6S,E15A!C5L12!//jf4cfls225.pdx.intel.com/apd_proj/ppg_lib/epg_masterlib/logical/mstr_discrete/cap/chips/chips.prt!CAP!CAP_0603-22.0UF,4V,20%,X6S,E15431-004!CAP!!!F2850!!PVDDQ_DEF!!
S!@baseboard_fab2_lib.baseboard_fab2(sch_1):page220_i229@mstr_discrete.cap(chips)!CAP_0603-22.0UF,4V,20%,X6S,E15A!C5L13!//jf4cfls225.pdx.intel.com/apd_proj/ppg_lib/epg_masterlib/logical/mstr_discrete/cap/chips/chips.prt!CAP!CAP_0603-22.0UF,4V,20%,X6S,E15431-004!CAP!!!F2849!!PVDDQ_DEF!!
S!@baseboard_fab2_lib.baseboard_fab2(sch_1):page220_i228@mstr_discrete.cap(chips)!CAP_0603-22.0UF,4V,20%,X6S,E15A!C5M7!//jf4cfls225.pdx.intel.com/apd_proj/ppg_lib/epg_masterlib/logical/mstr_discrete/cap/chips/chips.prt!CAP!CAP_0603-22.0UF,4V,20%,X6S,E15431-004!CAP!!!F2843!!PVDDQ_DEF!!
S!@baseboard_fab2_lib.baseboard_fab2(sch_1):page220_i227@mstr_discrete.cap(chips)!CAP_0603-22.0UF,4V,20%,X6S,E15A!C5M6!//jf4cfls225.pdx.intel.com/apd_proj/ppg_lib/epg_masterlib/logical/mstr_discrete/cap/chips/chips.prt!CAP!CAP_0603-22.0UF,4V,20%,X6S,E15431-004!CAP!!!F2844!!PVDDQ_DEF!!
S!@baseboard_fab2_lib.baseboard_fab2(sch_1):page220_i226@mstr_discrete.cap(chips)!CAP_0603-22.0UF,4V,20%,X6S,E15A!C5M5!//jf4cfls225.pdx.intel.com/apd_proj/ppg_lib/epg_masterlib/logical/mstr_discrete/cap/chips/chips.prt!CAP!CAP_0603-22.0UF,4V,20%,X6S,E15431-004!CAP!!!F2845!!PVDDQ_DEF!!
S!@baseboard_fab2_lib.baseboard_fab2(sch_1):page220_i225@mstr_discrete.cap(chips)!CAP_0603-22.0UF,4V,20%,X6S,E15A!C5M4!//jf4cfls225.pdx.intel.com/apd_proj/ppg_lib/epg_masterlib/logical/mstr_discrete/cap/chips/chips.prt!CAP!CAP_0603-22.0UF,4V,20%,X6S,E15431-004!CAP!!!F2846!!PVDDQ_DEF!!
S!@baseboard_fab2_lib.baseboard_fab2(sch_1):page220_i224@mstr_discrete.cap(chips)!CAP_0603-22.0UF,4V,20%,X6S,E15A!C5M2!//jf4cfls225.pdx.intel.com/apd_proj/ppg_lib/epg_masterlib/logical/mstr_discrete/cap/chips/chips.prt!CAP!CAP_0603-22.0UF,4V,20%,X6S,E15431-004!CAP!!!F2847!!PVDDQ_DEF!!
S!@baseboard_fab2_lib.baseboard_fab2(sch_1):page220_i223@mstr_discrete.cap(chips)!CAP_0603-22.0UF,4V,20%,X6S,E15A!C5M1!//jf4cfls225.pdx.intel.com/apd_proj/ppg_lib/epg_masterlib/logical/mstr_discrete/cap/chips/chips.prt!CAP!CAP_0603-22.0UF,4V,20%,X6S,E15431-004!CAP!!!F2848!!PVDDQ_DEF!!
S!@baseboard_fab2_lib.baseboard_fab2(sch_1):page220_i222@mstr_discrete.cap(chips)!CAP_0603-22.0UF,4V,20%,X6S,E15A!C4M2!//jf4cfls225.pdx.intel.com/apd_proj/ppg_lib/epg_masterlib/logical/mstr_discrete/cap/chips/chips.prt!CAP!CAP_0603-22.0UF,4V,20%,X6S,E15431-004!CAP!!!F2941!!PVDDQ_DEF!!
S!@baseboard_fab2_lib.baseboard_fab2(sch_1):page220_i221@mstr_discrete.cap(chips)!CAP_0603-22.0UF,4V,20%,X6S,E15A!C5A11!//jf4cfls225.pdx.intel.com/apd_proj/ppg_lib/epg_masterlib/logical/mstr_discrete/cap/chips/chips.prt!CAP!CAP_0603-22.0UF,4V,20%,X6S,E15431-004!CAP!!!F2930!!PVDDQ_DEF!!
S!@baseboard_fab2_lib.baseboard_fab2(sch_1):page42_i142@mstr_discrete.cap(chips)!CAP_0603-22.0UF,4V,20%,X6S,E15A!C5D44!//jf4cfls225.pdx.intel.com/apd_proj/ppg_lib/epg_masterlib/logical/mstr_discrete/cap/chips/chips.prt!CAP!CAP_0603-22.0UF,4V,20%,X6S,E15431-004!CAP!!!F2886!!PVCCIN_CPU0_DECAP_VR!!
S!@baseboard_fab2_lib.baseboard_fab2(sch_1):page42_i127@mstr_discrete.cap(chips)!CAP_0603-22.0UF,4V,20%,X6S,E15A!C5D4!//jf4cfls225.pdx.intel.com/apd_proj/ppg_lib/epg_masterlib/logical/mstr_discrete/cap/chips/chips.prt!CAP!CAP_0603-22.0UF,4V,20%,X6S,E15431-004!CAP!!!F2918!!PVCCIN_CPU0_DECAP_VR!!
S!@baseboard_fab2_lib.baseboard_fab2(sch_1):page42_i130@mstr_discrete.cap(chips)!CAP_0603-22.0UF,4V,20%,X6S,E15A!C5D3!//jf4cfls225.pdx.intel.com/apd_proj/ppg_lib/epg_masterlib/logical/mstr_discrete/cap/chips/chips.prt!CAP!CAP_0603-22.0UF,4V,20%,X6S,E15431-004!CAP!!!F2919!!PVCCIN_CPU0_DECAP_VR!!
S!@baseboard_fab2_lib.baseboard_fab2(sch_1):page42_i136@mstr_discrete.cap(chips)!CAP_0603-22.0UF,4V,20%,X6S,E15A!C5D2!//jf4cfls225.pdx.intel.com/apd_proj/ppg_lib/epg_masterlib/logical/mstr_discrete/cap/chips/chips.prt!CAP!CAP_0603-22.0UF,4V,20%,X6S,E15431-004!CAP!!!F2920!!PVCCIN_CPU0_DECAP_VR!!
S!@baseboard_fab2_lib.baseboard_fab2(sch_1):page42_i126@mstr_discrete.cap(chips)!CAP_0603-22.0UF,4V,20%,X6S,E15A!C5D1!//jf4cfls225.pdx.intel.com/apd_proj/ppg_lib/epg_masterlib/logical/mstr_discrete/cap/chips/chips.prt!CAP!CAP_0603-22.0UF,4V,20%,X6S,E15431-004!CAP!!!F2921!!PVCCIN_CPU0_DECAP_VR!!
S!@baseboard_fab2_lib.baseboard_fab2(sch_1):page42_i129@mstr_discrete.cap(chips)!CAP_0603-22.0UF,4V,20%,X6S,E15A!C5D59!//jf4cfls225.pdx.intel.com/apd_proj/ppg_lib/epg_masterlib/logical/mstr_discrete/cap/chips/chips.prt!CAP!CAP_0603-22.0UF,4V,20%,X6S,E15431-004!CAP!!!F2875!!PVCCIN_CPU0_DECAP_VR!!
S!@baseboard_fab2_lib.baseboard_fab2(sch_1):page42_i135@mstr_discrete.cap(chips)!CAP_0603-22.0UF,4V,20%,X6S,E15A!C5D42!//jf4cfls225.pdx.intel.com/apd_proj/ppg_lib/epg_masterlib/logical/mstr_discrete/cap/chips/chips.prt!CAP!CAP_0603-22.0UF,4V,20%,X6S,E15431-004!CAP!!!F2888!!PVCCIN_CPU0_DECAP_VR!!
S!@baseboard_fab2_lib.baseboard_fab2(sch_1):page42_i125@mstr_discrete.cap(chips)!CAP_0603-22.0UF,4V,20%,X6S,E15A!C5D5!//jf4cfls225.pdx.intel.com/apd_proj/ppg_lib/epg_masterlib/logical/mstr_discrete/cap/chips/chips.prt!CAP!CAP_0603-22.0UF,4V,20%,X6S,E15431-004!CAP!!!F2917!!PVCCIN_CPU0_DECAP_VR!!
S!@baseboard_fab2_lib.baseboard_fab2(sch_1):page42_i128@mstr_discrete.cap(chips)!CAP_0603-22.0UF,4V,20%,X6S,E15A!C5D19!//jf4cfls225.pdx.intel.com/apd_proj/ppg_lib/epg_masterlib/logical/mstr_discrete/cap/chips/chips.prt!CAP!CAP_0603-22.0UF,4V,20%,X6S,E15431-004!CAP!!!F2911!!PVCCIN_CPU0_DECAP_VR!!
S!@baseboard_fab2_lib.baseboard_fab2(sch_1):page42_i134@mstr_discrete.cap(chips)!CAP_0603-22.0UF,4V,20%,X6S,E15A!C5D18!//jf4cfls225.pdx.intel.com/apd_proj/ppg_lib/epg_masterlib/logical/mstr_discrete/cap/chips/chips.prt!CAP!CAP_0603-22.0UF,4V,20%,X6S,E15431-004!CAP!!!F2912!!PVCCIN_CPU0_DECAP_VR!!
S!@baseboard_fab2_lib.baseboard_fab2(sch_1):page42_i118@mstr_discrete.cap(chips)!CAP_0603-22.0UF,4V,20%,X6S,E15A!C5D17!//jf4cfls225.pdx.intel.com/apd_proj/ppg_lib/epg_masterlib/logical/mstr_discrete/cap/chips/chips.prt!CAP!CAP_0603-22.0UF,4V,20%,X6S,E15431-004!CAP!!!F2913!!PVCCIN_CPU0_DECAP_VR!!
S!@baseboard_fab2_lib.baseboard_fab2(sch_1):page42_i123@mstr_discrete.cap(chips)!CAP_0603-22.0UF,4V,20%,X6S,E15A!C5D16!//jf4cfls225.pdx.intel.com/apd_proj/ppg_lib/epg_masterlib/logical/mstr_discrete/cap/chips/chips.prt!CAP!CAP_0603-22.0UF,4V,20%,X6S,E15431-004!CAP!!!F2914!!PVCCIN_CPU0_DECAP_VR!!
S!@baseboard_fab2_lib.baseboard_fab2(sch_1):page42_i132@mstr_discrete.cap(chips)!CAP_0603-22.0UF,4V,20%,X6S,E15A!C5D15!//jf4cfls225.pdx.intel.com/apd_proj/ppg_lib/epg_masterlib/logical/mstr_discrete/cap/chips/chips.prt!CAP!CAP_0603-22.0UF,4V,20%,X6S,E15431-004!CAP!!!F2915!!PVCCIN_CPU0_DECAP_VR!!
S!@baseboard_fab2_lib.baseboard_fab2(sch_1):page42_i117@mstr_discrete.cap(chips)!CAP_0603-22.0UF,4V,20%,X6S,E15A!C5D14!//jf4cfls225.pdx.intel.com/apd_proj/ppg_lib/epg_masterlib/logical/mstr_discrete/cap/chips/chips.prt!CAP!CAP_0603-22.0UF,4V,20%,X6S,E15431-004!CAP!!!F2916!!PVCCIN_CPU0_DECAP_VR!!
S!@baseboard_fab2_lib.baseboard_fab2(sch_1):page42_i120@mstr_discrete.cap(chips)!CAP_0603-22.0UF,4V,20%,X6S,E15A!C5D58!//jf4cfls225.pdx.intel.com/apd_proj/ppg_lib/epg_masterlib/logical/mstr_discrete/cap/chips/chips.prt!CAP!CAP_0603-22.0UF,4V,20%,X6S,E15431-004!CAP!!!F2876!!PVCCIN_CPU0_DECAP_VR!!
S!@baseboard_fab2_lib.baseboard_fab2(sch_1):page42_i131@mstr_discrete.cap(chips)!CAP_0603-22.0UF,4V,20%,X6S,E15A!C5D43!//jf4cfls225.pdx.intel.com/apd_proj/ppg_lib/epg_masterlib/logical/mstr_discrete/cap/chips/chips.prt!CAP!CAP_0603-22.0UF,4V,20%,X6S,E15431-004!CAP!!!F2887!!PVCCIN_CPU0_DECAP_VR!!
S!@baseboard_fab2_lib.baseboard_fab2(sch_1):page42_i112@mstr_discrete.cap(chips)!CAP_0603-22.0UF,4V,20%,X6S,E15A!C5D60!//jf4cfls225.pdx.intel.com/apd_proj/ppg_lib/epg_masterlib/logical/mstr_discrete/cap/chips/chips.prt!CAP!CAP_0603-22.0UF,4V,20%,X6S,E15431-004!CAP!!!F2874!!PVCCIN_CPU0_DECAP_VR!!
S!@baseboard_fab2_lib.baseboard_fab2(sch_1):page42_i103@mstr_discrete.cap(chips)!CAP_0603-22.0UF,4V,20%,X6S,E15A!C5D32!//jf4cfls225.pdx.intel.com/apd_proj/ppg_lib/epg_masterlib/logical/mstr_discrete/cap/chips/chips.prt!CAP!CAP_0603-22.0UF,4V,20%,X6S,E15431-004!CAP!!!F2898!!PVCCIN_CPU0_DECAP_VR!!
S!@baseboard_fab2_lib.baseboard_fab2(sch_1):page42_i106@mstr_discrete.cap(chips)!CAP_0603-22.0UF,4V,20%,X6S,E15A!C5D31!//jf4cfls225.pdx.intel.com/apd_proj/ppg_lib/epg_masterlib/logical/mstr_discrete/cap/chips/chips.prt!CAP!CAP_0603-22.0UF,4V,20%,X6S,E15431-004!CAP!!!F2899!!PVCCIN_CPU0_DECAP_VR!!
S!@baseboard_fab2_lib.baseboard_fab2(sch_1):page42_i111@mstr_discrete.cap(chips)!CAP_0603-22.0UF,4V,20%,X6S,E15A!C5D30!//jf4cfls225.pdx.intel.com/apd_proj/ppg_lib/epg_masterlib/logical/mstr_discrete/cap/chips/chips.prt!CAP!CAP_0603-22.0UF,4V,20%,X6S,E15431-004!CAP!!!F2900!!PVCCIN_CPU0_DECAP_VR!!
S!@baseboard_fab2_lib.baseboard_fab2(sch_1):page42_i102@mstr_discrete.cap(chips)!CAP_0603-22.0UF,4V,20%,X6S,E15A!C5D29!//jf4cfls225.pdx.intel.com/apd_proj/ppg_lib/epg_masterlib/logical/mstr_discrete/cap/chips/chips.prt!CAP!CAP_0603-22.0UF,4V,20%,X6S,E15431-004!CAP!!!F2901!!PVCCIN_CPU0_DECAP_VR!!
S!@baseboard_fab2_lib.baseboard_fab2(sch_1):page42_i154@mstr_discrete.cap(chips)!CAP_0603-22.0UF,4V,20%,X6S,E15A!C5D26!//jf4cfls225.pdx.intel.com/apd_proj/ppg_lib/epg_masterlib/logical/mstr_discrete/cap/chips/chips.prt!CAP!CAP_0603-22.0UF,4V,20%,X6S,E15431-004!CAP!!!F2904!!PVCCIN_CPU0_DECAP_VR!!
S!@baseboard_fab2_lib.baseboard_fab2(sch_1):page42_i138@mstr_discrete.cap(chips)!CAP_0603-22.0UF,4V,20%,X6S,E15A!C5D24!//jf4cfls225.pdx.intel.com/apd_proj/ppg_lib/epg_masterlib/logical/mstr_discrete/cap/chips/chips.prt!CAP!CAP_0603-22.0UF,4V,20%,X6S,E15431-004!CAP!!!F2906!!PVCCIN_CPU0_DECAP_VR!!
S!@baseboard_fab2_lib.baseboard_fab2(sch_1):page42_i140@mstr_discrete.cap(chips)!CAP_0603-22.0UF,4V,20%,X6S,E15A!C5D39!//jf4cfls225.pdx.intel.com/apd_proj/ppg_lib/epg_masterlib/logical/mstr_discrete/cap/chips/chips.prt!CAP!CAP_0603-22.0UF,4V,20%,X6S,E15431-004!CAP!!!F2891!!PVCCIN_CPU0_DECAP_VR!!
S!@baseboard_fab2_lib.baseboard_fab2(sch_1):page42_i115@mstr_discrete.cap(chips)!CAP_0603-22.0UF,4V,20%,X6S,E15A!C5D40!//jf4cfls225.pdx.intel.com/apd_proj/ppg_lib/epg_masterlib/logical/mstr_discrete/cap/chips/chips.prt!CAP!CAP_0603-22.0UF,4V,20%,X6S,E15431-004!CAP!!!F2890!!PVCCIN_CPU0_DECAP_VR!!
S!@baseboard_fab2_lib.baseboard_fab2(sch_1):page42_i114@mstr_discrete.cap(chips)!CAP_0603-22.0UF,4V,20%,X6S,E15A!C5D41!//jf4cfls225.pdx.intel.com/apd_proj/ppg_lib/epg_masterlib/logical/mstr_discrete/cap/chips/chips.prt!CAP!CAP_0603-22.0UF,4V,20%,X6S,E15431-004!CAP!!!F2889!!PVCCIN_CPU0_DECAP_VR!!
S!@baseboard_fab2_lib.baseboard_fab2(sch_1):page42_i113@mstr_discrete.cap(chips)!CAP_0603-22.0UF,4V,20%,X6S,E15A!C5D61!//jf4cfls225.pdx.intel.com/apd_proj/ppg_lib/epg_masterlib/logical/mstr_discrete/cap/chips/chips.prt!CAP!CAP_0603-22.0UF,4V,20%,X6S,E15431-004!CAP!!!F2873!!PVCCIN_CPU0_DECAP_VR!!
S!@baseboard_fab2_lib.baseboard_fab2(sch_1):page42_i104@mstr_discrete.cap(chips)!CAP_0603-22.0UF,4V,20%,X6S,E15A!C5D47!//jf4cfls225.pdx.intel.com/apd_proj/ppg_lib/epg_masterlib/logical/mstr_discrete/cap/chips/chips.prt!CAP!CAP_0603-22.0UF,4V,20%,X6S,E15431-004!CAP!!!F2883!!PVCCIN_CPU0_DECAP_VR!!
S!@baseboard_fab2_lib.baseboard_fab2(sch_1):page42_i107@mstr_discrete.cap(chips)!CAP_0603-22.0UF,4V,20%,X6S,E15A!C5D46!//jf4cfls225.pdx.intel.com/apd_proj/ppg_lib/epg_masterlib/logical/mstr_discrete/cap/chips/chips.prt!CAP!CAP_0603-22.0UF,4V,20%,X6S,E15431-004!CAP!!!F2884!!PVCCIN_CPU0_DECAP_VR!!
S!@baseboard_fab2_lib.baseboard_fab2(sch_1):page76_i196@mstr_discrete.cap(chips)!CAP_0603-22.0UF,4V,20%,X6S,E15A!C3D10!//jf4cfls225.pdx.intel.com/apd_proj/ppg_lib/epg_masterlib/logical/mstr_discrete/cap/chips/chips.prt!CAP!CAP_0603-22.0UF,4V,20%,X6S,E15431-004!CAP!!!F2983!!PVCCIN_CPU1_DECAP_VR!!
S!@baseboard_fab2_lib.baseboard_fab2(sch_1):page76_i122@mstr_discrete.cap(chips)!CAP_0603-22.0UF,4V,20%,X6S,E15A!C2D34!//jf4cfls225.pdx.intel.com/apd_proj/ppg_lib/epg_masterlib/logical/mstr_discrete/cap/chips/chips.prt!CAP!CAP_0603-22.0UF,4V,20%,X6S,E15431-004!CAP!!!F3022!!PVCCIN_CPU1_DECAP_VR!!
S!@baseboard_fab2_lib.baseboard_fab2(sch_1):page76_i124@mstr_discrete.cap(chips)!CAP_0603-22.0UF,4V,20%,X6S,E15A!C2D16!//jf4cfls225.pdx.intel.com/apd_proj/ppg_lib/epg_masterlib/logical/mstr_discrete/cap/chips/chips.prt!CAP!CAP_0603-22.0UF,4V,20%,X6S,E15431-004!CAP!!!F3040!!PVCCIN_CPU1_DECAP_VR!!
S!@baseboard_fab2_lib.baseboard_fab2(sch_1):page76_i70@mstr_discrete.cap(chips)!CAP_0603-22.0UF,4V,20%,X6S,E15A!C2D36!//jf4cfls225.pdx.intel.com/apd_proj/ppg_lib/epg_masterlib/logical/mstr_discrete/cap/chips/chips.prt!CAP!CAP_0603-22.0UF,4V,20%,X6S,E15431-004!CAP!!!F3020!!PVCCIN_CPU1_DECAP_VR!!
S!@baseboard_fab2_lib.baseboard_fab2(sch_1):page76_i119@mstr_discrete.cap(chips)!CAP_0603-22.0UF,4V,20%,X6S,E15A!C2D37!//jf4cfls225.pdx.intel.com/apd_proj/ppg_lib/epg_masterlib/logical/mstr_discrete/cap/chips/chips.prt!CAP!CAP_0603-22.0UF,4V,20%,X6S,E15431-004!CAP!!!F3019!!PVCCIN_CPU1_DECAP_VR!!
S!@baseboard_fab2_lib.baseboard_fab2(sch_1):page76_i123@mstr_discrete.cap(chips)!CAP_0603-22.0UF,4V,20%,X6S,E15A!C2D45!//jf4cfls225.pdx.intel.com/apd_proj/ppg_lib/epg_masterlib/logical/mstr_discrete/cap/chips/chips.prt!CAP!CAP_0603-22.0UF,4V,20%,X6S,E15431-004!CAP!!!F3015!!PVCCIN_CPU1_DECAP_VR!!
S!@baseboard_fab2_lib.baseboard_fab2(sch_1):page76_i69@mstr_discrete.cap(chips)!CAP_0603-22.0UF,4V,20%,X6S,E15A!C3D2!//jf4cfls225.pdx.intel.com/apd_proj/ppg_lib/epg_masterlib/logical/mstr_discrete/cap/chips/chips.prt!CAP!CAP_0603-22.0UF,4V,20%,X6S,E15431-004!CAP!!!F2990!!PVCCIN_CPU1_DECAP_VR!!
S!@baseboard_fab2_lib.baseboard_fab2(sch_1):page76_i111@mstr_discrete.cap(chips)!CAP_0603-22.0UF,4V,20%,X6S,E15A!C3D1!//jf4cfls225.pdx.intel.com/apd_proj/ppg_lib/epg_masterlib/logical/mstr_discrete/cap/chips/chips.prt!CAP!CAP_0603-22.0UF,4V,20%,X6S,E15431-004!CAP!!!F2991!!PVCCIN_CPU1_DECAP_VR!!
S!@baseboard_fab2_lib.baseboard_fab2(sch_1):page76_i116@mstr_discrete.cap(chips)!CAP_0603-22.0UF,4V,20%,X6S,E15A!C2D1!//jf4cfls225.pdx.intel.com/apd_proj/ppg_lib/epg_masterlib/logical/mstr_discrete/cap/chips/chips.prt!CAP!CAP_0603-22.0UF,4V,20%,X6S,E15431-004!CAP!!!F3047!!PVCCIN_CPU1_DECAP_VR!!
S!@baseboard_fab2_lib.baseboard_fab2(sch_1):page76_i197@mstr_discrete.cap(chips)!CAP_0603-22.0UF,4V,20%,X6S,E15A!C2D18!//jf4cfls225.pdx.intel.com/apd_proj/ppg_lib/epg_masterlib/logical/mstr_discrete/cap/chips/chips.prt!CAP!CAP_0603-22.0UF,4V,20%,X6S,E15431-004!CAP!!!F3038!!PVCCIN_CPU1_DECAP_VR!!
S!@baseboard_fab2_lib.baseboard_fab2(sch_1):page76_i114@mstr_discrete.cap(chips)!CAP_0603-22.0UF,4V,20%,X6S,E15A!C2D17!//jf4cfls225.pdx.intel.com/apd_proj/ppg_lib/epg_masterlib/logical/mstr_discrete/cap/chips/chips.prt!CAP!CAP_0603-22.0UF,4V,20%,X6S,E15431-004!CAP!!!F3039!!PVCCIN_CPU1_DECAP_VR!!
S!@baseboard_fab2_lib.baseboard_fab2(sch_1):page76_i66@mstr_discrete.cap(chips)!CAP_0603-22.0UF,4V,20%,X6S,E15A!C2D27!//jf4cfls225.pdx.intel.com/apd_proj/ppg_lib/epg_masterlib/logical/mstr_discrete/cap/chips/chips.prt!CAP!CAP_0603-22.0UF,4V,20%,X6S,E15431-004!CAP!!!F3029!!PVCCIN_CPU1_DECAP_VR!!
S!@baseboard_fab2_lib.baseboard_fab2(sch_1):page76_i108@mstr_discrete.cap(chips)!CAP_0603-22.0UF,4V,20%,X6S,E15A!C2D26!//jf4cfls225.pdx.intel.com/apd_proj/ppg_lib/epg_masterlib/logical/mstr_discrete/cap/chips/chips.prt!CAP!CAP_0603-22.0UF,4V,20%,X6S,E15431-004!CAP!!!F3030!!PVCCIN_CPU1_DECAP_VR!!
S!@baseboard_fab2_lib.baseboard_fab2(sch_1):page76_i112@mstr_discrete.cap(chips)!CAP_0603-22.0UF,4V,20%,X6S,E15A!C2D23!//jf4cfls225.pdx.intel.com/apd_proj/ppg_lib/epg_masterlib/logical/mstr_discrete/cap/chips/chips.prt!CAP!CAP_0603-22.0UF,4V,20%,X6S,E15431-004!CAP!!!F3033!!PVCCIN_CPU1_DECAP_VR!!
S!@baseboard_fab2_lib.baseboard_fab2(sch_1):page76_i65@mstr_discrete.cap(chips)!CAP_0603-22.0UF,4V,20%,X6S,E15A!C2D21!//jf4cfls225.pdx.intel.com/apd_proj/ppg_lib/epg_masterlib/logical/mstr_discrete/cap/chips/chips.prt!CAP!CAP_0603-22.0UF,4V,20%,X6S,E15431-004!CAP!!!F3035!!PVCCIN_CPU1_DECAP_VR!!
S!@baseboard_fab2_lib.baseboard_fab2(sch_1):page76_i85@mstr_discrete.cap(chips)!CAP_0603-22.0UF,4V,20%,X6S,E15A!C2D33!//jf4cfls225.pdx.intel.com/apd_proj/ppg_lib/epg_masterlib/logical/mstr_discrete/cap/chips/chips.prt!CAP!CAP_0603-22.0UF,4V,20%,X6S,E15431-004!CAP!!!F3023!!PVCCIN_CPU1_DECAP_VR!!
S!@baseboard_fab2_lib.baseboard_fab2(sch_1):page76_i90@mstr_discrete.cap(chips)!CAP_0603-22.0UF,4V,20%,X6S,E15A!C2D32!//jf4cfls225.pdx.intel.com/apd_proj/ppg_lib/epg_masterlib/logical/mstr_discrete/cap/chips/chips.prt!CAP!CAP_0603-22.0UF,4V,20%,X6S,E15431-004!CAP!!!F3024!!PVCCIN_CPU1_DECAP_VR!!
S!@baseboard_fab2_lib.baseboard_fab2(sch_1):page76_i63@mstr_discrete.cap(chips)!CAP_0603-22.0UF,4V,20%,X6S,E15A!C2D31!//jf4cfls225.pdx.intel.com/apd_proj/ppg_lib/epg_masterlib/logical/mstr_discrete/cap/chips/chips.prt!CAP!CAP_0603-22.0UF,4V,20%,X6S,E15431-004!CAP!!!F3025!!PVCCIN_CPU1_DECAP_VR!!
S!@baseboard_fab2_lib.baseboard_fab2(sch_1):page76_i83@mstr_discrete.cap(chips)!CAP_0603-22.0UF,4V,20%,X6S,E15A!C2D30!//jf4cfls225.pdx.intel.com/apd_proj/ppg_lib/epg_masterlib/logical/mstr_discrete/cap/chips/chips.prt!CAP!CAP_0603-22.0UF,4V,20%,X6S,E15431-004!CAP!!!F3026!!PVCCIN_CPU1_DECAP_VR!!
S!@baseboard_fab2_lib.baseboard_fab2(sch_1):page76_i199@mstr_discrete.cap(chips)!CAP_0603-22.0UF,4V,20%,X6S,E15A!C2D29!//jf4cfls225.pdx.intel.com/apd_proj/ppg_lib/epg_masterlib/logical/mstr_discrete/cap/chips/chips.prt!CAP!CAP_0603-22.0UF,4V,20%,X6S,E15431-004!CAP!!!F3027!!PVCCIN_CPU1_DECAP_VR!!
S!@baseboard_fab2_lib.baseboard_fab2(sch_1):page76_i198@mstr_discrete.cap(chips)!CAP_0603-22.0UF,4V,20%,X6S,E15A!C2D28!//jf4cfls225.pdx.intel.com/apd_proj/ppg_lib/epg_masterlib/logical/mstr_discrete/cap/chips/chips.prt!CAP!CAP_0603-22.0UF,4V,20%,X6S,E15431-004!CAP!!!F3028!!PVCCIN_CPU1_DECAP_VR!!
S!@baseboard_fab2_lib.baseboard_fab2(sch_1):page76_i82@mstr_discrete.cap(chips)!CAP_0603-22.0UF,4V,20%,X6S,E15A!C2D25!//jf4cfls225.pdx.intel.com/apd_proj/ppg_lib/epg_masterlib/logical/mstr_discrete/cap/chips/chips.prt!CAP!CAP_0603-22.0UF,4V,20%,X6S,E15431-004!CAP!!!F3031!!PVCCIN_CPU1_DECAP_VR!!
S!@baseboard_fab2_lib.baseboard_fab2(sch_1):page76_i80@mstr_discrete.cap(chips)!CAP_0603-22.0UF,4V,20%,X6S,E15A!C2D24!//jf4cfls225.pdx.intel.com/apd_proj/ppg_lib/epg_masterlib/logical/mstr_discrete/cap/chips/chips.prt!CAP!CAP_0603-22.0UF,4V,20%,X6S,E15431-004!CAP!!!F3032!!PVCCIN_CPU1_DECAP_VR!!
S!@baseboard_fab2_lib.baseboard_fab2(sch_1):page76_i61@mstr_discrete.cap(chips)!CAP_0603-22.0UF,4V,20%,X6S,E15A!C2D22!//jf4cfls225.pdx.intel.com/apd_proj/ppg_lib/epg_masterlib/logical/mstr_discrete/cap/chips/chips.prt!CAP!CAP_0603-22.0UF,4V,20%,X6S,E15431-004!CAP!!!F3034!!PVCCIN_CPU1_DECAP_VR!!
S!@baseboard_fab2_lib.baseboard_fab2(sch_1):page76_i75@mstr_discrete.cap(chips)!CAP_0603-22.0UF,4V,20%,X6S,E15A!C2D19!//jf4cfls225.pdx.intel.com/apd_proj/ppg_lib/epg_masterlib/logical/mstr_discrete/cap/chips/chips.prt!CAP!CAP_0603-22.0UF,4V,20%,X6S,E15431-004!CAP!!!F3037!!PVCCIN_CPU1_DECAP_VR!!
S!@baseboard_fab2_lib.baseboard_fab2(sch_1):page76_i79@mstr_discrete.cap(chips)!CAP_0603-22.0UF,4V,20%,X6S,E15A!C2D20!//jf4cfls225.pdx.intel.com/apd_proj/ppg_lib/epg_masterlib/logical/mstr_discrete/cap/chips/chips.prt!CAP!CAP_0603-22.0UF,4V,20%,X6S,E15431-004!CAP!!!F3036!!PVCCIN_CPU1_DECAP_VR!!
S!@baseboard_fab2_lib.baseboard_fab2(sch_1):page76_i59@mstr_discrete.cap(chips)!CAP_0603-22.0UF,4V,20%,X6S,E15A!C2D12!//jf4cfls225.pdx.intel.com/apd_proj/ppg_lib/epg_masterlib/logical/mstr_discrete/cap/chips/chips.prt!CAP!CAP_0603-22.0UF,4V,20%,X6S,E15431-004!CAP!!!F3044!!PVCCIN_CPU1_DECAP_VR!!
S!@baseboard_fab2_lib.baseboard_fab2(sch_1):page76_i159@mstr_discrete.cap(chips)!CAP_0603-22.0UF,4V,20%,X6S,E15A!C2D15!//jf4cfls225.pdx.intel.com/apd_proj/ppg_lib/epg_masterlib/logical/mstr_discrete/cap/chips/chips.prt!CAP!CAP_0603-22.0UF,4V,20%,X6S,E15431-004!CAP!!!F3041!!PVCCIN_CPU1_DECAP_VR!!
S!@baseboard_fab2_lib.baseboard_fab2(sch_1):page214_i108@mstr_discrete.cap(chips)!CAP_0603-22.0UF,4V,20%,X6S,E15A!C3E1!//jf4cfls225.pdx.intel.com/apd_proj/ppg_lib/epg_masterlib/logical/mstr_discrete/cap/chips/chips.prt!CAP!CAP_0603-22.0UF,4V,20%,X6S,E15431-004!CAP!!!F2968!!PVCCIO_CPU1!!
S!@baseboard_fab2_lib.baseboard_fab2(sch_1):page212_i23@mstr_discrete.cap(chips)!CAP_0603-22.0UF,4V,20%,X6S,E15A!C7C6!//jf4cfls225.pdx.intel.com/apd_proj/ppg_lib/epg_masterlib/logical/mstr_discrete/cap/chips/chips.prt!CAP!CAP_0603-22.0UF,4V,20%,X6S,E15431-004!CAP!!!F2800!!PVCCIO_CPU0!!
S!@baseboard_fab2_lib.baseboard_fab2(sch_1):page214_i65@mstr_discrete.cap(chips)!CAP_0603-22.0UF,4V,20%,X6S,E15A!C7R1!//jf4cfls225.pdx.intel.com/apd_proj/ppg_lib/epg_masterlib/logical/mstr_discrete/cap/chips/chips.prt!CAP!CAP_0603-22.0UF,4V,20%,X6S,E15431-004!CAP!!!F2790!!PVCCIO_CPU1!!
S!@baseboard_fab2_lib.baseboard_fab2(sch_1):page212_i77@mstr_discrete.cap(chips)!CAP_0603-22.0UF,4V,20%,X6S,E15A!C7C10!//jf4cfls225.pdx.intel.com/apd_proj/ppg_lib/epg_masterlib/logical/mstr_discrete/cap/chips/chips.prt!CAP!CAP_0603-22.0UF,4V,20%,X6S,E15431-004!CAP!!!F2798!!!!
S!@baseboard_fab2_lib.baseboard_fab2(sch_1):page202_i27@mstr_discrete.cap(chips)!CAP_0603-22.0UF,4V,20%,X6S,E15A!C4E11!//jf4cfls225.pdx.intel.com/apd_proj/ppg_lib/epg_masterlib/logical/mstr_discrete/cap/chips/chips.prt!CAP!CAP_0603-22.0UF,4V,20%,X6S,E15431-004!CAP!!!F2942!!PVCCIN_CPU0_PWR_VR!!
S!@baseboard_fab2_lib.baseboard_fab2(sch_1):page204_i9@mstr_discrete.cap(chips)!CAP_0603-22.0UF,4V,20%,X6S,E15A!C4D12!//jf4cfls225.pdx.intel.com/apd_proj/ppg_lib/epg_masterlib/logical/mstr_discrete/cap/chips/chips.prt!CAP!CAP_0603-22.0UF,4V,20%,X6S,E15431-004!CAP!!!F2945!!PVCCIN_CPU0_PWR_VR!!
S!@baseboard_fab2_lib.baseboard_fab2(sch_1):page205_i5@mstr_discrete.cap(chips)!CAP_0603-22.0UF,4V,20%,X6S,E15A!C6N7!//jf4cfls225.pdx.intel.com/apd_proj/ppg_lib/epg_masterlib/logical/mstr_discrete/cap/chips/chips.prt!CAP!CAP_0603-22.0UF,4V,20%,X6S,E15431-004!CAP!!!F2817!!PVSA_CPU0_PWR_VR!!
S!@baseboard_fab2_lib.baseboard_fab2(sch_1):page202_i9@mstr_discrete.cap(chips)!CAP_0603-22.0UF,4V,20%,X6S,E15A!C6R7!//jf4cfls225.pdx.intel.com/apd_proj/ppg_lib/epg_masterlib/logical/mstr_discrete/cap/chips/chips.prt!CAP!CAP_0603-22.0UF,4V,20%,X6S,E15431-004!CAP!!!F2812!!PVCCIN_CPU0_PWR_VR!!
S!@baseboard_fab2_lib.baseboard_fab2(sch_1):page207_i8@mstr_discrete.cap(chips)!CAP_0603-22.0UF,4V,20%,X6S,E15A!C9R8!//jf4cfls225.pdx.intel.com/apd_proj/ppg_lib/epg_masterlib/logical/mstr_discrete/cap/chips/chips.prt!CAP!CAP_0603-22.0UF,4V,20%,X6S,E15431-004!CAP!!!F2748!!PVCCIN_CPU1_PWR_VR!!
S!@baseboard_fab2_lib.baseboard_fab2(sch_1):page207_i18@mstr_discrete.cap(chips)!CAP_0603-22.0UF,4V,20%,X6S,E15A!C1E3!//jf4cfls225.pdx.intel.com/apd_proj/ppg_lib/epg_masterlib/logical/mstr_discrete/cap/chips/chips.prt!CAP!CAP_0603-22.0UF,4V,20%,X6S,E15431-004!CAP!!!F3062!!PVCCIN_CPU1_PWR_VR!!
S!@baseboard_fab2_lib.baseboard_fab2(sch_1):page208_i9@mstr_discrete.cap(chips)!CAP_0603-22.0UF,4V,20%,X6S,E15A!C1D14!//jf4cfls225.pdx.intel.com/apd_proj/ppg_lib/epg_masterlib/logical/mstr_discrete/cap/chips/chips.prt!CAP!CAP_0603-22.0UF,4V,20%,X6S,E15431-004!CAP!!!F3064!!PVCCIN_CPU1_PWR_VR!!
S!@baseboard_fab2_lib.baseboard_fab2(sch_1):page208_i22@mstr_discrete.cap(chips)!CAP_0603-22.0UF,4V,20%,X6S,E15A!C1D3!//jf4cfls225.pdx.intel.com/apd_proj/ppg_lib/epg_masterlib/logical/mstr_discrete/cap/chips/chips.prt!CAP!CAP_0603-22.0UF,4V,20%,X6S,E15431-004!CAP!!!F3065!!PVCCIN_CPU1_PWR_VR!!
S!@baseboard_fab2_lib.baseboard_fab2(sch_1):page210_i8@mstr_discrete.cap(chips)!CAP_0603-22.0UF,4V,20%,X6S,E15A!C1C19!//jf4cfls225.pdx.intel.com/apd_proj/ppg_lib/epg_masterlib/logical/mstr_discrete/cap/chips/chips.prt!CAP!CAP_0603-22.0UF,4V,20%,X6S,E15431-004!CAP!!!F3066!!PVSA_CPU1_PWR_VR!!
S!@baseboard_fab2_lib.baseboard_fab2(sch_1):page203_i25@mstr_discrete.cap(chips)!CAP_0603-22.0UF,4V,20%,X6S,E15A!C6P3!//jf4cfls225.pdx.intel.com/apd_proj/ppg_lib/epg_masterlib/logical/mstr_discrete/cap/chips/chips.prt!CAP!CAP_0603-22.0UF,4V,20%,X6S,E15431-004!CAP!!!F2816!!PVCCIN_CPU0_PWR_VR!!
S!@baseboard_fab2_lib.baseboard_fab2(sch_1):page209_i42@mstr_discrete.cap(chips)!CAP_0603-22.0UF,4V,20%,X6S,E15A!C1D24!//jf4cfls225.pdx.intel.com/apd_proj/ppg_lib/epg_masterlib/logical/mstr_discrete/cap/chips/chips.prt!CAP!CAP_0603-22.0UF,4V,20%,X6S,E15431-004!CAP!!!F3063!!PVCCIN_CPU1_PWR_VR!!
S!@baseboard_fab2_lib.baseboard_fab2(sch_1):page203_i66@mstr_discrete.cap(chips)!CAP_0603-22.0UF,4V,20%,X6S,E15A!C6P21!//jf4cfls225.pdx.intel.com/apd_proj/ppg_lib/epg_masterlib/logical/mstr_discrete/cap/chips/chips.prt!CAP!CAP_0603-22.0UF,4V,20%,X6S,E15431-004!CAP!!!F2814!!PVCCIN_CPU0_PWR_VR!!
S!@baseboard_fab2_lib.baseboard_fab2(sch_1):page202_i62@mstr_discrete.cap(chips)!CAP_0603-22.0UF,4V,20%,X6S,E15A!C6P16!//jf4cfls225.pdx.intel.com/apd_proj/ppg_lib/epg_masterlib/logical/mstr_discrete/cap/chips/chips.prt!CAP!CAP_0603-22.0UF,4V,20%,X6S,E15431-004!CAP!!!F2815!!!!
S!@baseboard_fab2_lib.baseboard_fab2(sch_1):page202_i61@mstr_discrete.cap(chips)!CAP_0603-22.0UF,4V,20%,X6S,E15A!C4E3!//jf4cfls225.pdx.intel.com/apd_proj/ppg_lib/epg_masterlib/logical/mstr_discrete/cap/chips/chips.prt!CAP!CAP_0603-22.0UF,4V,20%,X6S,E15431-004!CAP!!!F2943!!!!
S!@baseboard_fab2_lib.baseboard_fab2(sch_1):page203_i68@mstr_discrete.cap(chips)!CAP_0603-22.0UF,4V,20%,X6S,E15A!C4D34!//jf4cfls225.pdx.intel.com/apd_proj/ppg_lib/epg_masterlib/logical/mstr_discrete/cap/chips/chips.prt!CAP!CAP_0603-22.0UF,4V,20%,X6S,E15431-004!CAP!!!F2944!!!!
S!@baseboard_fab2_lib.baseboard_fab2(sch_1):page203_i69@mstr_discrete.cap(chips)!CAP_0603-22.0UF,4V,20%,X6S,E15A!C4D4!//jf4cfls225.pdx.intel.com/apd_proj/ppg_lib/epg_masterlib/logical/mstr_discrete/cap/chips/chips.prt!CAP!CAP_0603-22.0UF,4V,20%,X6S,E15431-004!CAP!!!F2946!!!!
S!@baseboard_fab2_lib.baseboard_fab2(sch_1):page204_i70@mstr_discrete.cap(chips)!CAP_0603-22.0UF,4V,20%,X6S,E15A!C6R2!//jf4cfls225.pdx.intel.com/apd_proj/ppg_lib/epg_masterlib/logical/mstr_discrete/cap/chips/chips.prt!CAP!CAP_0603-22.0UF,4V,20%,X6S,E15431-004!CAP!!!F2813!!!!
S!@baseboard_fab2_lib.baseboard_fab2(sch_1):page205_i43@mstr_discrete.cap(chips)!CAP_0603-22.0UF,4V,20%,X6S,E15A!C4C11!//jf4cfls225.pdx.intel.com/apd_proj/ppg_lib/epg_masterlib/logical/mstr_discrete/cap/chips/chips.prt!CAP!CAP_0603-22.0UF,4V,20%,X6S,E15431-004!CAP!!!F2947!!!!
S!@baseboard_fab2_lib.baseboard_fab2(sch_1):page207_i59@mstr_discrete.cap(chips)!CAP_0603-22.0UF,4V,20%,X6S,E15A!C9P3!//jf4cfls225.pdx.intel.com/apd_proj/ppg_lib/epg_masterlib/logical/mstr_discrete/cap/chips/chips.prt!CAP!CAP_0603-22.0UF,4V,20%,X6S,E15431-004!CAP!!!F2752!!!!
S!@baseboard_fab2_lib.baseboard_fab2(sch_1):page207_i58@mstr_discrete.cap(chips)!CAP_0603-22.0UF,4V,20%,X6S,E15A!C1E9!//jf4cfls225.pdx.intel.com/apd_proj/ppg_lib/epg_masterlib/logical/mstr_discrete/cap/chips/chips.prt!CAP!CAP_0603-22.0UF,4V,20%,X6S,E15431-004!CAP!!!F3061!!!!
S!@baseboard_fab2_lib.baseboard_fab2(sch_1):page208_i67@mstr_discrete.cap(chips)!CAP_0603-22.0UF,4V,20%,X6S,E15A!C9R2!//jf4cfls225.pdx.intel.com/apd_proj/ppg_lib/epg_masterlib/logical/mstr_discrete/cap/chips/chips.prt!CAP!CAP_0603-22.0UF,4V,20%,X6S,E15431-004!CAP!!!F2749!!!!
S!@baseboard_fab2_lib.baseboard_fab2(sch_1):page208_i66@mstr_discrete.cap(chips)!CAP_0603-22.0UF,4V,20%,X6S,E15A!C9P10!//jf4cfls225.pdx.intel.com/apd_proj/ppg_lib/epg_masterlib/logical/mstr_discrete/cap/chips/chips.prt!CAP!CAP_0603-22.0UF,4V,20%,X6S,E15431-004!CAP!!!F2751!!!!
S!@baseboard_fab2_lib.baseboard_fab2(sch_1):page209_i55@mstr_discrete.cap(chips)!CAP_0603-22.0UF,4V,20%,X6S,E15A!C9P20!//jf4cfls225.pdx.intel.com/apd_proj/ppg_lib/epg_masterlib/logical/mstr_discrete/cap/chips/chips.prt!CAP!CAP_0603-22.0UF,4V,20%,X6S,E15431-004!CAP!!!F2750!!!!
S!@baseboard_fab2_lib.baseboard_fab2(sch_1):page210_i44@mstr_discrete.cap(chips)!CAP_0603-22.0UF,4V,20%,X6S,E15A!C9N22!//jf4cfls225.pdx.intel.com/apd_proj/ppg_lib/epg_masterlib/logical/mstr_discrete/cap/chips/chips.prt!CAP!CAP_0603-22.0UF,4V,20%,X6S,E15431-004!CAP!!!F2753!!!!
S!@baseboard_fab2_lib.baseboard_fab2(sch_1):page76_i208@mstr_discrete.cap(chips)!CAP_0603-22.0UF,4V,20%,X6S,E15A!C3D19!//jf4cfls225.pdx.intel.com/apd_proj/ppg_lib/epg_masterlib/logical/mstr_discrete/cap/chips/chips.prt!CAP!CAP_0603-22.0UF,4V,20%,X6S,E15431-004!CAP!!!F2974!!PVCCIN_CPU1_DECAP_VR!!
S!@baseboard_fab2_lib.baseboard_fab2(sch_1):page42_i180@mstr_discrete.cap(chips)!CAP_0603-22.0UF,4V,20%,X6S,E15A!C5D52!//jf4cfls225.pdx.intel.com/apd_proj/ppg_lib/epg_masterlib/logical/mstr_discrete/cap/chips/chips.prt!CAP!CAP_0603-22.0UF,4V,20%,X6S,E15431-004!CAP!!!F2878!!PVCCIN_CPU0_DECAP_VR!!
S!@baseboard_fab2_lib.baseboard_fab2(sch_1):page42_i174@mstr_discrete.cap(chips)!CAP_0603-22.0UF,4V,20%,X6S,E15A!C5D33!//jf4cfls225.pdx.intel.com/apd_proj/ppg_lib/epg_masterlib/logical/mstr_discrete/cap/chips/chips.prt!CAP!CAP_0603-22.0UF,4V,20%,X6S,E15431-004!CAP!!!F2897!!PVCCIN_CPU0_DECAP_VR!!
S!@baseboard_fab2_lib.baseboard_fab2(sch_1):page42_i175@mstr_discrete.cap(chips)!CAP_0603-22.0UF,4V,20%,X6S,E15A!C5D34!//jf4cfls225.pdx.intel.com/apd_proj/ppg_lib/epg_masterlib/logical/mstr_discrete/cap/chips/chips.prt!CAP!CAP_0603-22.0UF,4V,20%,X6S,E15431-004!CAP!!!F2896!!PVCCIN_CPU0_DECAP_VR!!
S!@baseboard_fab2_lib.baseboard_fab2(sch_1):page42_i179@mstr_discrete.cap(chips)!CAP_0603-22.0UF,4V,20%,X6S,E15A!C5D53!//jf4cfls225.pdx.intel.com/apd_proj/ppg_lib/epg_masterlib/logical/mstr_discrete/cap/chips/chips.prt!CAP!CAP_0603-22.0UF,4V,20%,X6S,E15431-004!CAP!!!F2877!!PVCCIN_CPU0_DECAP_VR!!
S!@baseboard_fab2_lib.baseboard_fab2(sch_1):page76_i202@mstr_discrete.cap(chips)!CAP_0603-22.0UF,4V,20%,X6S,E15A!C2D3!//jf4cfls225.pdx.intel.com/apd_proj/ppg_lib/epg_masterlib/logical/mstr_discrete/cap/chips/chips.prt!CAP!CAP_0603-22.0UF,4V,20%,X6S,E15431-004!CAP!!!F3045!!PVCCIN_CPU1_DECAP_VR!!
S!@baseboard_fab2_lib.baseboard_fab2(sch_1):page76_i201@mstr_discrete.cap(chips)!CAP_0603-22.0UF,4V,20%,X6S,E15A!C2D2!//jf4cfls225.pdx.intel.com/apd_proj/ppg_lib/epg_masterlib/logical/mstr_discrete/cap/chips/chips.prt!CAP!CAP_0603-22.0UF,4V,20%,X6S,E15431-004!CAP!!!F3046!!PVCCIN_CPU1_DECAP_VR!!
S!@baseboard_fab2_lib.baseboard_fab2(sch_1):page76_i207@mstr_discrete.cap(chips)!CAP_0603-22.0UF,4V,20%,X6S,E15A!C3D20!//jf4cfls225.pdx.intel.com/apd_proj/ppg_lib/epg_masterlib/logical/mstr_discrete/cap/chips/chips.prt!CAP!CAP_0603-22.0UF,4V,20%,X6S,E15431-004!CAP!!!F2973!!PVCCIN_CPU1_DECAP_VR!!
S!@baseboard_fab2_lib.baseboard_fab2(sch_1):page42_i173@mstr_discrete.cap(chips)!CAP_0603-22.0UF,4V,20%,X6S,E15A!C5D20!//jf4cfls225.pdx.intel.com/apd_proj/ppg_lib/epg_masterlib/logical/mstr_discrete/cap/chips/chips.prt!CAP!CAP_0603-22.0UF,4V,20%,X6S,E15431-004!CAP!!!F2910!!PVCCIN_CPU0_DECAP_VR!!
S!@baseboard_fab2_lib.baseboard_fab2(sch_1):page42_i100@mstr_discrete.cap(chips)!CAP_0603-22.0UF,4V,20%,X6S,E15A!C5D28!//jf4cfls225.pdx.intel.com/apd_proj/ppg_lib/epg_masterlib/logical/mstr_discrete/cap/chips/chips.prt!CAP!CAP_0603-22.0UF,4V,20%,X6S,E15431-004!CAP!!!F2902!!PVCCIN_CPU0_DECAP_VR!!
S!@baseboard_fab2_lib.baseboard_fab2(sch_1):page42_i109@mstr_discrete.cap(chips)!CAP_0603-22.0UF,4V,20%,X6S,E15A!C5D27!//jf4cfls225.pdx.intel.com/apd_proj/ppg_lib/epg_masterlib/logical/mstr_discrete/cap/chips/chips.prt!CAP!CAP_0603-22.0UF,4V,20%,X6S,E15431-004!CAP!!!F2903!!PVCCIN_CPU0_DECAP_VR!!
S!@baseboard_fab2_lib.baseboard_fab2(sch_1):page42_i176@mstr_discrete.cap(chips)!CAP_0603-22.0UF,4V,20%,X6S,E15A!C5D35!//jf4cfls225.pdx.intel.com/apd_proj/ppg_lib/epg_masterlib/logical/mstr_discrete/cap/chips/chips.prt!CAP!CAP_0603-22.0UF,4V,20%,X6S,E15431-004!CAP!!!F2895!!PVCCIN_CPU0_DECAP_VR!!
S!@baseboard_fab2_lib.baseboard_fab2(sch_1):page42_i155@mstr_discrete.cap(chips)!CAP_0603-22.0UF,4V,20%,X6S,E15A!C5D25!//jf4cfls225.pdx.intel.com/apd_proj/ppg_lib/epg_masterlib/logical/mstr_discrete/cap/chips/chips.prt!CAP!CAP_0603-22.0UF,4V,20%,X6S,E15431-004!CAP!!!F2905!!PVCCIN_CPU0_DECAP_VR!!
S!@baseboard_fab2_lib.baseboard_fab2(sch_1):page42_i156@mstr_discrete.cap(chips)!CAP_0603-22.0UF,4V,20%,X6S,E15A!C5D45!//jf4cfls225.pdx.intel.com/apd_proj/ppg_lib/epg_masterlib/logical/mstr_discrete/cap/chips/chips.prt!CAP!CAP_0603-22.0UF,4V,20%,X6S,E15431-004!CAP!!!F2885!!PVCCIN_CPU0_DECAP_VR!!
S!@baseboard_fab2_lib.baseboard_fab2(sch_1):page76_i204@mstr_discrete.cap(chips)!CAP_0603-22.0UF,4V,20%,X6S,E15A!C2D46!//jf4cfls225.pdx.intel.com/apd_proj/ppg_lib/epg_masterlib/logical/mstr_discrete/cap/chips/chips.prt!CAP!CAP_0603-22.0UF,4V,20%,X6S,E15431-004!CAP!!!F3014!!PVCCIN_CPU1_DECAP_VR!!
S!@baseboard_fab2_lib.baseboard_fab2(sch_1):page76_i73@mstr_discrete.cap(chips)!CAP_0603-22.0UF,4V,20%,X6S,E15A!C2D13!//jf4cfls225.pdx.intel.com/apd_proj/ppg_lib/epg_masterlib/logical/mstr_discrete/cap/chips/chips.prt!CAP!CAP_0603-22.0UF,4V,20%,X6S,E15431-004!CAP!!!F3043!!PVCCIN_CPU1_DECAP_VR!!
S!@baseboard_fab2_lib.baseboard_fab2(sch_1):page76_i76@mstr_discrete.cap(chips)!CAP_0603-22.0UF,4V,20%,X6S,E15A!C2D14!//jf4cfls225.pdx.intel.com/apd_proj/ppg_lib/epg_masterlib/logical/mstr_discrete/cap/chips/chips.prt!CAP!CAP_0603-22.0UF,4V,20%,X6S,E15431-004!CAP!!!F3042!!PVCCIN_CPU1_DECAP_VR!!
S!@baseboard_fab2_lib.baseboard_fab2(sch_1):page76_i203@mstr_discrete.cap(chips)!CAP_0603-22.0UF,4V,20%,X6S,E15A!C2D47!//jf4cfls225.pdx.intel.com/apd_proj/ppg_lib/epg_masterlib/logical/mstr_discrete/cap/chips/chips.prt!CAP!CAP_0603-22.0UF,4V,20%,X6S,E15431-004!CAP!!!F3013!!PVCCIN_CPU1_DECAP_VR!!
S!@baseboard_fab2_lib.baseboard_fab2(sch_1):page76_i160@mstr_discrete.cap(chips)!CAP_0603-22.0UF,4V,20%,X6S,E15A!C2D38!//jf4cfls225.pdx.intel.com/apd_proj/ppg_lib/epg_masterlib/logical/mstr_discrete/cap/chips/chips.prt!CAP!CAP_0603-22.0UF,4V,20%,X6S,E15431-004!CAP!!!F3018!!PVCCIN_CPU1_DECAP_VR!!
S!@baseboard_fab2_lib.baseboard_fab2(sch_1):page76_i205@mstr_discrete.cap(chips)!CAP_0603-22.0UF,4V,20%,X6S,E15A!C3D25!//jf4cfls225.pdx.intel.com/apd_proj/ppg_lib/epg_masterlib/logical/mstr_discrete/cap/chips/chips.prt!CAP!CAP_0603-22.0UF,4V,20%,X6S,E15431-004!CAP!!!F2969!!PVCCIN_CPU1_DECAP_VR!!
S!@baseboard_fab2_lib.baseboard_fab2(sch_1):page76_i161@mstr_discrete.cap(chips)!CAP_0603-22.0UF,4V,20%,X6S,E15A!C2D35!//jf4cfls225.pdx.intel.com/apd_proj/ppg_lib/epg_masterlib/logical/mstr_discrete/cap/chips/chips.prt!CAP!CAP_0603-22.0UF,4V,20%,X6S,E15431-004!CAP!!!F3021!!PVCCIN_CPU1_DECAP_VR!!
S!@baseboard_fab2_lib.baseboard_fab2(sch_1):page76_i179@mstr_discrete.cap(chips)!CAP_0603-22.0UF,4V,20%,X6S,E15A!C7P12!//jf4cfls225.pdx.intel.com/apd_proj/ppg_lib/epg_masterlib/logical/mstr_discrete/cap/chips/chips.prt!CAP!CAP_0603-22.0UF,4V,20%,X6S,E15431-004!CAP!!!F2792!!PVCCIN_CPU1_DECAP_VR!!
S!@baseboard_fab2_lib.baseboard_fab2(sch_1):page42_i90@mstr_discrete.cap(chips)!CAP_0603-22.0UF,4V,20%,X6S,E15A!C5D48!//jf4cfls225.pdx.intel.com/apd_proj/ppg_lib/epg_masterlib/logical/mstr_discrete/cap/chips/chips.prt!CAP!CAP_0603-22.0UF,4V,20%,X6S,E15431-004!CAP!!!F2882!!PVCCIN_CPU0_DECAP_VR!!
S!@baseboard_fab2_lib.baseboard_fab2(sch_1):page42_i68@mstr_discrete.cap(chips)!CAP_0603-22.0UF,4V,20%,X6S,E15A!C6D8!//jf4cfls225.pdx.intel.com/apd_proj/ppg_lib/epg_masterlib/logical/mstr_discrete/cap/chips/chips.prt!CAP!CAP_0603-22.0UF,4V,20%,X6S,E15431-004!CAP!!!F2820!!PVCCIN_CPU0_DECAP_VR!!
S!@baseboard_fab2_lib.baseboard_fab2(sch_1):page42_i89@mstr_discrete.cap(chips)!CAP_0603-22.0UF,4V,20%,X6S,E15A!C5D50!//jf4cfls225.pdx.intel.com/apd_proj/ppg_lib/epg_masterlib/logical/mstr_discrete/cap/chips/chips.prt!CAP!CAP_0603-22.0UF,4V,20%,X6S,E15431-004!CAP!!!F2880!!PVCCIN_CPU0_DECAP_VR!!
S!@baseboard_fab2_lib.baseboard_fab2(sch_1):page42_i151@mstr_discrete.cap(chips)!CAP_0603-22.0UF,4V,20%,X6S,E15A!C5D36!//jf4cfls225.pdx.intel.com/apd_proj/ppg_lib/epg_masterlib/logical/mstr_discrete/cap/chips/chips.prt!CAP!CAP_0603-22.0UF,4V,20%,X6S,E15431-004!CAP!!!F2894!!PVCCIN_CPU0_DECAP_VR!!
S!@baseboard_fab2_lib.baseboard_fab2(sch_1):page42_i88@mstr_discrete.cap(chips)!CAP_0603-22.0UF,4V,20%,X6S,E15A!C5D21!//jf4cfls225.pdx.intel.com/apd_proj/ppg_lib/epg_masterlib/logical/mstr_discrete/cap/chips/chips.prt!CAP!CAP_0603-22.0UF,4V,20%,X6S,E15431-004!CAP!!!F2909!!PVCCIN_CPU0_DECAP_VR!!
S!@baseboard_fab2_lib.baseboard_fab2(sch_1):page42_i152@mstr_discrete.cap(chips)!CAP_0603-22.0UF,4V,20%,X6S,E15A!C5D49!//jf4cfls225.pdx.intel.com/apd_proj/ppg_lib/epg_masterlib/logical/mstr_discrete/cap/chips/chips.prt!CAP!CAP_0603-22.0UF,4V,20%,X6S,E15431-004!CAP!!!F2881!!PVCCIN_CPU0_DECAP_VR!!
S!@baseboard_fab2_lib.baseboard_fab2(sch_1):page42_i83@mstr_discrete.cap(chips)!CAP_0603-22.0UF,4V,20%,X6S,E15A!C5D51!//jf4cfls225.pdx.intel.com/apd_proj/ppg_lib/epg_masterlib/logical/mstr_discrete/cap/chips/chips.prt!CAP!CAP_0603-22.0UF,4V,20%,X6S,E15431-004!CAP!!!F2879!!PVCCIN_CPU0_DECAP_VR!!
S!@baseboard_fab2_lib.baseboard_fab2(sch_1):page42_i77@mstr_discrete.cap(chips)!CAP_0603-22.0UF,4V,20%,X6S,E15A!C6D2!//jf4cfls225.pdx.intel.com/apd_proj/ppg_lib/epg_masterlib/logical/mstr_discrete/cap/chips/chips.prt!CAP!CAP_0603-22.0UF,4V,20%,X6S,E15431-004!CAP!!!F2826!!PVCCIN_CPU0_DECAP_VR!!
S!@baseboard_fab2_lib.baseboard_fab2(sch_1):page42_i75@mstr_discrete.cap(chips)!CAP_0603-22.0UF,4V,20%,X6S,E15A!C6D5!//jf4cfls225.pdx.intel.com/apd_proj/ppg_lib/epg_masterlib/logical/mstr_discrete/cap/chips/chips.prt!CAP!CAP_0603-22.0UF,4V,20%,X6S,E15431-004!CAP!!!F2823!!PVCCIN_CPU0_DECAP_VR!!
S!@baseboard_fab2_lib.baseboard_fab2(sch_1):page42_i70@mstr_discrete.cap(chips)!CAP_0603-22.0UF,4V,20%,X6S,E15A!C5D37!//jf4cfls225.pdx.intel.com/apd_proj/ppg_lib/epg_masterlib/logical/mstr_discrete/cap/chips/chips.prt!CAP!CAP_0603-22.0UF,4V,20%,X6S,E15431-004!CAP!!!F2893!!PVCCIN_CPU0_DECAP_VR!!
S!@baseboard_fab2_lib.baseboard_fab2(sch_1):page42_i69@mstr_discrete.cap(chips)!CAP_0603-22.0UF,4V,20%,X6S,E15A!C5D38!//jf4cfls225.pdx.intel.com/apd_proj/ppg_lib/epg_masterlib/logical/mstr_discrete/cap/chips/chips.prt!CAP!CAP_0603-22.0UF,4V,20%,X6S,E15431-004!CAP!!!F2892!!PVCCIN_CPU0_DECAP_VR!!
S!@baseboard_fab2_lib.baseboard_fab2(sch_1):page76_i165@mstr_discrete.cap(chips)!CAP_0603-22.0UF,4V,20%,X6S,E15A!C2D39!//jf4cfls225.pdx.intel.com/apd_proj/ppg_lib/epg_masterlib/logical/mstr_discrete/cap/chips/chips.prt!CAP!CAP_0603-22.0UF,4V,20%,X6S,E15431-004!CAP!!!F3017!!PVCCIN_CPU1_DECAP_VR!!
S!@baseboard_fab2_lib.baseboard_fab2(sch_1):page76_i166@mstr_discrete.cap(chips)!CAP_0603-22.0UF,4V,20%,X6S,E15A!C3D17!//jf4cfls225.pdx.intel.com/apd_proj/ppg_lib/epg_masterlib/logical/mstr_discrete/cap/chips/chips.prt!CAP!CAP_0603-22.0UF,4V,20%,X6S,E15431-004!CAP!!!F2976!!PVCCIN_CPU1_DECAP_VR!!
S!@baseboard_fab2_lib.baseboard_fab2(sch_1):page76_i169@mstr_discrete.cap(chips)!CAP_0603-22.0UF,4V,20%,X6S,E15A!C3D18!//jf4cfls225.pdx.intel.com/apd_proj/ppg_lib/epg_masterlib/logical/mstr_discrete/cap/chips/chips.prt!CAP!CAP_0603-22.0UF,4V,20%,X6S,E15431-004!CAP!!!F2975!!PVCCIN_CPU1_DECAP_VR!!
S!@baseboard_fab2_lib.baseboard_fab2(sch_1):page76_i10@mstr_discrete.cap(chips)!CAP_0603-22.0UF,4V,20%,X6S,E15A!C2D40!//jf4cfls225.pdx.intel.com/apd_proj/ppg_lib/epg_masterlib/logical/mstr_discrete/cap/chips/chips.prt!CAP!CAP_0603-22.0UF,4V,20%,X6S,E15431-004!CAP!!!F3016!!PVCCIN_CPU1_DECAP_VR!!
S!@baseboard_fab2_lib.baseboard_fab2(sch_1):page76_i171@mstr_discrete.cap(chips)!CAP_0603-22.0UF,4V,20%,X6S,E15A!C3D14!//jf4cfls225.pdx.intel.com/apd_proj/ppg_lib/epg_masterlib/logical/mstr_discrete/cap/chips/chips.prt!CAP!CAP_0603-22.0UF,4V,20%,X6S,E15431-004!CAP!!!F2979!!PVCCIN_CPU1_DECAP_VR!!
S!@baseboard_fab2_lib.baseboard_fab2(sch_1):page76_i8@mstr_discrete.cap(chips)!CAP_0603-22.0UF,4V,20%,X6S,E15A!C3D13!//jf4cfls225.pdx.intel.com/apd_proj/ppg_lib/epg_masterlib/logical/mstr_discrete/cap/chips/chips.prt!CAP!CAP_0603-22.0UF,4V,20%,X6S,E15431-004!CAP!!!F2980!!PVCCIN_CPU1_DECAP_VR!!
S!@baseboard_fab2_lib.baseboard_fab2(sch_1):page76_i170@mstr_discrete.cap(chips)!CAP_0603-22.0UF,4V,20%,X6S,E15A!C3D6!//jf4cfls225.pdx.intel.com/apd_proj/ppg_lib/epg_masterlib/logical/mstr_discrete/cap/chips/chips.prt!CAP!CAP_0603-22.0UF,4V,20%,X6S,E15431-004!CAP!!!F2987!!PVCCIN_CPU1_DECAP_VR!!
S!@baseboard_fab2_lib.baseboard_fab2(sch_1):page76_i7@mstr_discrete.cap(chips)!CAP_0603-22.0UF,4V,20%,X6S,E15A!C3D11!//jf4cfls225.pdx.intel.com/apd_proj/ppg_lib/epg_masterlib/logical/mstr_discrete/cap/chips/chips.prt!CAP!CAP_0603-22.0UF,4V,20%,X6S,E15431-004!CAP!!!F2982!!PVCCIN_CPU1_DECAP_VR!!
S!@baseboard_fab2_lib.baseboard_fab2(sch_1):page76_i5@mstr_discrete.cap(chips)!CAP_0603-22.0UF,4V,20%,X6S,E15A!C3D4!//jf4cfls225.pdx.intel.com/apd_proj/ppg_lib/epg_masterlib/logical/mstr_discrete/cap/chips/chips.prt!CAP!CAP_0603-22.0UF,4V,20%,X6S,E15431-004!CAP!!!F2989!!PVCCIN_CPU1_DECAP_VR!!
S!@baseboard_fab2_lib.baseboard_fab2(sch_1):page76_i176@mstr_discrete.cap(chips)!CAP_0603-22.0UF,4V,20%,X6S,E15A!C3D16!//jf4cfls225.pdx.intel.com/apd_proj/ppg_lib/epg_masterlib/logical/mstr_discrete/cap/chips/chips.prt!CAP!CAP_0603-22.0UF,4V,20%,X6S,E15431-004!CAP!!!F2977!!PVCCIN_CPU1_DECAP_VR!!
S!@baseboard_fab2_lib.baseboard_fab2(sch_1):page76_i4@mstr_discrete.cap(chips)!CAP_0603-22.0UF,4V,20%,X6S,E15A!C3D12!//jf4cfls225.pdx.intel.com/apd_proj/ppg_lib/epg_masterlib/logical/mstr_discrete/cap/chips/chips.prt!CAP!CAP_0603-22.0UF,4V,20%,X6S,E15431-004!CAP!!!F2981!!PVCCIN_CPU1_DECAP_VR!!
S!@baseboard_fab2_lib.baseboard_fab2(sch_1):page76_i18@mstr_discrete.cap(chips)!CAP_0603-22.0UF,4V,20%,X6S,E15A!C3D8!//jf4cfls225.pdx.intel.com/apd_proj/ppg_lib/epg_masterlib/logical/mstr_discrete/cap/chips/chips.prt!CAP!CAP_0603-22.0UF,4V,20%,X6S,E15431-004!CAP!!!F2985!!PVCCIN_CPU1_DECAP_VR!!
S!@baseboard_fab2_lib.baseboard_fab2(sch_1):page76_i3@mstr_discrete.cap(chips)!CAP_0603-22.0UF,4V,20%,X6S,E15A!C3D5!//jf4cfls225.pdx.intel.com/apd_proj/ppg_lib/epg_masterlib/logical/mstr_discrete/cap/chips/chips.prt!CAP!CAP_0603-22.0UF,4V,20%,X6S,E15431-004!CAP!!!F2988!!PVCCIN_CPU1_DECAP_VR!!
S!@baseboard_fab2_lib.baseboard_fab2(sch_1):page76_i15@mstr_discrete.cap(chips)!CAP_0603-22.0UF,4V,20%,X6S,E15A!C3D9!//jf4cfls225.pdx.intel.com/apd_proj/ppg_lib/epg_masterlib/logical/mstr_discrete/cap/chips/chips.prt!CAP!CAP_0603-22.0UF,4V,20%,X6S,E15431-004!CAP!!!F2984!!PVCCIN_CPU1_DECAP_VR!!
S!@baseboard_fab2_lib.baseboard_fab2(sch_1):page76_i1@mstr_discrete.cap(chips)!CAP_0603-22.0UF,4V,20%,X6S,E15A!C3D21!//jf4cfls225.pdx.intel.com/apd_proj/ppg_lib/epg_masterlib/logical/mstr_discrete/cap/chips/chips.prt!CAP!CAP_0603-22.0UF,4V,20%,X6S,E15431-004!CAP!!!F2972!!PVCCIN_CPU1_DECAP_VR!!
S!@baseboard_fab2_lib.baseboard_fab2(sch_1):page42_i153@mstr_discrete.cap(chips)!CAP_0603-22.0UF,4V,20%,X6S,E15A!C5D22!//jf4cfls225.pdx.intel.com/apd_proj/ppg_lib/epg_masterlib/logical/mstr_discrete/cap/chips/chips.prt!CAP!CAP_0603-22.0UF,4V,20%,X6S,E15431-004!CAP!!!F2908!!PVCCIN_CPU0_DECAP_VR!!
S!@baseboard_fab2_lib.baseboard_fab2(sch_1):page76_i172@mstr_discrete.cap(chips)!CAP_0603-22.0UF,4V,20%,X6S,E15A!C3D23!//jf4cfls225.pdx.intel.com/apd_proj/ppg_lib/epg_masterlib/logical/mstr_discrete/cap/chips/chips.prt!CAP!CAP_0603-22.0UF,4V,20%,X6S,E15431-004!CAP!!!F2971!!PVCCIN_CPU1_DECAP_VR!!
S!@baseboard_fab2_lib.baseboard_fab2(sch_1):page76_i206@mstr_discrete.cap(chips)!CAP_0603-22.0UF,4V,20%,X6S,E15A!C7P16!//jf4cfls225.pdx.intel.com/apd_proj/ppg_lib/epg_masterlib/logical/mstr_discrete/cap/chips/chips.prt!CAP!CAP_0603-22.0UF,4V,20%,X6S,E15431-004!CAP!!!F2791!!PVCCIN_CPU1_DECAP_VR!!
S!@baseboard_fab2_lib.baseboard_fab2(sch_1):page76_i174@mstr_discrete.cap(chips)!CAP_0603-22.0UF,4V,20%,X6S,E15A!C3D15!//jf4cfls225.pdx.intel.com/apd_proj/ppg_lib/epg_masterlib/logical/mstr_discrete/cap/chips/chips.prt!CAP!CAP_0603-22.0UF,4V,20%,X6S,E15431-004!CAP!!!F2978!!PVCCIN_CPU1_DECAP_VR!!
S!@baseboard_fab2_lib.baseboard_fab2(sch_1):page42_i178@mstr_discrete.cap(chips)!CAP_0603-22.0UF,4V,20%,X6S,E15A!C4P8!//jf4cfls225.pdx.intel.com/apd_proj/ppg_lib/epg_masterlib/logical/mstr_discrete/cap/chips/chips.prt!CAP!CAP_0603-22.0UF,4V,20%,X6S,E15431-004!CAP!!!F2939!!PVCCIN_CPU0_DECAP_VR!!
S!@baseboard_fab2_lib.baseboard_fab2(sch_1):page42_i147@mstr_discrete.cap(chips)!CAP_0603-22.0UF,4V,20%,X6S,E15A!C6D10!//jf4cfls225.pdx.intel.com/apd_proj/ppg_lib/epg_masterlib/logical/mstr_discrete/cap/chips/chips.prt!CAP!CAP_0603-22.0UF,4V,20%,X6S,E15431-004!CAP!!!F2818!!PVCCIN_CPU0_DECAP_VR!!
S!@baseboard_fab2_lib.baseboard_fab2(sch_1):page42_i145@mstr_discrete.cap(chips)!CAP_0603-22.0UF,4V,20%,X6S,E15A!C6D9!//jf4cfls225.pdx.intel.com/apd_proj/ppg_lib/epg_masterlib/logical/mstr_discrete/cap/chips/chips.prt!CAP!CAP_0603-22.0UF,4V,20%,X6S,E15431-004!CAP!!!F2819!!PVCCIN_CPU0_DECAP_VR!!
S!@baseboard_fab2_lib.baseboard_fab2(sch_1):page42_i164@mstr_discrete.cap(chips)!CAP_0603-22.0UF,4V,20%,X6S,E15A!C4P6!//jf4cfls225.pdx.intel.com/apd_proj/ppg_lib/epg_masterlib/logical/mstr_discrete/cap/chips/chips.prt!CAP!CAP_0603-22.0UF,4V,20%,X6S,E15431-004!CAP!!!F2940!!PVCCIN_CPU0_DECAP_VR!!
S!@baseboard_fab2_lib.baseboard_fab2(sch_1):page76_i164@mstr_discrete.cap(chips)!CAP_0603-22.0UF,4V,20%,X6S,E15A!C3D7!//jf4cfls225.pdx.intel.com/apd_proj/ppg_lib/epg_masterlib/logical/mstr_discrete/cap/chips/chips.prt!CAP!CAP_0603-22.0UF,4V,20%,X6S,E15431-004!CAP!!!F2986!!PVCCIN_CPU1_DECAP_VR!!
S!@baseboard_fab2_lib.baseboard_fab2(sch_1):page42_i98@mstr_discrete.cap(chips)!CAP_0603-22.0UF,4V,20%,X6S,E15A!C5D23!//jf4cfls225.pdx.intel.com/apd_proj/ppg_lib/epg_masterlib/logical/mstr_discrete/cap/chips/chips.prt!CAP!CAP_0603-22.0UF,4V,20%,X6S,E15431-004!CAP!!!F2907!!PVCCIN_CPU0_DECAP_VR!!
S!@baseboard_fab2_lib.baseboard_fab2(sch_1):page42_i72@mstr_discrete.cap(chips)!CAP_0603-22.0UF,4V,20%,X6S,E15A!C6D7!//jf4cfls225.pdx.intel.com/apd_proj/ppg_lib/epg_masterlib/logical/mstr_discrete/cap/chips/chips.prt!CAP!CAP_0603-22.0UF,4V,20%,X6S,E15431-004!CAP!!!F2821!!PVCCIN_CPU0_DECAP_VR!!
S!@baseboard_fab2_lib.baseboard_fab2(sch_1):page42_i81@mstr_discrete.cap(chips)!CAP_0603-22.0UF,4V,20%,X6S,E15A!C6D6!//jf4cfls225.pdx.intel.com/apd_proj/ppg_lib/epg_masterlib/logical/mstr_discrete/cap/chips/chips.prt!CAP!CAP_0603-22.0UF,4V,20%,X6S,E15431-004!CAP!!!F2822!!PVCCIN_CPU0_DECAP_VR!!
S!@baseboard_fab2_lib.baseboard_fab2(sch_1):page42_i80@mstr_discrete.cap(chips)!CAP_0603-22.0UF,4V,20%,X6S,E15A!C6D3!//jf4cfls225.pdx.intel.com/apd_proj/ppg_lib/epg_masterlib/logical/mstr_discrete/cap/chips/chips.prt!CAP!CAP_0603-22.0UF,4V,20%,X6S,E15431-004!CAP!!!F2825!!PVCCIN_CPU0_DECAP_VR!!
S!@baseboard_fab2_lib.baseboard_fab2(sch_1):page42_i74@mstr_discrete.cap(chips)!CAP_0603-22.0UF,4V,20%,X6S,E15A!C6D4!//jf4cfls225.pdx.intel.com/apd_proj/ppg_lib/epg_masterlib/logical/mstr_discrete/cap/chips/chips.prt!CAP!CAP_0603-22.0UF,4V,20%,X6S,E15431-004!CAP!!!F2824!!PVCCIN_CPU0_DECAP_VR!!
S!@baseboard_fab2_lib.baseboard_fab2(sch_1):page76_i175@mstr_discrete.cap(chips)!CAP_0603-22.0UF,4V,20%,X6S,E15A!C3D24!//jf4cfls225.pdx.intel.com/apd_proj/ppg_lib/epg_masterlib/logical/mstr_discrete/cap/chips/chips.prt!CAP!CAP_0603-22.0UF,4V,20%,X6S,E15431-004!CAP!!!F2970!!PVCCIN_CPU1_DECAP_VR!!
S!@baseboard_fab2_lib.baseboard_fab2(sch_1):page132_i56@mstr_discrete.cap(chips)!CAP_0603-22.0UF,4V,20%,X6S,E15A!C3L24!//jf4cfls225.pdx.intel.com/apd_proj/ppg_lib/epg_masterlib/logical/mstr_discrete/cap/chips/chips.prt!CAP!CAP_0603-22.0UF,4V,20%,X6S,E15431-004!CAP!!!F2961!!SB_DECOUPLING!!
S!@baseboard_fab2_lib.baseboard_fab2(sch_1):page132_i54@mstr_discrete.cap(chips)!CAP_0603-22.0UF,4V,20%,X6S,E15A!C3L22!//jf4cfls225.pdx.intel.com/apd_proj/ppg_lib/epg_masterlib/logical/mstr_discrete/cap/chips/chips.prt!CAP!CAP_0603-22.0UF,4V,20%,X6S,E15431-004!CAP!!!F2963!!SB_DECOUPLING!!
S!@baseboard_fab2_lib.baseboard_fab2(sch_1):page132_i52@mstr_discrete.cap(chips)!CAP_0603-22.0UF,4V,20%,X6S,E15A!C3L23!//jf4cfls225.pdx.intel.com/apd_proj/ppg_lib/epg_masterlib/logical/mstr_discrete/cap/chips/chips.prt!CAP!CAP_0603-22.0UF,4V,20%,X6S,E15431-004!CAP!!!F2962!!SB_DECOUPLING!!
S!@baseboard_fab2_lib.baseboard_fab2(sch_1):page132_i6@mstr_discrete.cap(chips)!CAP_0603-22.0UF,4V,20%,X6S,E15A!C3M6!//jf4cfls225.pdx.intel.com/apd_proj/ppg_lib/epg_masterlib/logical/mstr_discrete/cap/chips/chips.prt!CAP!CAP_0603-22.0UF,4V,20%,X6S,E15431-004!CAP!!!F2957!!SB_DECOUPLING!!
S!@baseboard_fab2_lib.baseboard_fab2(sch_1):page132_i19@mstr_discrete.cap(chips)!CAP_0603-22.0UF,4V,20%,X6S,E15A!C3N11!//jf4cfls225.pdx.intel.com/apd_proj/ppg_lib/epg_masterlib/logical/mstr_discrete/cap/chips/chips.prt!CAP!CAP_0603-22.0UF,4V,20%,X6S,E15431-004!CAP!!!F2954!!SB_DECOUPLING!!
S!@baseboard_fab2_lib.baseboard_fab2(sch_1):page132_i20@mstr_discrete.cap(chips)!CAP_0603-22.0UF,4V,20%,X6S,E15A!C3N31!//jf4cfls225.pdx.intel.com/apd_proj/ppg_lib/epg_masterlib/logical/mstr_discrete/cap/chips/chips.prt!CAP!CAP_0603-22.0UF,4V,20%,X6S,E15431-004!CAP!!!F2948!!SB_DECOUPLING!!
S!@baseboard_fab2_lib.baseboard_fab2(sch_1):page132_i4@mstr_discrete.cap(chips)!CAP_0603-22.0UF,4V,20%,X6S,E15A!C3L27!//jf4cfls225.pdx.intel.com/apd_proj/ppg_lib/epg_masterlib/logical/mstr_discrete/cap/chips/chips.prt!CAP!CAP_0603-22.0UF,4V,20%,X6S,E15431-004!CAP!!!F2958!!SB_DECOUPLING!!
S!@baseboard_fab2_lib.baseboard_fab2(sch_1):page132_i13@mstr_discrete.cap(chips)!CAP_0603-22.0UF,4V,20%,X6S,E15A!C3N10!//jf4cfls225.pdx.intel.com/apd_proj/ppg_lib/epg_masterlib/logical/mstr_discrete/cap/chips/chips.prt!CAP!CAP_0603-22.0UF,4V,20%,X6S,E15431-004!CAP!!!F2955!!SB_DECOUPLING!!
S!@baseboard_fab2_lib.baseboard_fab2(sch_1):page132_i17@mstr_discrete.cap(chips)!CAP_0603-22.0UF,4V,20%,X6S,E15A!C3N28!//jf4cfls225.pdx.intel.com/apd_proj/ppg_lib/epg_masterlib/logical/mstr_discrete/cap/chips/chips.prt!CAP!CAP_0603-22.0UF,4V,20%,X6S,E15431-004!CAP!!!F2950!!SB_DECOUPLING!!
S!@baseboard_fab2_lib.baseboard_fab2(sch_1):page132_i3@mstr_discrete.cap(chips)!CAP_0603-22.0UF,4V,20%,X6S,E15A!C3L26!//jf4cfls225.pdx.intel.com/apd_proj/ppg_lib/epg_masterlib/logical/mstr_discrete/cap/chips/chips.prt!CAP!CAP_0603-22.0UF,4V,20%,X6S,E15431-004!CAP!!!F2959!!SB_DECOUPLING!!
S!@baseboard_fab2_lib.baseboard_fab2(sch_1):page132_i12@mstr_discrete.cap(chips)!CAP_0603-22.0UF,4V,20%,X6S,E15A!C3N12!//jf4cfls225.pdx.intel.com/apd_proj/ppg_lib/epg_masterlib/logical/mstr_discrete/cap/chips/chips.prt!CAP!CAP_0603-22.0UF,4V,20%,X6S,E15431-004!CAP!!!F2953!!SB_DECOUPLING!!
S!@baseboard_fab2_lib.baseboard_fab2(sch_1):page132_i16@mstr_discrete.cap(chips)!CAP_0603-22.0UF,4V,20%,X6S,E15A!C3N24!//jf4cfls225.pdx.intel.com/apd_proj/ppg_lib/epg_masterlib/logical/mstr_discrete/cap/chips/chips.prt!CAP!CAP_0603-22.0UF,4V,20%,X6S,E15431-004!CAP!!!F2952!!SB_DECOUPLING!!
S!@baseboard_fab2_lib.baseboard_fab2(sch_1):page132_i2@mstr_discrete.cap(chips)!CAP_0603-22.0UF,4V,20%,X6S,E15A!C3M7!//jf4cfls225.pdx.intel.com/apd_proj/ppg_lib/epg_masterlib/logical/mstr_discrete/cap/chips/chips.prt!CAP!CAP_0603-22.0UF,4V,20%,X6S,E15431-004!CAP!!!F2956!!SB_DECOUPLING!!
S!@baseboard_fab2_lib.baseboard_fab2(sch_1):page132_i11@mstr_discrete.cap(chips)!CAP_0603-22.0UF,4V,20%,X6S,E15A!C7A36!//jf4cfls225.pdx.intel.com/apd_proj/ppg_lib/epg_masterlib/logical/mstr_discrete/cap/chips/chips.prt!CAP!CAP_0603-22.0UF,4V,20%,X6S,E15431-004!CAP!!!F2811!!SB_DECOUPLING!!
S!@baseboard_fab2_lib.baseboard_fab2(sch_1):page132_i9@mstr_discrete.cap(chips)!CAP_0603-22.0UF,4V,20%,X6S,E15A!C3N30!//jf4cfls225.pdx.intel.com/apd_proj/ppg_lib/epg_masterlib/logical/mstr_discrete/cap/chips/chips.prt!CAP!CAP_0603-22.0UF,4V,20%,X6S,E15431-004!CAP!!!F2949!!SB_DECOUPLING!!
S!@baseboard_fab2_lib.baseboard_fab2(sch_1):page132_i7@mstr_discrete.cap(chips)!CAP_0603-22.0UF,4V,20%,X6S,E15A!C7C9!//jf4cfls225.pdx.intel.com/apd_proj/ppg_lib/epg_masterlib/logical/mstr_discrete/cap/chips/chips.prt!CAP!CAP_0603-22.0UF,4V,20%,X6S,E15431-004!CAP!!!F2799!!SB_DECOUPLING!!
S!@baseboard_fab2_lib.baseboard_fab2(sch_1):page132_i1@mstr_discrete.cap(chips)!CAP_0603-22.0UF,4V,20%,X6S,E15A!C3L25!//jf4cfls225.pdx.intel.com/apd_proj/ppg_lib/epg_masterlib/logical/mstr_discrete/cap/chips/chips.prt!CAP!CAP_0603-22.0UF,4V,20%,X6S,E15431-004!CAP!!!F2960!!SB_DECOUPLING!!
S!@baseboard_fab2_lib.baseboard_fab2(sch_1):page132_i8@mstr_discrete.cap(chips)!CAP_0603-22.0UF,4V,20%,X6S,E15A!C3N27!//jf4cfls225.pdx.intel.com/apd_proj/ppg_lib/epg_masterlib/logical/mstr_discrete/cap/chips/chips.prt!CAP!CAP_0603-22.0UF,4V,20%,X6S,E15431-004!CAP!!!F2951!!SB_DECOUPLING!!
S!@baseboard_fab2_lib.baseboard_fab2(sch_1):page130_i45@mstr_discrete.cap(chips)!CAP_0603-22.0UF,4V,20%,X6S,E15A!C2M2!//jf4cfls225.pdx.intel.com/apd_proj/ppg_lib/epg_masterlib/logical/mstr_discrete/cap/chips/chips.prt!CAP!CAP_0603-22.0UF,4V,20%,X6S,E15431-004!CAP!!!F2999!!SB_DECOUPLING!!
S!@baseboard_fab2_lib.baseboard_fab2(sch_1):page130_i39@mstr_discrete.cap(chips)!CAP_0603-22.0UF,4V,20%,X6S,E15A!C8B4!//jf4cfls225.pdx.intel.com/apd_proj/ppg_lib/epg_masterlib/logical/mstr_discrete/cap/chips/chips.prt!CAP!CAP_0603-22.0UF,4V,20%,X6S,E15431-004!CAP!!!F2782!!SB_DECOUPLING!!
S!@baseboard_fab2_lib.baseboard_fab2(sch_1):page130_i38@mstr_discrete.cap(chips)!CAP_0603-22.0UF,4V,20%,X6S,E15A!C7D3!//jf4cfls225.pdx.intel.com/apd_proj/ppg_lib/epg_masterlib/logical/mstr_discrete/cap/chips/chips.prt!CAP!CAP_0603-22.0UF,4V,20%,X6S,E15431-004!CAP!!!F2797!!SB_DECOUPLING!!
S!@baseboard_fab2_lib.baseboard_fab2(sch_1):page130_i43@mstr_discrete.cap(chips)!CAP_0603-22.0UF,4V,20%,X6S,E15A!C2M1!//jf4cfls225.pdx.intel.com/apd_proj/ppg_lib/epg_masterlib/logical/mstr_discrete/cap/chips/chips.prt!CAP!CAP_0603-22.0UF,4V,20%,X6S,E15431-004!CAP!!!F3000!!SB_DECOUPLING!!
S!@baseboard_fab2_lib.baseboard_fab2(sch_1):page130_i30@mstr_discrete.cap(chips)!CAP_0603-22.0UF,4V,20%,X6S,E15A!C8B2!//jf4cfls225.pdx.intel.com/apd_proj/ppg_lib/epg_masterlib/logical/mstr_discrete/cap/chips/chips.prt!CAP!CAP_0603-22.0UF,4V,20%,X6S,E15431-004!CAP!!!F2784!!SB_DECOUPLING!!
S!@baseboard_fab2_lib.baseboard_fab2(sch_1):page130_i41@mstr_discrete.cap(chips)!CAP_0603-22.0UF,4V,20%,X6S,E15A!C8B1!//jf4cfls225.pdx.intel.com/apd_proj/ppg_lib/epg_masterlib/logical/mstr_discrete/cap/chips/chips.prt!CAP!CAP_0603-22.0UF,4V,20%,X6S,E15431-004!CAP!!!F2785!!SB_DECOUPLING!!
S!@baseboard_fab2_lib.baseboard_fab2(sch_1):page131_i18@mstr_discrete.cap(chips)!CAP_0603-22.0UF,4V,20%,X6S,E15A!C7B17!//jf4cfls225.pdx.intel.com/apd_proj/ppg_lib/epg_masterlib/logical/mstr_discrete/cap/chips/chips.prt!CAP!CAP_0603-22.0UF,4V,20%,X6S,E15431-004!CAP!!!F2808!!SB_DECOUPLING!!
S!@baseboard_fab2_lib.baseboard_fab2(sch_1):page131_i6@mstr_discrete.cap(chips)!CAP_0603-22.0UF,4V,20%,X6S,E15A!C7B20!//jf4cfls225.pdx.intel.com/apd_proj/ppg_lib/epg_masterlib/logical/mstr_discrete/cap/chips/chips.prt!CAP!CAP_0603-22.0UF,4V,20%,X6S,E15431-004!CAP!!!F2805!!SB_DECOUPLING!!
S!@baseboard_fab2_lib.baseboard_fab2(sch_1):page131_i12@mstr_discrete.cap(chips)!CAP_0603-22.0UF,4V,20%,X6S,E15A!C7B18!//jf4cfls225.pdx.intel.com/apd_proj/ppg_lib/epg_masterlib/logical/mstr_discrete/cap/chips/chips.prt!CAP!CAP_0603-22.0UF,4V,20%,X6S,E15431-004!CAP!!!F2807!!SB_DECOUPLING!!
S!@baseboard_fab2_lib.baseboard_fab2(sch_1):page131_i4@mstr_discrete.cap(chips)!CAP_0603-22.0UF,4V,20%,X6S,E15A!C7B21!//jf4cfls225.pdx.intel.com/apd_proj/ppg_lib/epg_masterlib/logical/mstr_discrete/cap/chips/chips.prt!CAP!CAP_0603-22.0UF,4V,20%,X6S,E15431-004!CAP!!!F2804!!SB_DECOUPLING!!
S!@baseboard_fab2_lib.baseboard_fab2(sch_1):page131_i11@mstr_discrete.cap(chips)!CAP_0603-22.0UF,4V,20%,X6S,E15A!C7B24!//jf4cfls225.pdx.intel.com/apd_proj/ppg_lib/epg_masterlib/logical/mstr_discrete/cap/chips/chips.prt!CAP!CAP_0603-22.0UF,4V,20%,X6S,E15431-004!CAP!!!F2801!!SB_DECOUPLING!!
S!@baseboard_fab2_lib.baseboard_fab2(sch_1):page131_i3@mstr_discrete.cap(chips)!CAP_0603-22.0UF,4V,20%,X6S,E15A!C7B16!//jf4cfls225.pdx.intel.com/apd_proj/ppg_lib/epg_masterlib/logical/mstr_discrete/cap/chips/chips.prt!CAP!CAP_0603-22.0UF,4V,20%,X6S,E15431-004!CAP!!!F2809!!SB_DECOUPLING!!
S!@baseboard_fab2_lib.baseboard_fab2(sch_1):page131_i10@mstr_discrete.cap(chips)!CAP_0603-22.0UF,4V,20%,X6S,E15A!C7B22!//jf4cfls225.pdx.intel.com/apd_proj/ppg_lib/epg_masterlib/logical/mstr_discrete/cap/chips/chips.prt!CAP!CAP_0603-22.0UF,4V,20%,X6S,E15431-004!CAP!!!F2803!!SB_DECOUPLING!!
S!@baseboard_fab2_lib.baseboard_fab2(sch_1):page131_i2@mstr_discrete.cap(chips)!CAP_0603-22.0UF,4V,20%,X6S,E15A!C7B19!//jf4cfls225.pdx.intel.com/apd_proj/ppg_lib/epg_masterlib/logical/mstr_discrete/cap/chips/chips.prt!CAP!CAP_0603-22.0UF,4V,20%,X6S,E15431-004!CAP!!!F2806!!SB_DECOUPLING!!
S!@baseboard_fab2_lib.baseboard_fab2(sch_1):page131_i7@mstr_discrete.cap(chips)!CAP_0603-22.0UF,4V,20%,X6S,E15A!C7B23!//jf4cfls225.pdx.intel.com/apd_proj/ppg_lib/epg_masterlib/logical/mstr_discrete/cap/chips/chips.prt!CAP!CAP_0603-22.0UF,4V,20%,X6S,E15431-004!CAP!!!F2802!!SB_DECOUPLING!!
S!@baseboard_fab2_lib.baseboard_fab2(sch_1):page131_i1@mstr_discrete.cap(chips)!CAP_0603-22.0UF,4V,20%,X6S,E15A!C7B15!//jf4cfls225.pdx.intel.com/apd_proj/ppg_lib/epg_masterlib/logical/mstr_discrete/cap/chips/chips.prt!CAP!CAP_0603-22.0UF,4V,20%,X6S,E15431-004!CAP!!!F2810!!SB_DECOUPLING!!
S!@baseboard_fab2_lib.baseboard_fab2(sch_1):page131_i20@mstr_discrete.cap(chips)!CAP_0603-22.0UF,4V,20%,X6S,E15A!C8B13!//jf4cfls225.pdx.intel.com/apd_proj/ppg_lib/epg_masterlib/logical/mstr_discrete/cap/chips/chips.prt!CAP!CAP_0603-22.0UF,4V,20%,X6S,E15431-004!CAP!!!F2778!!SB_DECOUPLING!!
S!@baseboard_fab2_lib.baseboard_fab2(sch_1):page131_i16@mstr_discrete.cap(chips)!CAP_0603-22.0UF,4V,20%,X6S,E15A!C8B14!//jf4cfls225.pdx.intel.com/apd_proj/ppg_lib/epg_masterlib/logical/mstr_discrete/cap/chips/chips.prt!CAP!CAP_0603-22.0UF,4V,20%,X6S,E15431-004!CAP!!!F2777!!SB_DECOUPLING!!
S!@baseboard_fab2_lib.baseboard_fab2(sch_1):page131_i15@mstr_discrete.cap(chips)!CAP_0603-22.0UF,4V,20%,X6S,E15A!C8B11!//jf4cfls225.pdx.intel.com/apd_proj/ppg_lib/epg_masterlib/logical/mstr_discrete/cap/chips/chips.prt!CAP!CAP_0603-22.0UF,4V,20%,X6S,E15431-004!CAP!!!F2779!!SB_DECOUPLING!!
S!@baseboard_fab2_lib.baseboard_fab2(sch_1):page131_i14@mstr_discrete.cap(chips)!CAP_0603-22.0UF,4V,20%,X6S,E15A!C8B9!//jf4cfls225.pdx.intel.com/apd_proj/ppg_lib/epg_masterlib/logical/mstr_discrete/cap/chips/chips.prt!CAP!CAP_0603-22.0UF,4V,20%,X6S,E15431-004!CAP!!!F2781!!SB_DECOUPLING!!
S!@baseboard_fab2_lib.baseboard_fab2(sch_1):page131_i8@mstr_discrete.cap(chips)!CAP_0603-22.0UF,4V,20%,X6S,E15A!C8B10!//jf4cfls225.pdx.intel.com/apd_proj/ppg_lib/epg_masterlib/logical/mstr_discrete/cap/chips/chips.prt!CAP!CAP_0603-22.0UF,4V,20%,X6S,E15431-004!CAP!!!F2780!!SB_DECOUPLING!!
S!@baseboard_fab2_lib.baseboard_fab2(sch_1):page130_i32@mstr_discrete.cap(chips)!CAP_0603-22.0UF,4V,20%,X6S,E15A!C8B3!//jf4cfls225.pdx.intel.com/apd_proj/ppg_lib/epg_masterlib/logical/mstr_discrete/cap/chips/chips.prt!CAP!CAP_0603-22.0UF,4V,20%,X6S,E15431-004!CAP!!!F2783!!SB_DECOUPLING!!
S!@baseboard_fab2_lib.baseboard_fab2(sch_1):page131_i52@mstr_discrete.cap(chips)!CAP_0603-22.0UF,4V,20%,X6S,E15A!C2M12!//jf4cfls225.pdx.intel.com/apd_proj/ppg_lib/epg_masterlib/logical/mstr_discrete/cap/chips/chips.prt!CAP!CAP_0603-22.0UF,4V,20%,X6S,E15431-004!CAP!!!F2998!!SB_DECOUPLING!!
S!@baseboard_fab2_lib.baseboard_fab2(sch_1):page131_i50@mstr_discrete.cap(chips)!CAP_0603-22.0UF,4V,20%,X6S,E15A!C2N10!//jf4cfls225.pdx.intel.com/apd_proj/ppg_lib/epg_masterlib/logical/mstr_discrete/cap/chips/chips.prt!CAP!CAP_0603-22.0UF,4V,20%,X6S,E15431-004!CAP!!!F2996!!SB_DECOUPLING!!
S!@baseboard_fab2_lib.baseboard_fab2(sch_1):page131_i48@mstr_discrete.cap(chips)!CAP_0603-22.0UF,4V,20%,X6S,E15A!C2M13!//jf4cfls225.pdx.intel.com/apd_proj/ppg_lib/epg_masterlib/logical/mstr_discrete/cap/chips/chips.prt!CAP!CAP_0603-22.0UF,4V,20%,X6S,E15431-004!CAP!!!F2997!!SB_DECOUPLING!!
S!@baseboard_fab2_lib.baseboard_fab2(sch_1):page55_i140@mstr_discrete.res(chips)!RES_0402-90.9,1%,1/16W,CHIP,G2A!R7P17!//jf4cfls225.pdx.intel.com/apd_proj/ppg_lib/epg_masterlib/logical/mstr_discrete/res/chips/chips.prt!RES!RES_0402-90.9,1%,1/16W,CHIP,G21796-365!RES!!!F284!!CPU1!!
S!@baseboard_fab2_lib.baseboard_fab2(sch_1):page21_i181@mstr_discrete.res(chips)!RES_0402-90.9,1%,1/16W,CHIP,G2A!R4P10!//jf4cfls225.pdx.intel.com/apd_proj/ppg_lib/epg_masterlib/logical/mstr_discrete/res/chips/chips.prt!RES!RES_0402-90.9,1%,1/16W,CHIP,G21796-365!RES!!!F288!!CPU0!!
S!@baseboard_fab2_lib.baseboard_fab2(sch_1):page21_i180@mstr_discrete.res(chips)!RES_0402-90.9,1%,1/16W,CHIP,G2A!R4P8!//jf4cfls225.pdx.intel.com/apd_proj/ppg_lib/epg_masterlib/logical/mstr_discrete/res/chips/chips.prt!RES!RES_0402-90.9,1%,1/16W,CHIP,G21796-365!RES!!!F289!!CPU0!!
S!@baseboard_fab2_lib.baseboard_fab2(sch_1):page21_i178@mstr_discrete.res(chips)!RES_0402-90.9,1%,1/16W,CHIP,G2A!R5D2!//jf4cfls225.pdx.intel.com/apd_proj/ppg_lib/epg_masterlib/logical/mstr_discrete/res/chips/chips.prt!RES!RES_0402-90.9,1%,1/16W,CHIP,G21796-365!RES!!!F286!!CPU0!!
S!@baseboard_fab2_lib.baseboard_fab2(sch_1):page21_i177@mstr_discrete.res(chips)!RES_0402-90.9,1%,1/16W,CHIP,G2A!R5D1!//jf4cfls225.pdx.intel.com/apd_proj/ppg_lib/epg_masterlib/logical/mstr_discrete/res/chips/chips.prt!RES!RES_0402-90.9,1%,1/16W,CHIP,G21796-365!RES!!!F287!!CPU0!!
S!@baseboard_fab2_lib.baseboard_fab2(sch_1):page55_i119@mstr_discrete.res(chips)!RES_0402-90.9,1%,1/16W,CHIP,G2A!R7P16!//jf4cfls225.pdx.intel.com/apd_proj/ppg_lib/epg_masterlib/logical/mstr_discrete/res/chips/chips.prt!RES!RES_0402-90.9,1%,1/16W,CHIP,G21796-365!RES!!!F285!!CPU1!!
S!@baseboard_fab2_lib.baseboard_fab2(sch_1):page55_i117@mstr_discrete.res(chips)!RES_0402-90.9,1%,1/16W,CHIP,G2A!R3D2!//jf4cfls225.pdx.intel.com/apd_proj/ppg_lib/epg_masterlib/logical/mstr_discrete/res/chips/chips.prt!RES!RES_0402-90.9,1%,1/16W,CHIP,G21796-365!RES!!!F290!!CPU1!!
S!@baseboard_fab2_lib.baseboard_fab2(sch_1):page55_i116@mstr_discrete.res(chips)!RES_0402-90.9,1%,1/16W,CHIP,G2A!R3D1!//jf4cfls225.pdx.intel.com/apd_proj/ppg_lib/epg_masterlib/logical/mstr_discrete/res/chips/chips.prt!RES!RES_0402-90.9,1%,1/16W,CHIP,G21796-365!RES!!!F291!!CPU1!!
S!@baseboard_fab2_lib.baseboard_fab2(sch_1):page169_i126@mstr_discrete.res(chips)!RES_0402-200.0K,1%,1/16W,CHIP,A!R1U50!//jf4cfls225.pdx.intel.com/apd_proj/ppg_lib/epg_masterlib/logical/mstr_discrete/res/chips/chips.prt!RES!RES_0402-200.0K,1%,1/16W,CHIP,G21796-080!RES!!!F889!!BMC_VOLT_MONITOR!!
S!@baseboard_fab2_lib.baseboard_fab2(sch_1):page147_i75@mstr_discrete.cap(chips)!CAP_0402-0.1UF,16V,10%,EMPTY,AA!C9G8!//jf4cfls225.pdx.intel.com/apd_proj/ppg_lib/epg_masterlib/logical/mstr_discrete/cap/chips/chips.prt!CAP!CAP_0402-0.1UF,16V,10%,EMPTY,A36096-030!CAP_0402!!!F4085!!BMC!!
S!@baseboard_fab2_lib.baseboard_fab2(sch_1):page147_i79@mstr_discrete.cap(chips)!CAP_0402-0.1UF,16V,10%,EMPTY,AA!C9G10!//jf4cfls225.pdx.intel.com/apd_proj/ppg_lib/epg_masterlib/logical/mstr_discrete/cap/chips/chips.prt!CAP!CAP_0402-0.1UF,16V,10%,EMPTY,A36096-030!CAP_0402!!!F4084!!BMC!!
S!@baseboard_fab2_lib.baseboard_fab2(sch_1):page147_i76@mstr_discrete.cap(chips)!CAP_0402-0.1UF,16V,10%,EMPTY,AA!C9G11!//jf4cfls225.pdx.intel.com/apd_proj/ppg_lib/epg_masterlib/logical/mstr_discrete/cap/chips/chips.prt!CAP!CAP_0402-0.1UF,16V,10%,EMPTY,A36096-030!CAP_0402!!!F4083!!BMC!!
S!@baseboard_fab2_lib.baseboard_fab2(sch_1):page95_i119@mstr_discrete.fet_n(chips)!FET_N_SOT23-2N7002,FET,C79254-A!Q7E8!//jf4cfls225.pdx.intel.com/apd_proj/ppg_lib/epg_masterlib/logical/mstr_discrete/fet_n/chips/chips.prt!FET_N!FET_N_SOT23-2N7002,FET,C79254-001!FET_N!!!F2142!!PROC_SIDEBAND!!
S!@baseboard_fab2_lib.baseboard_fab2(sch_1):page196_i124@mstr_discrete.fet_n(chips)!FET_N_SOT23-2N7002,FET,C79254-A!Q2P2!//jf4cfls225.pdx.intel.com/apd_proj/ppg_lib/epg_masterlib/logical/mstr_discrete/fet_n/chips/chips.prt!FET_N!FET_N_SOT23-2N7002,FET,C79254-001!FET_N!!!F2143!!V_SUPER!!
S!@baseboard_fab2_lib.baseboard_fab2(sch_1):page135_i100@mstr_discrete.fet_n(chips)!FET_N_SOT23-2N7002,FET,C79254-A!Q8D2!//jf4cfls225.pdx.intel.com/apd_proj/ppg_lib/epg_masterlib/logical/mstr_discrete/fet_n/chips/chips.prt!FET_N!FET_N_SOT23-2N7002,FET,C79254-001!FET_N!!!F2144!!THERMTRIP_PCH!!
S!@baseboard_fab2_lib.baseboard_fab2(sch_1):page95_i104@mstr_discrete.fet_n(chips)!FET_N_SOT23-2N7002,FET,C79254-A!Q7E4!//jf4cfls225.pdx.intel.com/apd_proj/ppg_lib/epg_masterlib/logical/mstr_discrete/fet_n/chips/chips.prt!FET_N!FET_N_SOT23-2N7002,FET,C79254-001!FET_N!!!F2139!!PROC_SIDEBAND!!
S!@baseboard_fab2_lib.baseboard_fab2(sch_1):page89_i18@mstr_discrete.fet_n(chips)!FET_N_SOT23-2N7002,FET,C79254-A!Q6F1!//jf4cfls225.pdx.intel.com/apd_proj/ppg_lib/epg_masterlib/logical/mstr_discrete/fet_n/chips/chips.prt!FET_N!FET_N_SOT23-2N7002,FET,C79254-001!FET_N!!!F2141!!NVDIMM!!
S!@baseboard_fab2_lib.baseboard_fab2(sch_1):page135_i76@mstr_discrete.fet_n(chips)!FET_N_SOT23-2N7002,FET,C79254-A!Q7D1!//jf4cfls225.pdx.intel.com/apd_proj/ppg_lib/epg_masterlib/logical/mstr_discrete/fet_n/chips/chips.prt!FET_N!FET_N_SOT23-2N7002,FET,C79254-001!FET_N!!!F2140!!THERMTRIP_PCH!!
S!@baseboard_fab2_lib.baseboard_fab2(sch_1):page167_i49@mstr_memory.at24c64(chips)!AT24C64_SOICLF-IC,C47049-001-GA!U8D4!//jf4cfls225.pdx.intel.com/apd_proj/ppg_lib/epg_masterlib/logical/mstr_memory/at24c64/chips/chips.prt!AT24C64!AT24C64_SOICLF-IC,C47049-001!AT24C64!!!F4186!!TEMP_SENSORS!!
S!@baseboard_fab2_lib.baseboard_fab2(sch_1):page167_i7@mstr_discrete.cap(chips)!CAP_0402LF-47.0PF,50V,5%,EMPTYA!C1M4!//jf4cfls225.pdx.intel.com/apd_proj/ppg_lib/epg_masterlib/logical/mstr_discrete/cap/chips/chips.prt!CAP!CAP_0402LF-47.0PF,50V,5%,EMPTY,A36095-025!CAP!!!F3104!!TEMP_SENSORS!!
S!@baseboard_fab2_lib.baseboard_fab2(sch_1):page167_i24@mstr_discrete.cap(chips)!CAP_0402LF-47.0PF,50V,5%,EMPTYA!C1E19!//jf4cfls225.pdx.intel.com/apd_proj/ppg_lib/epg_masterlib/logical/mstr_discrete/cap/chips/chips.prt!CAP!CAP_0402LF-47.0PF,50V,5%,EMPTY,A36095-025!CAP!!!F3105!!TEMP_SENSORS!!
S!@baseboard_fab2_lib.baseboard_fab2(sch_1):page127_i71@mstr_discrete.inductor(chips)!INDUCTOR_SMT-0.022UH,IND,72189A!L2M1!//jf4cfls225.pdx.intel.com/apd_proj/ppg_lib/epg_masterlib/logical/mstr_discrete/inductor/chips/chips.prt!INDUCTOR!INDUCTOR_SMT-0.022UH,IND,721891-082!INDUCTOR!!!F2081!!SB_FILTER_KR_PLL!!
S!@baseboard_fab2_lib.baseboard_fab2(sch_1):page167_i3@mstr_discrete.pnp(chips)!PNP_TO92-MPS2907,IC,G73554-001!Q9B1!//jf4cfls225.pdx.intel.com/apd_proj/ppg_lib/epg_masterlib/logical/mstr_discrete/pnp/chips/chips.prt!PNP!PNP_TO92-MPS2907,IC,G73554-001!PNP!!!F1977!!TEMP_SENSORS!!
S!@baseboard_fab2_lib.baseboard_fab2(sch_1):page167_i27@mstr_discrete.pnp(chips)!PNP_TO92-MPS2907,IC,G73554-001!Q1E1!//jf4cfls225.pdx.intel.com/apd_proj/ppg_lib/epg_masterlib/logical/mstr_discrete/pnp/chips/chips.prt!PNP!PNP_TO92-MPS2907,IC,G73554-001!PNP!!!F1978!!TEMP_SENSORS!!
S!@baseboard_fab2_lib.baseboard_fab2(sch_1):page167_i1@mstr_analog.tmp421(chips)!TMP421_TSSOP-IC,G62962-001!U9B4!//jf4cfls225.pdx.intel.com/apd_proj/ppg_lib/epg_masterlib/logical/mstr_analog/tmp421/chips/chips.prt!TMP421!TMP421_TSSOP-IC,G62962-001!TMP421_TSSOP!!!F61!!TEMP_SENSORS!!
S!@baseboard_fab2_lib.baseboard_fab2(sch_1):page167_i30@mstr_analog.tmp421(chips)!TMP421_TSSOP-IC,G62962-001!U1E1!//jf4cfls225.pdx.intel.com/apd_proj/ppg_lib/epg_masterlib/logical/mstr_analog/tmp421/chips/chips.prt!TMP421!TMP421_TSSOP-IC,G62962-001!TMP421_TSSOP!!!F62!!TEMP_SENSORS!!
S!@baseboard_fab2_lib.baseboard_fab2(sch_1):page238_i39@mstr_discrete.cap(chips)!CAP_0402-1.0UF,16V,10%,X6S,D97A!C9E11!//jf4cfls225.pdx.intel.com/apd_proj/ppg_lib/epg_masterlib/logical/mstr_discrete/cap/chips/chips.prt!CAP!CAP_0402-1.0UF,16V,10%,X6S,D97712-011!CAP_0402!!!F3759!!!!
S!@baseboard_fab2_lib.baseboard_fab2(sch_1):page199_i119@mstr_discrete.cap(chips)!CAP_0402-1.0UF,16V,10%,X6S,D97A!C1D19!//jf4cfls225.pdx.intel.com/apd_proj/ppg_lib/epg_masterlib/logical/mstr_discrete/cap/chips/chips.prt!CAP!CAP_0402-1.0UF,16V,10%,X6S,D97712-011!CAP_0402!!!F3817!!HOT_SWAP!!
S!@baseboard_fab2_lib.baseboard_fab2(sch_1):page202_i34@mstr_discrete.cap(chips)!CAP_0402-1.0UF,16V,10%,X6S,D97A!C4E10!//jf4cfls225.pdx.intel.com/apd_proj/ppg_lib/epg_masterlib/logical/mstr_discrete/cap/chips/chips.prt!CAP!CAP_0402-1.0UF,16V,10%,X6S,D97712-011!CAP_0402!!!F3786!!PVCCIN_CPU0_PWR_VR!!
S!@baseboard_fab2_lib.baseboard_fab2(sch_1):page212_i39@mstr_discrete.cap(chips)!CAP_0402-1.0UF,16V,10%,X6S,D97A!C7C12!//jf4cfls225.pdx.intel.com/apd_proj/ppg_lib/epg_masterlib/logical/mstr_discrete/cap/chips/chips.prt!CAP!CAP_0402-1.0UF,16V,10%,X6S,D97712-011!CAP_0402!!!F3768!!PVCCIO_CPU0!!
S!@baseboard_fab2_lib.baseboard_fab2(sch_1):page212_i36@mstr_discrete.cap(chips)!CAP_0402-1.0UF,16V,10%,X6S,D97A!C7C17!//jf4cfls225.pdx.intel.com/apd_proj/ppg_lib/epg_masterlib/logical/mstr_discrete/cap/chips/chips.prt!CAP!CAP_0402-1.0UF,16V,10%,X6S,D97712-011!CAP_0402!!!F3767!!PVCCIO_CPU0!!
S!@baseboard_fab2_lib.baseboard_fab2(sch_1):page231_i161@mstr_discrete.cap(chips)!CAP_0402-1.0UF,16V,10%,X6S,D97A!C3T10!//jf4cfls225.pdx.intel.com/apd_proj/ppg_lib/epg_masterlib/logical/mstr_discrete/cap/chips/chips.prt!CAP!CAP_0402-1.0UF,16V,10%,X6S,D97712-011!CAP_0402!!!F3801!!PVPP_KLM_VR!!
S!@baseboard_fab2_lib.baseboard_fab2(sch_1):page240_i139@mstr_discrete.cap(chips)!CAP_0402-1.0UF,16V,10%,X6S,D97A!C8E14!//jf4cfls225.pdx.intel.com/apd_proj/ppg_lib/epg_masterlib/logical/mstr_discrete/cap/chips/chips.prt!CAP!CAP_0402-1.0UF,16V,10%,X6S,D97712-011!CAP_0402!!!F3760!!P3V3_STBY_VR!!
S!@baseboard_fab2_lib.baseboard_fab2(sch_1):page232_i207@mstr_discrete.cap(chips)!CAP_0402-1.0UF,16V,10%,X6S,D97A!C3M9!//jf4cfls225.pdx.intel.com/apd_proj/ppg_lib/epg_masterlib/logical/mstr_discrete/cap/chips/chips.prt!CAP!CAP_0402-1.0UF,16V,10%,X6S,D97712-011!CAP_0402!!!F3803!!PVPP_KLM_VR!!
S!@baseboard_fab2_lib.baseboard_fab2(sch_1):page233_i196@mstr_discrete.cap(chips)!CAP_0402-1.0UF,16V,10%,X6S,D97A!C4G4!//jf4cfls225.pdx.intel.com/apd_proj/ppg_lib/epg_masterlib/logical/mstr_discrete/cap/chips/chips.prt!CAP!CAP_0402-1.0UF,16V,10%,X6S,D97712-011!CAP_0402!!!F3782!!PVPP_KLM_VR!!
S!@baseboard_fab2_lib.baseboard_fab2(sch_1):page234_i152@mstr_discrete.cap(chips)!CAP_0402-1.0UF,16V,10%,X6S,D97A!C6L11!//jf4cfls225.pdx.intel.com/apd_proj/ppg_lib/epg_masterlib/logical/mstr_discrete/cap/chips/chips.prt!CAP!CAP_0402-1.0UF,16V,10%,X6S,D97712-011!CAP_0402!!!F3777!!PVPP_KLM_VR!!
S!@baseboard_fab2_lib.baseboard_fab2(sch_1):page205_i20@mstr_discrete.cap(chips)!CAP_0402-1.0UF,16V,10%,X6S,D97A!C4C6!//jf4cfls225.pdx.intel.com/apd_proj/ppg_lib/epg_masterlib/logical/mstr_discrete/cap/chips/chips.prt!CAP!CAP_0402-1.0UF,16V,10%,X6S,D97712-011!CAP_0402!!!F3796!!PVSA_CPU0_PWR_VR!!
S!@baseboard_fab2_lib.baseboard_fab2(sch_1):page202_i47@mstr_discrete.cap(chips)!CAP_0402-1.0UF,16V,10%,X6S,D97A!C4D48!//jf4cfls225.pdx.intel.com/apd_proj/ppg_lib/epg_masterlib/logical/mstr_discrete/cap/chips/chips.prt!CAP!CAP_0402-1.0UF,16V,10%,X6S,D97712-011!CAP_0402!!!F3787!!PVCCIN_CPU0_PWR_VR!!
S!@baseboard_fab2_lib.baseboard_fab2(sch_1):page202_i36@mstr_discrete.cap(chips)!CAP_0402-1.0UF,16V,10%,X6S,D97A!C4E19!//jf4cfls225.pdx.intel.com/apd_proj/ppg_lib/epg_masterlib/logical/mstr_discrete/cap/chips/chips.prt!CAP!CAP_0402-1.0UF,16V,10%,X6S,D97712-011!CAP_0402!!!F3784!!PVCCIN_CPU0_PWR_VR!!
S!@baseboard_fab2_lib.baseboard_fab2(sch_1):page202_i45@mstr_discrete.cap(chips)!CAP_0402-1.0UF,16V,10%,X6S,D97A!C4E26!//jf4cfls225.pdx.intel.com/apd_proj/ppg_lib/epg_masterlib/logical/mstr_discrete/cap/chips/chips.prt!CAP!CAP_0402-1.0UF,16V,10%,X6S,D97712-011!CAP_0402!!!F3788!!PVCCIN_CPU0_PWR_VR!!
S!@baseboard_fab2_lib.baseboard_fab2(sch_1):page203_i47@mstr_discrete.cap(chips)!CAP_0402-1.0UF,16V,10%,X6S,D97A!C4D30!//jf4cfls225.pdx.intel.com/apd_proj/ppg_lib/epg_masterlib/logical/mstr_discrete/cap/chips/chips.prt!CAP!CAP_0402-1.0UF,16V,10%,X6S,D97712-011!CAP_0402!!!F3789!!PVCCIN_CPU0_PWR_VR!!
S!@baseboard_fab2_lib.baseboard_fab2(sch_1):page203_i53@mstr_discrete.cap(chips)!CAP_0402-1.0UF,16V,10%,X6S,D97A!C4D10!//jf4cfls225.pdx.intel.com/apd_proj/ppg_lib/epg_masterlib/logical/mstr_discrete/cap/chips/chips.prt!CAP!CAP_0402-1.0UF,16V,10%,X6S,D97712-011!CAP_0402!!!F3791!!PVCCIN_CPU0_PWR_VR!!
S!@baseboard_fab2_lib.baseboard_fab2(sch_1):page203_i45@mstr_discrete.cap(chips)!CAP_0402-1.0UF,16V,10%,X6S,D97A!C4D16!//jf4cfls225.pdx.intel.com/apd_proj/ppg_lib/epg_masterlib/logical/mstr_discrete/cap/chips/chips.prt!CAP!CAP_0402-1.0UF,16V,10%,X6S,D97712-011!CAP_0402!!!F3790!!PVCCIN_CPU0_PWR_VR!!
S!@baseboard_fab2_lib.baseboard_fab2(sch_1):page203_i51@mstr_discrete.cap(chips)!CAP_0402-1.0UF,16V,10%,X6S,D97A!C4D7!//jf4cfls225.pdx.intel.com/apd_proj/ppg_lib/epg_masterlib/logical/mstr_discrete/cap/chips/chips.prt!CAP!CAP_0402-1.0UF,16V,10%,X6S,D97712-011!CAP_0402!!!F3792!!PVCCIN_CPU0_PWR_VR!!
S!@baseboard_fab2_lib.baseboard_fab2(sch_1):page204_i34@mstr_discrete.cap(chips)!CAP_0402-1.0UF,16V,10%,X6S,D97A!C4D46!//jf4cfls225.pdx.intel.com/apd_proj/ppg_lib/epg_masterlib/logical/mstr_discrete/cap/chips/chips.prt!CAP!CAP_0402-1.0UF,16V,10%,X6S,D97712-011!CAP_0402!!!F3794!!PVCCIN_CPU0_PWR_VR!!
S!@baseboard_fab2_lib.baseboard_fab2(sch_1):page216_i48@mstr_discrete.cap(chips)!CAP_0402-1.0UF,16V,10%,X6S,D97A!C7G37!//jf4cfls225.pdx.intel.com/apd_proj/ppg_lib/epg_masterlib/logical/mstr_discrete/cap/chips/chips.prt!CAP!CAP_0402-1.0UF,16V,10%,X6S,D97712-011!CAP_0402!!!F3762!!VDDQ_ABC_PWR_VR!!
S!@baseboard_fab2_lib.baseboard_fab2(sch_1):page216_i79@mstr_discrete.cap(chips)!CAP_0402-1.0UF,16V,10%,X6S,D97A!C7G30!//jf4cfls225.pdx.intel.com/apd_proj/ppg_lib/epg_masterlib/logical/mstr_discrete/cap/chips/chips.prt!CAP!CAP_0402-1.0UF,16V,10%,X6S,D97712-011!CAP_0402!!!F3764!!VDDQ_ABC_PWR_VR!!
S!@baseboard_fab2_lib.baseboard_fab2(sch_1):page216_i50@mstr_discrete.cap(chips)!CAP_0402-1.0UF,16V,10%,X6S,D97A!C7G33!//jf4cfls225.pdx.intel.com/apd_proj/ppg_lib/epg_masterlib/logical/mstr_discrete/cap/chips/chips.prt!CAP!CAP_0402-1.0UF,16V,10%,X6S,D97712-011!CAP_0402!!!F3763!!VDDQ_ABC_PWR_VR!!
S!@baseboard_fab2_lib.baseboard_fab2(sch_1):page205_i32@mstr_discrete.cap(chips)!CAP_0402-1.0UF,16V,10%,X6S,D97A!C4C9!//jf4cfls225.pdx.intel.com/apd_proj/ppg_lib/epg_masterlib/logical/mstr_discrete/cap/chips/chips.prt!CAP!CAP_0402-1.0UF,16V,10%,X6S,D97712-011!CAP_0402!!!F3795!!PVSA_CPU0_PWR_VR!!
S!@baseboard_fab2_lib.baseboard_fab2(sch_1):page216_i77@mstr_discrete.cap(chips)!CAP_0402-1.0UF,16V,10%,X6S,D97A!C7G40!//jf4cfls225.pdx.intel.com/apd_proj/ppg_lib/epg_masterlib/logical/mstr_discrete/cap/chips/chips.prt!CAP!CAP_0402-1.0UF,16V,10%,X6S,D97712-011!CAP_0402!!!F3761!!VDDQ_ABC_PWR_VR!!
S!@baseboard_fab2_lib.baseboard_fab2(sch_1):page219_i79@mstr_discrete.cap(chips)!CAP_0402-1.0UF,16V,10%,X6S,D97A!C7A21!//jf4cfls225.pdx.intel.com/apd_proj/ppg_lib/epg_masterlib/logical/mstr_discrete/cap/chips/chips.prt!CAP!CAP_0402-1.0UF,16V,10%,X6S,D97712-011!CAP_0402!!!F3770!!VDDQ_DEF_PWR_VR!!
S!@baseboard_fab2_lib.baseboard_fab2(sch_1):page219_i50@mstr_discrete.cap(chips)!CAP_0402-1.0UF,16V,10%,X6S,D97A!C7A16!//jf4cfls225.pdx.intel.com/apd_proj/ppg_lib/epg_masterlib/logical/mstr_discrete/cap/chips/chips.prt!CAP!CAP_0402-1.0UF,16V,10%,X6S,D97712-011!CAP_0402!!!F3771!!VDDQ_DEF_PWR_VR!!
S!@baseboard_fab2_lib.baseboard_fab2(sch_1):page219_i77@mstr_discrete.cap(chips)!CAP_0402-1.0UF,16V,10%,X6S,D97A!C7A24!//jf4cfls225.pdx.intel.com/apd_proj/ppg_lib/epg_masterlib/logical/mstr_discrete/cap/chips/chips.prt!CAP!CAP_0402-1.0UF,16V,10%,X6S,D97712-011!CAP_0402!!!F3769!!VDDQ_DEF_PWR_VR!!
S!@baseboard_fab2_lib.baseboard_fab2(sch_1):page227_i48@mstr_discrete.cap(chips)!CAP_0402-1.0UF,16V,10%,X6S,D97A!C1A19!//jf4cfls225.pdx.intel.com/apd_proj/ppg_lib/epg_masterlib/logical/mstr_discrete/cap/chips/chips.prt!CAP!CAP_0402-1.0UF,16V,10%,X6S,D97712-011!CAP_0402!!!F3825!!VDDQ_KLM_PWR_VR!!
S!@baseboard_fab2_lib.baseboard_fab2(sch_1):page227_i79@mstr_discrete.cap(chips)!CAP_0402-1.0UF,16V,10%,X6S,D97A!C1A9!//jf4cfls225.pdx.intel.com/apd_proj/ppg_lib/epg_masterlib/logical/mstr_discrete/cap/chips/chips.prt!CAP!CAP_0402-1.0UF,16V,10%,X6S,D97712-011!CAP_0402!!!F3827!!VDDQ_KLM_PWR_VR!!
S!@baseboard_fab2_lib.baseboard_fab2(sch_1):page227_i50@mstr_discrete.cap(chips)!CAP_0402-1.0UF,16V,10%,X6S,D97A!C1B20!//jf4cfls225.pdx.intel.com/apd_proj/ppg_lib/epg_masterlib/logical/mstr_discrete/cap/chips/chips.prt!CAP!CAP_0402-1.0UF,16V,10%,X6S,D97712-011!CAP_0402!!!F3826!!VDDQ_KLM_PWR_VR!!
S!@baseboard_fab2_lib.baseboard_fab2(sch_1):page224_i48@mstr_discrete.cap(chips)!CAP_0402-1.0UF,16V,10%,X6S,D97A!C1F27!//jf4cfls225.pdx.intel.com/apd_proj/ppg_lib/epg_masterlib/logical/mstr_discrete/cap/chips/chips.prt!CAP!CAP_0402-1.0UF,16V,10%,X6S,D97712-011!CAP_0402!!!F3809!!VDDQ_GHJ_PWR_VR!!
S!@baseboard_fab2_lib.baseboard_fab2(sch_1):page224_i79@mstr_discrete.cap(chips)!CAP_0402-1.0UF,16V,10%,X6S,D97A!C1G13!//jf4cfls225.pdx.intel.com/apd_proj/ppg_lib/epg_masterlib/logical/mstr_discrete/cap/chips/chips.prt!CAP!CAP_0402-1.0UF,16V,10%,X6S,D97712-011!CAP_0402!!!F3807!!VDDQ_GHJ_PWR_VR!!
S!@baseboard_fab2_lib.baseboard_fab2(sch_1):page224_i50@mstr_discrete.cap(chips)!CAP_0402-1.0UF,16V,10%,X6S,D97A!C1G6!//jf4cfls225.pdx.intel.com/apd_proj/ppg_lib/epg_masterlib/logical/mstr_discrete/cap/chips/chips.prt!CAP!CAP_0402-1.0UF,16V,10%,X6S,D97712-011!CAP_0402!!!F3808!!VDDQ_GHJ_PWR_VR!!
S!@baseboard_fab2_lib.baseboard_fab2(sch_1):page224_i77@mstr_discrete.cap(chips)!CAP_0402-1.0UF,16V,10%,X6S,D97A!C1G28!//jf4cfls225.pdx.intel.com/apd_proj/ppg_lib/epg_masterlib/logical/mstr_discrete/cap/chips/chips.prt!CAP!CAP_0402-1.0UF,16V,10%,X6S,D97712-011!CAP_0402!!!F3810!!VDDQ_GHJ_PWR_VR!!
S!@baseboard_fab2_lib.baseboard_fab2(sch_1):page207_i32@mstr_discrete.cap(chips)!CAP_0402-1.0UF,16V,10%,X6S,D97A!C1E8!//jf4cfls225.pdx.intel.com/apd_proj/ppg_lib/epg_masterlib/logical/mstr_discrete/cap/chips/chips.prt!CAP!CAP_0402-1.0UF,16V,10%,X6S,D97712-011!CAP_0402!!!F3812!!PVCCIN_CPU1_PWR_VR!!
S!@baseboard_fab2_lib.baseboard_fab2(sch_1):page207_i40@mstr_discrete.cap(chips)!CAP_0402-1.0UF,16V,10%,X6S,D97A!C1E24!//jf4cfls225.pdx.intel.com/apd_proj/ppg_lib/epg_masterlib/logical/mstr_discrete/cap/chips/chips.prt!CAP!CAP_0402-1.0UF,16V,10%,X6S,D97712-011!CAP_0402!!!F3814!!PVCCIN_CPU1_PWR_VR!!
S!@baseboard_fab2_lib.baseboard_fab2(sch_1):page207_i42@mstr_discrete.cap(chips)!CAP_0402-1.0UF,16V,10%,X6S,D97A!C1D35!//jf4cfls225.pdx.intel.com/apd_proj/ppg_lib/epg_masterlib/logical/mstr_discrete/cap/chips/chips.prt!CAP!CAP_0402-1.0UF,16V,10%,X6S,D97712-011!CAP_0402!!!F3813!!PVCCIN_CPU1_PWR_VR!!
S!@baseboard_fab2_lib.baseboard_fab2(sch_1):page207_i34@mstr_discrete.cap(chips)!CAP_0402-1.0UF,16V,10%,X6S,D97A!C1E13!//jf4cfls225.pdx.intel.com/apd_proj/ppg_lib/epg_masterlib/logical/mstr_discrete/cap/chips/chips.prt!CAP!CAP_0402-1.0UF,16V,10%,X6S,D97712-011!CAP_0402!!!F3811!!PVCCIN_CPU1_PWR_VR!!
S!@baseboard_fab2_lib.baseboard_fab2(sch_1):page208_i45@mstr_discrete.cap(chips)!CAP_0402-1.0UF,16V,10%,X6S,D97A!C1D23!//jf4cfls225.pdx.intel.com/apd_proj/ppg_lib/epg_masterlib/logical/mstr_discrete/cap/chips/chips.prt!CAP!CAP_0402-1.0UF,16V,10%,X6S,D97712-011!CAP_0402!!!F3816!!PVCCIN_CPU1_PWR_VR!!
S!@baseboard_fab2_lib.baseboard_fab2(sch_1):page208_i52@mstr_discrete.cap(chips)!CAP_0402-1.0UF,16V,10%,X6S,D97A!C1D12!//jf4cfls225.pdx.intel.com/apd_proj/ppg_lib/epg_masterlib/logical/mstr_discrete/cap/chips/chips.prt!CAP!CAP_0402-1.0UF,16V,10%,X6S,D97712-011!CAP_0402!!!F3819!!PVCCIN_CPU1_PWR_VR!!
S!@baseboard_fab2_lib.baseboard_fab2(sch_1):page208_i43@mstr_discrete.cap(chips)!CAP_0402-1.0UF,16V,10%,X6S,D97A!C1D17!//jf4cfls225.pdx.intel.com/apd_proj/ppg_lib/epg_masterlib/logical/mstr_discrete/cap/chips/chips.prt!CAP!CAP_0402-1.0UF,16V,10%,X6S,D97712-011!CAP_0402!!!F3818!!PVCCIN_CPU1_PWR_VR!!
S!@baseboard_fab2_lib.baseboard_fab2(sch_1):page208_i50@mstr_discrete.cap(chips)!CAP_0402-1.0UF,16V,10%,X6S,D97A!C1D7!//jf4cfls225.pdx.intel.com/apd_proj/ppg_lib/epg_masterlib/logical/mstr_discrete/cap/chips/chips.prt!CAP!CAP_0402-1.0UF,16V,10%,X6S,D97712-011!CAP_0402!!!F3820!!PVCCIN_CPU1_PWR_VR!!
S!@baseboard_fab2_lib.baseboard_fab2(sch_1):page210_i28@mstr_discrete.cap(chips)!CAP_0402-1.0UF,16V,10%,X6S,D97A!C1C15!//jf4cfls225.pdx.intel.com/apd_proj/ppg_lib/epg_masterlib/logical/mstr_discrete/cap/chips/chips.prt!CAP!CAP_0402-1.0UF,16V,10%,X6S,D97712-011!CAP_0402!!!F3823!!PVSA_CPU1_PWR_VR!!
S!@baseboard_fab2_lib.baseboard_fab2(sch_1):page210_i26@mstr_discrete.cap(chips)!CAP_0402-1.0UF,16V,10%,X6S,D97A!C1C5!//jf4cfls225.pdx.intel.com/apd_proj/ppg_lib/epg_masterlib/logical/mstr_discrete/cap/chips/chips.prt!CAP!CAP_0402-1.0UF,16V,10%,X6S,D97712-011!CAP_0402!!!F3824!!PVSA_CPU1_PWR_VR!!
S!@baseboard_fab2_lib.baseboard_fab2(sch_1):page204_i36@mstr_discrete.cap(chips)!CAP_0402-1.0UF,16V,10%,X6S,D97A!C4C18!//jf4cfls225.pdx.intel.com/apd_proj/ppg_lib/epg_masterlib/logical/mstr_discrete/cap/chips/chips.prt!CAP!CAP_0402-1.0UF,16V,10%,X6S,D97712-011!CAP_0402!!!F3793!!PVCCIN_CPU0_PWR_VR!!
S!@baseboard_fab2_lib.baseboard_fab2(sch_1):page241_i30@mstr_discrete.cap(chips)!CAP_0402-1.0UF,16V,10%,X6S,D97A!C7E14!//jf4cfls225.pdx.intel.com/apd_proj/ppg_lib/epg_masterlib/logical/mstr_discrete/cap/chips/chips.prt!CAP!CAP_0402-1.0UF,16V,10%,X6S,D97712-011!CAP_0402!!!F3765!!P5V_STBY_VR!!
S!@baseboard_fab2_lib.baseboard_fab2(sch_1):page227_i77@mstr_discrete.cap(chips)!CAP_0402-1.0UF,16V,10%,X6S,D97A!C1A6!//jf4cfls225.pdx.intel.com/apd_proj/ppg_lib/epg_masterlib/logical/mstr_discrete/cap/chips/chips.prt!CAP!CAP_0402-1.0UF,16V,10%,X6S,D97712-011!CAP_0402!!!F3828!!VDDQ_KLM_PWR_VR!!
S!@baseboard_fab2_lib.baseboard_fab2(sch_1):page209_i16@mstr_discrete.cap(chips)!CAP_0402-1.0UF,16V,10%,X6S,D97A!C1C26!//jf4cfls225.pdx.intel.com/apd_proj/ppg_lib/epg_masterlib/logical/mstr_discrete/cap/chips/chips.prt!CAP!CAP_0402-1.0UF,16V,10%,X6S,D97712-011!CAP_0402!!!F3821!!PVCCIN_CPU1_PWR_VR!!
S!@baseboard_fab2_lib.baseboard_fab2(sch_1):page209_i18@mstr_discrete.cap(chips)!CAP_0402-1.0UF,16V,10%,X6S,D97A!C1D32!//jf4cfls225.pdx.intel.com/apd_proj/ppg_lib/epg_masterlib/logical/mstr_discrete/cap/chips/chips.prt!CAP!CAP_0402-1.0UF,16V,10%,X6S,D97712-011!CAP_0402!!!F3822!!PVCCIN_CPU1_PWR_VR!!
S!@baseboard_fab2_lib.baseboard_fab2(sch_1):page219_i48@mstr_discrete.cap(chips)!CAP_0402-1.0UF,16V,10%,X6S,D97A!C7A11!//jf4cfls225.pdx.intel.com/apd_proj/ppg_lib/epg_masterlib/logical/mstr_discrete/cap/chips/chips.prt!CAP!CAP_0402-1.0UF,16V,10%,X6S,D97712-011!CAP_0402!!!F3772!!VDDQ_DEF_PWR_VR!!
S!@baseboard_fab2_lib.baseboard_fab2(sch_1):page214_i79@mstr_discrete.cap(chips)!CAP_0402-1.0UF,16V,10%,X6S,D97A!C4E15!//jf4cfls225.pdx.intel.com/apd_proj/ppg_lib/epg_masterlib/logical/mstr_discrete/cap/chips/chips.prt!CAP!CAP_0402-1.0UF,16V,10%,X6S,D97712-011!CAP_0402!!!F3785!!PVCCIO_CPU1!!
S!@baseboard_fab2_lib.baseboard_fab2(sch_1):page214_i76@mstr_discrete.cap(chips)!CAP_0402-1.0UF,16V,10%,X6S,D97A!C4E22!//jf4cfls225.pdx.intel.com/apd_proj/ppg_lib/epg_masterlib/logical/mstr_discrete/cap/chips/chips.prt!CAP!CAP_0402-1.0UF,16V,10%,X6S,D97712-011!CAP_0402!!!F3783!!PVCCIO_CPU1!!
S!@baseboard_fab2_lib.baseboard_fab2(sch_1):page236_i33@mstr_discrete.cap(chips)!CAP_0402-1.0UF,16V,10%,X6S,D97A!C7A9!//jf4cfls225.pdx.intel.com/apd_proj/ppg_lib/epg_masterlib/logical/mstr_discrete/cap/chips/chips.prt!CAP!CAP_0402-1.0UF,16V,10%,X6S,D97712-011!CAP_0402!!!F3774!!P1V05_PCH_STBY_VR!!
S!@baseboard_fab2_lib.baseboard_fab2(sch_1):page236_i22@mstr_discrete.cap(chips)!CAP_0402-1.0UF,16V,10%,X6S,D97A!C7A7!//jf4cfls225.pdx.intel.com/apd_proj/ppg_lib/epg_masterlib/logical/mstr_discrete/cap/chips/chips.prt!CAP!CAP_0402-1.0UF,16V,10%,X6S,D97712-011!CAP_0402!!!F3775!!PVNN_PCH_STBY!!
S!@baseboard_fab2_lib.baseboard_fab2(sch_1):page236_i19@mstr_discrete.cap(chips)!CAP_0402-1.0UF,16V,10%,X6S,D97A!C7A6!//jf4cfls225.pdx.intel.com/apd_proj/ppg_lib/epg_masterlib/logical/mstr_discrete/cap/chips/chips.prt!CAP!CAP_0402-1.0UF,16V,10%,X6S,D97712-011!CAP_0402!!!F3776!!P1V05_PCH_STBY_VR!!
S!@baseboard_fab2_lib.baseboard_fab2(sch_1):page236_i36@mstr_discrete.cap(chips)!CAP_0402-1.0UF,16V,10%,X6S,D97A!C7A10!//jf4cfls225.pdx.intel.com/apd_proj/ppg_lib/epg_masterlib/logical/mstr_discrete/cap/chips/chips.prt!CAP!CAP_0402-1.0UF,16V,10%,X6S,D97712-011!CAP_0402!!!F3773!!P1V05_PCH_STBY_VR!!
S!@baseboard_fab2_lib.baseboard_fab2(sch_1):page199_i3@mstr_discrete.cap(chips)!CAP_0402-1.0UF,16V,10%,X6S,D97A!C1D25!//jf4cfls225.pdx.intel.com/apd_proj/ppg_lib/epg_masterlib/logical/mstr_discrete/cap/chips/chips.prt!CAP!CAP_0402-1.0UF,16V,10%,X6S,D97712-011!CAP_0402!!!F3815!!HOT_SWAP!!
S!@baseboard_fab2_lib.baseboard_fab2(sch_1):page112_i140@mstr_discrete.cap(chips)!CAP_0402-1.0UF,16V,10%,X6S,D97A!C1L19!//jf4cfls225.pdx.intel.com/apd_proj/ppg_lib/epg_masterlib/logical/mstr_discrete/cap/chips/chips.prt!CAP!CAP_0402-1.0UF,16V,10%,X6S,D97712-011!CAP_0402!!!F3805!!DEBUG!!
S!@baseboard_fab2_lib.baseboard_fab2(sch_1):page112_i136@mstr_discrete.cap(chips)!CAP_0402-1.0UF,16V,10%,X6S,D97A!C1L1!//jf4cfls225.pdx.intel.com/apd_proj/ppg_lib/epg_masterlib/logical/mstr_discrete/cap/chips/chips.prt!CAP!CAP_0402-1.0UF,16V,10%,X6S,D97712-011!CAP_0402!!!F3806!!DEBUG!!
S!@baseboard_fab2_lib.baseboard_fab2(sch_1):page92_i79@mstr_discrete.cap(chips)!CAP_0402-1.0UF,16V,10%,X6S,D97A!C7D4!//jf4cfls225.pdx.intel.com/apd_proj/ppg_lib/epg_masterlib/logical/mstr_discrete/cap/chips/chips.prt!CAP!CAP_0402-1.0UF,16V,10%,X6S,D97712-011!CAP_0402!!!F3766!!PROC_SIDEBAND!!
S!@baseboard_fab2_lib.baseboard_fab2(sch_1):page92_i84@mstr_discrete.cap(chips)!CAP_0402-1.0UF,16V,10%,X6S,D97A!C3P50!//jf4cfls225.pdx.intel.com/apd_proj/ppg_lib/epg_masterlib/logical/mstr_discrete/cap/chips/chips.prt!CAP!CAP_0402-1.0UF,16V,10%,X6S,D97712-011!CAP_0402!!!F3802!!PROC_SIDEBAND!!
S!@baseboard_fab2_lib.baseboard_fab2(sch_1):page152_i18@mstr_discrete.cap(chips)!CAP_0402-1.0UF,16V,10%,X6S,D97A!C1U19!//jf4cfls225.pdx.intel.com/apd_proj/ppg_lib/epg_masterlib/logical/mstr_discrete/cap/chips/chips.prt!CAP!CAP_0402-1.0UF,16V,10%,X6S,D97712-011!CAP_0402!!!F3804!!PROC_SIDEBAND!!
S!@baseboard_fab2_lib.baseboard_fab2(sch_1):page221_i24@mstr_discrete.cap(chips)!CAP_0402-1.0UF,16V,10%,X6S,D97A!C4G15!//jf4cfls225.pdx.intel.com/apd_proj/ppg_lib/epg_masterlib/logical/mstr_discrete/cap/chips/chips.prt!CAP!CAP_0402-1.0UF,16V,10%,X6S,D97712-011!CAP_0402!!!F3781!!VTT_ABC_PWR_VR!!
S!@baseboard_fab2_lib.baseboard_fab2(sch_1):page221_i34@mstr_discrete.cap(chips)!CAP_0402-1.0UF,16V,10%,X6S,D97A!C4G16!//jf4cfls225.pdx.intel.com/apd_proj/ppg_lib/epg_masterlib/logical/mstr_discrete/cap/chips/chips.prt!CAP!CAP_0402-1.0UF,16V,10%,X6S,D97712-011!CAP_0402!!!F3780!!VTT_ABC_PWR_VR!!
S!@baseboard_fab2_lib.baseboard_fab2(sch_1):page222_i21@mstr_discrete.cap(chips)!CAP_0402-1.0UF,16V,10%,X6S,D97A!C4A9!//jf4cfls225.pdx.intel.com/apd_proj/ppg_lib/epg_masterlib/logical/mstr_discrete/cap/chips/chips.prt!CAP!CAP_0402-1.0UF,16V,10%,X6S,D97712-011!CAP_0402!!!F3799!!VTT_DEF_PWR_VR!!
S!@baseboard_fab2_lib.baseboard_fab2(sch_1):page229_i21@mstr_discrete.cap(chips)!CAP_0402-1.0UF,16V,10%,X6S,D97A!C4G21!//jf4cfls225.pdx.intel.com/apd_proj/ppg_lib/epg_masterlib/logical/mstr_discrete/cap/chips/chips.prt!CAP!CAP_0402-1.0UF,16V,10%,X6S,D97712-011!CAP_0402!!!F3778!!VTT_GHJ_PWR_VR!!
S!@baseboard_fab2_lib.baseboard_fab2(sch_1):page230_i21@mstr_discrete.cap(chips)!CAP_0402-1.0UF,16V,10%,X6S,D97A!C4A14!//jf4cfls225.pdx.intel.com/apd_proj/ppg_lib/epg_masterlib/logical/mstr_discrete/cap/chips/chips.prt!CAP!CAP_0402-1.0UF,16V,10%,X6S,D97712-011!CAP_0402!!!F3797!!VTT_KLM_PWR_VR!!
S!@baseboard_fab2_lib.baseboard_fab2(sch_1):page222_i28@mstr_discrete.cap(chips)!CAP_0402-1.0UF,16V,10%,X6S,D97A!C4A10!//jf4cfls225.pdx.intel.com/apd_proj/ppg_lib/epg_masterlib/logical/mstr_discrete/cap/chips/chips.prt!CAP!CAP_0402-1.0UF,16V,10%,X6S,D97712-011!CAP_0402!!!F3798!!VTT_DEF_PWR_VR!!
S!@baseboard_fab2_lib.baseboard_fab2(sch_1):page229_i27@mstr_discrete.cap(chips)!CAP_0402-1.0UF,16V,10%,X6S,D97A!C4G18!//jf4cfls225.pdx.intel.com/apd_proj/ppg_lib/epg_masterlib/logical/mstr_discrete/cap/chips/chips.prt!CAP!CAP_0402-1.0UF,16V,10%,X6S,D97712-011!CAP_0402!!!F3779!!VTT_GHJ_PWR_VR!!
S!@baseboard_fab2_lib.baseboard_fab2(sch_1):page230_i28@mstr_discrete.cap(chips)!CAP_0402-1.0UF,16V,10%,X6S,D97A!C4A8!//jf4cfls225.pdx.intel.com/apd_proj/ppg_lib/epg_masterlib/logical/mstr_discrete/cap/chips/chips.prt!CAP!CAP_0402-1.0UF,16V,10%,X6S,D97712-011!CAP_0402!!!F3800!!VTT_KLM_PWR_VR!!
S!@baseboard_fab2_lib.baseboard_fab2(sch_1):page221_i1@mstr_vreg.mic5166(chips)!MIC5166_DFN-IC,H55101-001!EU4G3!//jf4cfls225.pdx.intel.com/apd_proj/ppg_lib/epg_masterlib/logical/mstr_vreg/mic5166/chips/chips.prt!MIC5166!MIC5166_DFN-IC,H55101-001!MIC5166_DFN!!!F2021!!VTT_ABC_PWR_VR!!
S!@baseboard_fab2_lib.baseboard_fab2(sch_1):page222_i31@mstr_vreg.mic5166(chips)!MIC5166_DFN-IC,H55101-001!EU4A1!//jf4cfls225.pdx.intel.com/apd_proj/ppg_lib/epg_masterlib/logical/mstr_vreg/mic5166/chips/chips.prt!MIC5166!MIC5166_DFN-IC,H55101-001!MIC5166_DFN!!!F2024!!VTT_DEF_PWR_VR!!
S!@baseboard_fab2_lib.baseboard_fab2(sch_1):page229_i24@mstr_vreg.mic5166(chips)!MIC5166_DFN-IC,H55101-001!EU4G2!//jf4cfls225.pdx.intel.com/apd_proj/ppg_lib/epg_masterlib/logical/mstr_vreg/mic5166/chips/chips.prt!MIC5166!MIC5166_DFN-IC,H55101-001!MIC5166_DFN!!!F2022!!VTT_GHJ_PWR_VR!!
S!@baseboard_fab2_lib.baseboard_fab2(sch_1):page230_i31@mstr_vreg.mic5166(chips)!MIC5166_DFN-IC,H55101-001!EU4A2!//jf4cfls225.pdx.intel.com/apd_proj/ppg_lib/epg_masterlib/logical/mstr_vreg/mic5166/chips/chips.prt!MIC5166!MIC5166_DFN-IC,H55101-001!MIC5166_DFN!!!F2023!!VTT_KLM_PWR_VR!!
S!@baseboard_fab2_lib.baseboard_fab2(sch_1):page197_i97@mstr_vreg.max9634(chips)!MAX9634_SOT-IC,H35789-001!U4F1!//jf4cfls225.pdx.intel.com/apd_proj/ppg_lib/epg_masterlib/logical/mstr_vreg/max9634/chips/chips.prt!MAX9634!MAX9634_SOT-IC,H35789-001!MAX9634_SOT!!!F2025!!PVDDQ_ABC_PWR_VR!!
S!@baseboard_fab2_lib.baseboard_fab2(sch_1):page197_i120@mstr_vreg.max9634(chips)!MAX9634_SOT-IC,H35789-001!U4B1!//jf4cfls225.pdx.intel.com/apd_proj/ppg_lib/epg_masterlib/logical/mstr_vreg/max9634/chips/chips.prt!MAX9634!MAX9634_SOT-IC,H35789-001!MAX9634_SOT!!!F2026!!PVDDQ_DEF_PWR_VR!!
S!@baseboard_fab2_lib.baseboard_fab2(sch_1):page197_i133@mstr_vreg.max9634(chips)!MAX9634_SOT-IC,H35789-001!U1F1!//jf4cfls225.pdx.intel.com/apd_proj/ppg_lib/epg_masterlib/logical/mstr_vreg/max9634/chips/chips.prt!MAX9634!MAX9634_SOT-IC,H35789-001!MAX9634_SOT!!!F2027!!PVDDQ_GHJ_PWR_VR!!
S!@baseboard_fab2_lib.baseboard_fab2(sch_1):page197_i144@mstr_vreg.max9634(chips)!MAX9634_SOT-IC,H35789-001!U1B1!//jf4cfls225.pdx.intel.com/apd_proj/ppg_lib/epg_masterlib/logical/mstr_vreg/max9634/chips/chips.prt!MAX9634!MAX9634_SOT-IC,H35789-001!MAX9634_SOT!!!F2028!!PVDDQ_KLM_PWR_VR!!
S!@baseboard_fab2_lib.baseboard_fab2(sch_1):page197_i99@mstr_discrete.res(chips)!RES_1206-0.002,1%,1W,CHIP,G521A!R4F2!//jf4cfls225.pdx.intel.com/apd_proj/ppg_lib/epg_masterlib/logical/mstr_discrete/res/chips/chips.prt!RES!RES_1206-0.002,1%,1W,CHIP,G52199-004!RES!!!F252!!PVDDQ_ABC_PWR_VR!!
S!@baseboard_fab2_lib.baseboard_fab2(sch_1):page197_i121@mstr_discrete.res(chips)!RES_1206-0.002,1%,1W,CHIP,G521A!R4B12!//jf4cfls225.pdx.intel.com/apd_proj/ppg_lib/epg_masterlib/logical/mstr_discrete/res/chips/chips.prt!RES!RES_1206-0.002,1%,1W,CHIP,G52199-004!RES!!!F253!!PVDDQ_DEF_PWR_VR!!
S!@baseboard_fab2_lib.baseboard_fab2(sch_1):page197_i131@mstr_discrete.res(chips)!RES_1206-0.002,1%,1W,CHIP,G521A!R1F3!//jf4cfls225.pdx.intel.com/apd_proj/ppg_lib/epg_masterlib/logical/mstr_discrete/res/chips/chips.prt!RES!RES_1206-0.002,1%,1W,CHIP,G52199-004!RES!!!F254!!PVDDQ_GHJ_PWR_VR!!
S!@baseboard_fab2_lib.baseboard_fab2(sch_1):page197_i142@mstr_discrete.res(chips)!RES_1206-0.002,1%,1W,CHIP,G521A!R9M4!//jf4cfls225.pdx.intel.com/apd_proj/ppg_lib/epg_masterlib/logical/mstr_discrete/res/chips/chips.prt!RES!RES_1206-0.002,1%,1W,CHIP,G52199-004!RES!!!F251!!PVDDQ_KLM_PWR_VR!!
S!@baseboard_fab2_lib.baseboard_fab2(sch_1):page107_i272@mstr_discrete.cap(chips)!CAP_0402-0.22UF,16V,10%,X7R,A3A!C2U3!//jf4cfls225.pdx.intel.com/apd_proj/ppg_lib/epg_masterlib/logical/mstr_discrete/cap/chips/chips.prt!CAP!CAP_0402-0.22UF,16V,10%,X7R,A36096-155!CAP_0402!!!F3971!!!!
S!@baseboard_fab2_lib.baseboard_fab2(sch_1):page107_i257@mstr_discrete.cap(chips)!CAP_0402-0.22UF,16V,10%,X7R,A3A!C2U4!//jf4cfls225.pdx.intel.com/apd_proj/ppg_lib/epg_masterlib/logical/mstr_discrete/cap/chips/chips.prt!CAP!CAP_0402-0.22UF,16V,10%,X7R,A36096-155!CAP_0402!!!F3970!!!!
S!@baseboard_fab2_lib.baseboard_fab2(sch_1):page107_i274@mstr_discrete.cap(chips)!CAP_0402-0.22UF,16V,10%,X7R,A3A!C2U5!//jf4cfls225.pdx.intel.com/apd_proj/ppg_lib/epg_masterlib/logical/mstr_discrete/cap/chips/chips.prt!CAP!CAP_0402-0.22UF,16V,10%,X7R,A36096-155!CAP_0402!!!F3969!!!!
S!@baseboard_fab2_lib.baseboard_fab2(sch_1):page107_i260@mstr_discrete.cap(chips)!CAP_0402-0.22UF,16V,10%,X7R,A3A!C2U6!//jf4cfls225.pdx.intel.com/apd_proj/ppg_lib/epg_masterlib/logical/mstr_discrete/cap/chips/chips.prt!CAP!CAP_0402-0.22UF,16V,10%,X7R,A36096-155!CAP_0402!!!F3968!!!!
S!@baseboard_fab2_lib.baseboard_fab2(sch_1):page107_i277@mstr_discrete.cap(chips)!CAP_0402-0.22UF,16V,10%,X7R,A3A!C2U7!//jf4cfls225.pdx.intel.com/apd_proj/ppg_lib/epg_masterlib/logical/mstr_discrete/cap/chips/chips.prt!CAP!CAP_0402-0.22UF,16V,10%,X7R,A36096-155!CAP_0402!!!F3967!!!!
S!@baseboard_fab2_lib.baseboard_fab2(sch_1):page107_i264@mstr_discrete.cap(chips)!CAP_0402-0.22UF,16V,10%,X7R,A3A!C2U8!//jf4cfls225.pdx.intel.com/apd_proj/ppg_lib/epg_masterlib/logical/mstr_discrete/cap/chips/chips.prt!CAP!CAP_0402-0.22UF,16V,10%,X7R,A36096-155!CAP_0402!!!F3966!!!!
S!@baseboard_fab2_lib.baseboard_fab2(sch_1):page107_i279@mstr_discrete.cap(chips)!CAP_0402-0.22UF,16V,10%,X7R,A3A!C2U9!//jf4cfls225.pdx.intel.com/apd_proj/ppg_lib/epg_masterlib/logical/mstr_discrete/cap/chips/chips.prt!CAP!CAP_0402-0.22UF,16V,10%,X7R,A36096-155!CAP_0402!!!F3965!!!!
S!@baseboard_fab2_lib.baseboard_fab2(sch_1):page107_i267@mstr_discrete.cap(chips)!CAP_0402-0.22UF,16V,10%,X7R,A3A!C2U10!//jf4cfls225.pdx.intel.com/apd_proj/ppg_lib/epg_masterlib/logical/mstr_discrete/cap/chips/chips.prt!CAP!CAP_0402-0.22UF,16V,10%,X7R,A36096-155!CAP_0402!!!F3964!!!!
S!@baseboard_fab2_lib.baseboard_fab2(sch_1):page107_i278@mstr_discrete.cap(chips)!CAP_0402-0.22UF,16V,10%,X7R,A3A!C2U11!//jf4cfls225.pdx.intel.com/apd_proj/ppg_lib/epg_masterlib/logical/mstr_discrete/cap/chips/chips.prt!CAP!CAP_0402-0.22UF,16V,10%,X7R,A36096-155!CAP_0402!!!F3963!!!!
S!@baseboard_fab2_lib.baseboard_fab2(sch_1):page107_i265@mstr_discrete.cap(chips)!CAP_0402-0.22UF,16V,10%,X7R,A3A!C2U12!//jf4cfls225.pdx.intel.com/apd_proj/ppg_lib/epg_masterlib/logical/mstr_discrete/cap/chips/chips.prt!CAP!CAP_0402-0.22UF,16V,10%,X7R,A36096-155!CAP_0402!!!F3962!!!!
S!@baseboard_fab2_lib.baseboard_fab2(sch_1):page107_i297@mstr_discrete.cap(chips)!CAP_0402-0.22UF,16V,10%,X7R,A3A!C2U13!//jf4cfls225.pdx.intel.com/apd_proj/ppg_lib/epg_masterlib/logical/mstr_discrete/cap/chips/chips.prt!CAP!CAP_0402-0.22UF,16V,10%,X7R,A36096-155!CAP_0402!!!F3961!!!!
S!@baseboard_fab2_lib.baseboard_fab2(sch_1):page107_i287@mstr_discrete.cap(chips)!CAP_0402-0.22UF,16V,10%,X7R,A3A!C2U14!//jf4cfls225.pdx.intel.com/apd_proj/ppg_lib/epg_masterlib/logical/mstr_discrete/cap/chips/chips.prt!CAP!CAP_0402-0.22UF,16V,10%,X7R,A36096-155!CAP_0402!!!F3960!!!!
S!@baseboard_fab2_lib.baseboard_fab2(sch_1):page107_i296@mstr_discrete.cap(chips)!CAP_0402-0.22UF,16V,10%,X7R,A3A!C2U15!//jf4cfls225.pdx.intel.com/apd_proj/ppg_lib/epg_masterlib/logical/mstr_discrete/cap/chips/chips.prt!CAP!CAP_0402-0.22UF,16V,10%,X7R,A36096-155!CAP_0402!!!F3959!!!!
S!@baseboard_fab2_lib.baseboard_fab2(sch_1):page107_i286@mstr_discrete.cap(chips)!CAP_0402-0.22UF,16V,10%,X7R,A3A!C2U16!//jf4cfls225.pdx.intel.com/apd_proj/ppg_lib/epg_masterlib/logical/mstr_discrete/cap/chips/chips.prt!CAP!CAP_0402-0.22UF,16V,10%,X7R,A36096-155!CAP_0402!!!F3958!!!!
S!@baseboard_fab2_lib.baseboard_fab2(sch_1):page107_i300@mstr_discrete.cap(chips)!CAP_0402-0.22UF,16V,10%,X7R,A3A!C2U17!//jf4cfls225.pdx.intel.com/apd_proj/ppg_lib/epg_masterlib/logical/mstr_discrete/cap/chips/chips.prt!CAP!CAP_0402-0.22UF,16V,10%,X7R,A36096-155!CAP_0402!!!F3957!!!!
S!@baseboard_fab2_lib.baseboard_fab2(sch_1):page107_i294@mstr_discrete.cap(chips)!CAP_0402-0.22UF,16V,10%,X7R,A3A!C2U18!//jf4cfls225.pdx.intel.com/apd_proj/ppg_lib/epg_masterlib/logical/mstr_discrete/cap/chips/chips.prt!CAP!CAP_0402-0.22UF,16V,10%,X7R,A36096-155!CAP_0402!!!F3956!!!!
S!@baseboard_fab2_lib.baseboard_fab2(sch_1):page107_i212@mstr_discrete.cap(chips)!CAP_0402-0.22UF,16V,10%,X7R,A3A!C3P11!//jf4cfls225.pdx.intel.com/apd_proj/ppg_lib/epg_masterlib/logical/mstr_discrete/cap/chips/chips.prt!CAP!CAP_0402-0.22UF,16V,10%,X7R,A36096-155!CAP_0402!!!F3931!!!!
S!@baseboard_fab2_lib.baseboard_fab2(sch_1):page107_i207@mstr_discrete.cap(chips)!CAP_0402-0.22UF,16V,10%,X7R,A3A!C3P13!//jf4cfls225.pdx.intel.com/apd_proj/ppg_lib/epg_masterlib/logical/mstr_discrete/cap/chips/chips.prt!CAP!CAP_0402-0.22UF,16V,10%,X7R,A36096-155!CAP_0402!!!F3930!!!!
S!@baseboard_fab2_lib.baseboard_fab2(sch_1):page107_i226@mstr_discrete.cap(chips)!CAP_0402-0.22UF,16V,10%,X7R,A3A!C3P15!//jf4cfls225.pdx.intel.com/apd_proj/ppg_lib/epg_masterlib/logical/mstr_discrete/cap/chips/chips.prt!CAP!CAP_0402-0.22UF,16V,10%,X7R,A36096-155!CAP_0402!!!F3929!!!!
S!@baseboard_fab2_lib.baseboard_fab2(sch_1):page107_i208@mstr_discrete.cap(chips)!CAP_0402-0.22UF,16V,10%,X7R,A3A!C3P17!//jf4cfls225.pdx.intel.com/apd_proj/ppg_lib/epg_masterlib/logical/mstr_discrete/cap/chips/chips.prt!CAP!CAP_0402-0.22UF,16V,10%,X7R,A36096-155!CAP_0402!!!F3928!!!!
S!@baseboard_fab2_lib.baseboard_fab2(sch_1):page107_i219@mstr_discrete.cap(chips)!CAP_0402-0.22UF,16V,10%,X7R,A3A!C3P18!//jf4cfls225.pdx.intel.com/apd_proj/ppg_lib/epg_masterlib/logical/mstr_discrete/cap/chips/chips.prt!CAP!CAP_0402-0.22UF,16V,10%,X7R,A36096-155!CAP_0402!!!F3927!!!!
S!@baseboard_fab2_lib.baseboard_fab2(sch_1):page107_i215@mstr_discrete.cap(chips)!CAP_0402-0.22UF,16V,10%,X7R,A3A!C3P20!//jf4cfls225.pdx.intel.com/apd_proj/ppg_lib/epg_masterlib/logical/mstr_discrete/cap/chips/chips.prt!CAP!CAP_0402-0.22UF,16V,10%,X7R,A36096-155!CAP_0402!!!F3926!!!!
S!@baseboard_fab2_lib.baseboard_fab2(sch_1):page107_i229@mstr_discrete.cap(chips)!CAP_0402-0.22UF,16V,10%,X7R,A3A!C3P23!//jf4cfls225.pdx.intel.com/apd_proj/ppg_lib/epg_masterlib/logical/mstr_discrete/cap/chips/chips.prt!CAP!CAP_0402-0.22UF,16V,10%,X7R,A36096-155!CAP_0402!!!F3925!!!!
S!@baseboard_fab2_lib.baseboard_fab2(sch_1):page107_i216@mstr_discrete.cap(chips)!CAP_0402-0.22UF,16V,10%,X7R,A3A!C3P25!//jf4cfls225.pdx.intel.com/apd_proj/ppg_lib/epg_masterlib/logical/mstr_discrete/cap/chips/chips.prt!CAP!CAP_0402-0.22UF,16V,10%,X7R,A36096-155!CAP_0402!!!F3924!!!!
S!@baseboard_fab2_lib.baseboard_fab2(sch_1):page107_i223@mstr_discrete.cap(chips)!CAP_0402-0.22UF,16V,10%,X7R,A3A!C3P27!//jf4cfls225.pdx.intel.com/apd_proj/ppg_lib/epg_masterlib/logical/mstr_discrete/cap/chips/chips.prt!CAP!CAP_0402-0.22UF,16V,10%,X7R,A36096-155!CAP_0402!!!F3923!!!!
S!@baseboard_fab2_lib.baseboard_fab2(sch_1):page107_i232@mstr_discrete.cap(chips)!CAP_0402-0.22UF,16V,10%,X7R,A3A!C3P28!//jf4cfls225.pdx.intel.com/apd_proj/ppg_lib/epg_masterlib/logical/mstr_discrete/cap/chips/chips.prt!CAP!CAP_0402-0.22UF,16V,10%,X7R,A36096-155!CAP_0402!!!F3922!!!!
S!@baseboard_fab2_lib.baseboard_fab2(sch_1):page107_i245@mstr_discrete.cap(chips)!CAP_0402-0.22UF,16V,10%,X7R,A3A!C3P30!//jf4cfls225.pdx.intel.com/apd_proj/ppg_lib/epg_masterlib/logical/mstr_discrete/cap/chips/chips.prt!CAP!CAP_0402-0.22UF,16V,10%,X7R,A36096-155!CAP_0402!!!F3921!!!!
S!@baseboard_fab2_lib.baseboard_fab2(sch_1):page107_i234@mstr_discrete.cap(chips)!CAP_0402-0.22UF,16V,10%,X7R,A3A!C3P32!//jf4cfls225.pdx.intel.com/apd_proj/ppg_lib/epg_masterlib/logical/mstr_discrete/cap/chips/chips.prt!CAP!CAP_0402-0.22UF,16V,10%,X7R,A36096-155!CAP_0402!!!F3920!!!!
S!@baseboard_fab2_lib.baseboard_fab2(sch_1):page107_i240@mstr_discrete.cap(chips)!CAP_0402-0.22UF,16V,10%,X7R,A3A!C3P35!//jf4cfls225.pdx.intel.com/apd_proj/ppg_lib/epg_masterlib/logical/mstr_discrete/cap/chips/chips.prt!CAP!CAP_0402-0.22UF,16V,10%,X7R,A36096-155!CAP_0402!!!F3919!!!!
S!@baseboard_fab2_lib.baseboard_fab2(sch_1):page107_i235@mstr_discrete.cap(chips)!CAP_0402-0.22UF,16V,10%,X7R,A3A!C3P37!//jf4cfls225.pdx.intel.com/apd_proj/ppg_lib/epg_masterlib/logical/mstr_discrete/cap/chips/chips.prt!CAP!CAP_0402-0.22UF,16V,10%,X7R,A36096-155!CAP_0402!!!F3918!!!!
S!@baseboard_fab2_lib.baseboard_fab2(sch_1):page107_i248@mstr_discrete.cap(chips)!CAP_0402-0.22UF,16V,10%,X7R,A3A!C3P39!//jf4cfls225.pdx.intel.com/apd_proj/ppg_lib/epg_masterlib/logical/mstr_discrete/cap/chips/chips.prt!CAP!CAP_0402-0.22UF,16V,10%,X7R,A36096-155!CAP_0402!!!F3917!!!!
S!@baseboard_fab2_lib.baseboard_fab2(sch_1):page107_i241@mstr_discrete.cap(chips)!CAP_0402-0.22UF,16V,10%,X7R,A3A!C3P40!//jf4cfls225.pdx.intel.com/apd_proj/ppg_lib/epg_masterlib/logical/mstr_discrete/cap/chips/chips.prt!CAP!CAP_0402-0.22UF,16V,10%,X7R,A36096-155!CAP_0402!!!F3916!!!!
S!@baseboard_fab2_lib.baseboard_fab2(sch_1):page185_i96@mstr_discrete.cap(chips)!CAP_0402-0.22UF,16V,10%,X7R,A3A!C8F7!//jf4cfls225.pdx.intel.com/apd_proj/ppg_lib/epg_masterlib/logical/mstr_discrete/cap/chips/chips.prt!CAP!CAP_0402-0.22UF,16V,10%,X7R,A36096-155!CAP_0402!!!F3856!!M_2!!
S!@baseboard_fab2_lib.baseboard_fab2(sch_1):page185_i98@mstr_discrete.cap(chips)!CAP_0402-0.22UF,16V,10%,X7R,A3A!C8F12!//jf4cfls225.pdx.intel.com/apd_proj/ppg_lib/epg_masterlib/logical/mstr_discrete/cap/chips/chips.prt!CAP!CAP_0402-0.22UF,16V,10%,X7R,A36096-155!CAP_0402!!!F3855!!M_2!!
S!@baseboard_fab2_lib.baseboard_fab2(sch_1):page105_i247@mstr_discrete.cap(chips)!CAP_0402-0.22UF,16V,10%,X7R,A3A!C3M2!//jf4cfls225.pdx.intel.com/apd_proj/ppg_lib/epg_masterlib/logical/mstr_discrete/cap/chips/chips.prt!CAP!CAP_0402-0.22UF,16V,10%,X7R,A36096-155!CAP_0402!!!F3954!!OCP_STEERING!!
S!@baseboard_fab2_lib.baseboard_fab2(sch_1):page105_i255@mstr_discrete.cap(chips)!CAP_0402-0.22UF,16V,10%,X7R,A3A!C3M1!//jf4cfls225.pdx.intel.com/apd_proj/ppg_lib/epg_masterlib/logical/mstr_discrete/cap/chips/chips.prt!CAP!CAP_0402-0.22UF,16V,10%,X7R,A36096-155!CAP_0402!!!F3955!!OCP_STEERING!!
S!@baseboard_fab2_lib.baseboard_fab2(sch_1):page105_i234@mstr_discrete.cap(chips)!CAP_0402-0.22UF,16V,10%,X7R,A3A!C3M11!//jf4cfls225.pdx.intel.com/apd_proj/ppg_lib/epg_masterlib/logical/mstr_discrete/cap/chips/chips.prt!CAP!CAP_0402-0.22UF,16V,10%,X7R,A36096-155!CAP_0402!!!F3951!!OCP_STEERING!!
S!@baseboard_fab2_lib.baseboard_fab2(sch_1):page105_i246@mstr_discrete.cap(chips)!CAP_0402-0.22UF,16V,10%,X7R,A3A!C3M12!//jf4cfls225.pdx.intel.com/apd_proj/ppg_lib/epg_masterlib/logical/mstr_discrete/cap/chips/chips.prt!CAP!CAP_0402-0.22UF,16V,10%,X7R,A36096-155!CAP_0402!!!F3950!!OCP_STEERING!!
S!@baseboard_fab2_lib.baseboard_fab2(sch_1):page105_i239@mstr_discrete.cap(chips)!CAP_0402-0.22UF,16V,10%,X7R,A3A!C3M13!//jf4cfls225.pdx.intel.com/apd_proj/ppg_lib/epg_masterlib/logical/mstr_discrete/cap/chips/chips.prt!CAP!CAP_0402-0.22UF,16V,10%,X7R,A36096-155!CAP_0402!!!F3949!!OCP_STEERING!!
S!@baseboard_fab2_lib.baseboard_fab2(sch_1):page105_i253@mstr_discrete.cap(chips)!CAP_0402-0.22UF,16V,10%,X7R,A3A!C3M14!//jf4cfls225.pdx.intel.com/apd_proj/ppg_lib/epg_masterlib/logical/mstr_discrete/cap/chips/chips.prt!CAP!CAP_0402-0.22UF,16V,10%,X7R,A36096-155!CAP_0402!!!F3948!!OCP_STEERING!!
S!@baseboard_fab2_lib.baseboard_fab2(sch_1):page105_i232@mstr_discrete.cap(chips)!CAP_0402-0.22UF,16V,10%,X7R,A3A!C3M3!//jf4cfls225.pdx.intel.com/apd_proj/ppg_lib/epg_masterlib/logical/mstr_discrete/cap/chips/chips.prt!CAP!CAP_0402-0.22UF,16V,10%,X7R,A36096-155!CAP_0402!!!F3953!!OCP_STEERING!!
S!@baseboard_fab2_lib.baseboard_fab2(sch_1):page105_i244@mstr_discrete.cap(chips)!CAP_0402-0.22UF,16V,10%,X7R,A3A!C3M4!//jf4cfls225.pdx.intel.com/apd_proj/ppg_lib/epg_masterlib/logical/mstr_discrete/cap/chips/chips.prt!CAP!CAP_0402-0.22UF,16V,10%,X7R,A36096-155!CAP_0402!!!F3952!!OCP_STEERING!!
S!@baseboard_fab2_lib.baseboard_fab2(sch_1):page105_i205@mstr_discrete.cap(chips)!CAP_0402-0.22UF,16V,10%,X7R,A3A!C3M25!//jf4cfls225.pdx.intel.com/apd_proj/ppg_lib/epg_masterlib/logical/mstr_discrete/cap/chips/chips.prt!CAP!CAP_0402-0.22UF,16V,10%,X7R,A36096-155!CAP_0402!!!F3947!!OCP_STEERING!!
S!@baseboard_fab2_lib.baseboard_fab2(sch_1):page105_i229@mstr_discrete.cap(chips)!CAP_0402-0.22UF,16V,10%,X7R,A3A!C3M26!//jf4cfls225.pdx.intel.com/apd_proj/ppg_lib/epg_masterlib/logical/mstr_discrete/cap/chips/chips.prt!CAP!CAP_0402-0.22UF,16V,10%,X7R,A36096-155!CAP_0402!!!F3946!!OCP_STEERING!!
S!@baseboard_fab2_lib.baseboard_fab2(sch_1):page105_i212@mstr_discrete.cap(chips)!CAP_0402-0.22UF,16V,10%,X7R,A3A!C3M28!//jf4cfls225.pdx.intel.com/apd_proj/ppg_lib/epg_masterlib/logical/mstr_discrete/cap/chips/chips.prt!CAP!CAP_0402-0.22UF,16V,10%,X7R,A36096-155!CAP_0402!!!F3945!!OCP_STEERING!!
S!@baseboard_fab2_lib.baseboard_fab2(sch_1):page105_i223@mstr_discrete.cap(chips)!CAP_0402-0.22UF,16V,10%,X7R,A3A!C3M32!//jf4cfls225.pdx.intel.com/apd_proj/ppg_lib/epg_masterlib/logical/mstr_discrete/cap/chips/chips.prt!CAP!CAP_0402-0.22UF,16V,10%,X7R,A36096-155!CAP_0402!!!F3944!!OCP_STEERING!!
S!@baseboard_fab2_lib.baseboard_fab2(sch_1):page105_i218@mstr_discrete.cap(chips)!CAP_0402-0.22UF,16V,10%,X7R,A3A!C3M36!//jf4cfls225.pdx.intel.com/apd_proj/ppg_lib/epg_masterlib/logical/mstr_discrete/cap/chips/chips.prt!CAP!CAP_0402-0.22UF,16V,10%,X7R,A36096-155!CAP_0402!!!F3940!!OCP_STEERING!!
S!@baseboard_fab2_lib.baseboard_fab2(sch_1):page105_i225@mstr_discrete.cap(chips)!CAP_0402-0.22UF,16V,10%,X7R,A3A!C3M35!//jf4cfls225.pdx.intel.com/apd_proj/ppg_lib/epg_masterlib/logical/mstr_discrete/cap/chips/chips.prt!CAP!CAP_0402-0.22UF,16V,10%,X7R,A36096-155!CAP_0402!!!F3941!!OCP_STEERING!!
S!@baseboard_fab2_lib.baseboard_fab2(sch_1):page105_i206@mstr_discrete.cap(chips)!CAP_0402-0.22UF,16V,10%,X7R,A3A!C3M34!//jf4cfls225.pdx.intel.com/apd_proj/ppg_lib/epg_masterlib/logical/mstr_discrete/cap/chips/chips.prt!CAP!CAP_0402-0.22UF,16V,10%,X7R,A36096-155!CAP_0402!!!F3942!!OCP_STEERING!!
S!@baseboard_fab2_lib.baseboard_fab2(sch_1):page105_i217@mstr_discrete.cap(chips)!CAP_0402-0.22UF,16V,10%,X7R,A3A!C3M33!//jf4cfls225.pdx.intel.com/apd_proj/ppg_lib/epg_masterlib/logical/mstr_discrete/cap/chips/chips.prt!CAP!CAP_0402-0.22UF,16V,10%,X7R,A36096-155!CAP_0402!!!F3943!!OCP_STEERING!!
S!@baseboard_fab2_lib.baseboard_fab2(sch_1):page105_i196@mstr_discrete.cap(chips)!CAP_0402-0.22UF,16V,10%,X7R,A3A!C6B4!//jf4cfls225.pdx.intel.com/apd_proj/ppg_lib/epg_masterlib/logical/mstr_discrete/cap/chips/chips.prt!CAP!CAP_0402-0.22UF,16V,10%,X7R,A36096-155!CAP_0402!!!F3908!!OCP_STEERING!!
S!@baseboard_fab2_lib.baseboard_fab2(sch_1):page105_i201@mstr_discrete.cap(chips)!CAP_0402-0.22UF,16V,10%,X7R,A3A!C6B5!//jf4cfls225.pdx.intel.com/apd_proj/ppg_lib/epg_masterlib/logical/mstr_discrete/cap/chips/chips.prt!CAP!CAP_0402-0.22UF,16V,10%,X7R,A36096-155!CAP_0402!!!F3907!!OCP_STEERING!!
S!@baseboard_fab2_lib.baseboard_fab2(sch_1):page105_i169@mstr_discrete.cap(chips)!CAP_0402-0.22UF,16V,10%,X7R,A3A!C6B6!//jf4cfls225.pdx.intel.com/apd_proj/ppg_lib/epg_masterlib/logical/mstr_discrete/cap/chips/chips.prt!CAP!CAP_0402-0.22UF,16V,10%,X7R,A36096-155!CAP_0402!!!F3906!!OCP_STEERING!!
S!@baseboard_fab2_lib.baseboard_fab2(sch_1):page105_i198@mstr_discrete.cap(chips)!CAP_0402-0.22UF,16V,10%,X7R,A3A!C6B8!//jf4cfls225.pdx.intel.com/apd_proj/ppg_lib/epg_masterlib/logical/mstr_discrete/cap/chips/chips.prt!CAP!CAP_0402-0.22UF,16V,10%,X7R,A36096-155!CAP_0402!!!F3905!!OCP_STEERING!!
S!@baseboard_fab2_lib.baseboard_fab2(sch_1):page105_i185@mstr_discrete.cap(chips)!CAP_0402-0.22UF,16V,10%,X7R,A3A!C6B9!//jf4cfls225.pdx.intel.com/apd_proj/ppg_lib/epg_masterlib/logical/mstr_discrete/cap/chips/chips.prt!CAP!CAP_0402-0.22UF,16V,10%,X7R,A36096-155!CAP_0402!!!F3904!!OCP_STEERING!!
S!@baseboard_fab2_lib.baseboard_fab2(sch_1):page105_i193@mstr_discrete.cap(chips)!CAP_0402-0.22UF,16V,10%,X7R,A3A!C6B10!//jf4cfls225.pdx.intel.com/apd_proj/ppg_lib/epg_masterlib/logical/mstr_discrete/cap/chips/chips.prt!CAP!CAP_0402-0.22UF,16V,10%,X7R,A36096-155!CAP_0402!!!F3903!!OCP_STEERING!!
S!@baseboard_fab2_lib.baseboard_fab2(sch_1):page105_i166@mstr_discrete.cap(chips)!CAP_0402-0.22UF,16V,10%,X7R,A3A!C6B11!//jf4cfls225.pdx.intel.com/apd_proj/ppg_lib/epg_masterlib/logical/mstr_discrete/cap/chips/chips.prt!CAP!CAP_0402-0.22UF,16V,10%,X7R,A36096-155!CAP_0402!!!F3902!!OCP_STEERING!!
S!@baseboard_fab2_lib.baseboard_fab2(sch_1):page105_i187@mstr_discrete.cap(chips)!CAP_0402-0.22UF,16V,10%,X7R,A3A!C6B12!//jf4cfls225.pdx.intel.com/apd_proj/ppg_lib/epg_masterlib/logical/mstr_discrete/cap/chips/chips.prt!CAP!CAP_0402-0.22UF,16V,10%,X7R,A36096-155!CAP_0402!!!F3901!!OCP_STEERING!!
S!@baseboard_fab2_lib.baseboard_fab2(sch_1):page105_i181@mstr_discrete.cap(chips)!CAP_0402-0.22UF,16V,10%,X7R,A3A!C6B14!//jf4cfls225.pdx.intel.com/apd_proj/ppg_lib/epg_masterlib/logical/mstr_discrete/cap/chips/chips.prt!CAP!CAP_0402-0.22UF,16V,10%,X7R,A36096-155!CAP_0402!!!F3899!!OCP_STEERING!!
S!@baseboard_fab2_lib.baseboard_fab2(sch_1):page105_i189@mstr_discrete.cap(chips)!CAP_0402-0.22UF,16V,10%,X7R,A3A!C6B13!//jf4cfls225.pdx.intel.com/apd_proj/ppg_lib/epg_masterlib/logical/mstr_discrete/cap/chips/chips.prt!CAP!CAP_0402-0.22UF,16V,10%,X7R,A36096-155!CAP_0402!!!F3900!!OCP_STEERING!!
S!@baseboard_fab2_lib.baseboard_fab2(sch_1):page105_i163@mstr_discrete.cap(chips)!CAP_0402-0.22UF,16V,10%,X7R,A3A!C6B15!//jf4cfls225.pdx.intel.com/apd_proj/ppg_lib/epg_masterlib/logical/mstr_discrete/cap/chips/chips.prt!CAP!CAP_0402-0.22UF,16V,10%,X7R,A36096-155!CAP_0402!!!F3898!!OCP_STEERING!!
S!@baseboard_fab2_lib.baseboard_fab2(sch_1):page105_i180@mstr_discrete.cap(chips)!CAP_0402-0.22UF,16V,10%,X7R,A3A!C6B16!//jf4cfls225.pdx.intel.com/apd_proj/ppg_lib/epg_masterlib/logical/mstr_discrete/cap/chips/chips.prt!CAP!CAP_0402-0.22UF,16V,10%,X7R,A36096-155!CAP_0402!!!F3897!!OCP_STEERING!!
S!@baseboard_fab2_lib.baseboard_fab2(sch_1):page105_i175@mstr_discrete.cap(chips)!CAP_0402-0.22UF,16V,10%,X7R,A3A!C6B17!//jf4cfls225.pdx.intel.com/apd_proj/ppg_lib/epg_masterlib/logical/mstr_discrete/cap/chips/chips.prt!CAP!CAP_0402-0.22UF,16V,10%,X7R,A36096-155!CAP_0402!!!F3896!!OCP_STEERING!!
S!@baseboard_fab2_lib.baseboard_fab2(sch_1):page105_i153@mstr_discrete.cap(chips)!CAP_0402-0.22UF,16V,10%,X7R,A3A!C6B18!//jf4cfls225.pdx.intel.com/apd_proj/ppg_lib/epg_masterlib/logical/mstr_discrete/cap/chips/chips.prt!CAP!CAP_0402-0.22UF,16V,10%,X7R,A36096-155!CAP_0402!!!F3895!!OCP_STEERING!!
S!@baseboard_fab2_lib.baseboard_fab2(sch_1):page105_i160@mstr_discrete.cap(chips)!CAP_0402-0.22UF,16V,10%,X7R,A3A!C6B19!//jf4cfls225.pdx.intel.com/apd_proj/ppg_lib/epg_masterlib/logical/mstr_discrete/cap/chips/chips.prt!CAP!CAP_0402-0.22UF,16V,10%,X7R,A36096-155!CAP_0402!!!F3894!!OCP_STEERING!!
S!@baseboard_fab2_lib.baseboard_fab2(sch_1):page105_i173@mstr_discrete.cap(chips)!CAP_0402-0.22UF,16V,10%,X7R,A3A!C6B20!//jf4cfls225.pdx.intel.com/apd_proj/ppg_lib/epg_masterlib/logical/mstr_discrete/cap/chips/chips.prt!CAP!CAP_0402-0.22UF,16V,10%,X7R,A36096-155!CAP_0402!!!F3893!!OCP_STEERING!!
S!@baseboard_fab2_lib.baseboard_fab2(sch_1):page106_i55@mstr_discrete.cap(chips)!CAP_0402-0.22UF,16V,10%,X7R,A3A!C1R8!//jf4cfls225.pdx.intel.com/apd_proj/ppg_lib/epg_masterlib/logical/mstr_discrete/cap/chips/chips.prt!CAP!CAP_0402-0.22UF,16V,10%,X7R,A36096-155!CAP_0402!!!F3989!!PCIE_STEERING!!
S!@baseboard_fab2_lib.baseboard_fab2(sch_1):page106_i70@mstr_discrete.cap(chips)!CAP_0402-0.22UF,16V,10%,X7R,A3A!C1R7!//jf4cfls225.pdx.intel.com/apd_proj/ppg_lib/epg_masterlib/logical/mstr_discrete/cap/chips/chips.prt!CAP!CAP_0402-0.22UF,16V,10%,X7R,A36096-155!CAP_0402!!!F3990!!PCIE_STEERING!!
S!@baseboard_fab2_lib.baseboard_fab2(sch_1):page106_i40@mstr_discrete.cap(chips)!CAP_0402-0.22UF,16V,10%,X7R,A3A!C1R6!//jf4cfls225.pdx.intel.com/apd_proj/ppg_lib/epg_masterlib/logical/mstr_discrete/cap/chips/chips.prt!CAP!CAP_0402-0.22UF,16V,10%,X7R,A36096-155!CAP_0402!!!F3991!!PCIE_STEERING!!
S!@baseboard_fab2_lib.baseboard_fab2(sch_1):page106_i59@mstr_discrete.cap(chips)!CAP_0402-0.22UF,16V,10%,X7R,A3A!C1R5!//jf4cfls225.pdx.intel.com/apd_proj/ppg_lib/epg_masterlib/logical/mstr_discrete/cap/chips/chips.prt!CAP!CAP_0402-0.22UF,16V,10%,X7R,A36096-155!CAP_0402!!!F3992!!PCIE_STEERING!!
S!@baseboard_fab2_lib.baseboard_fab2(sch_1):page106_i26@mstr_discrete.cap(chips)!CAP_0402-0.22UF,16V,10%,X7R,A3A!C1R4!//jf4cfls225.pdx.intel.com/apd_proj/ppg_lib/epg_masterlib/logical/mstr_discrete/cap/chips/chips.prt!CAP!CAP_0402-0.22UF,16V,10%,X7R,A36096-155!CAP_0402!!!F3993!!PCIE_STEERING!!
S!@baseboard_fab2_lib.baseboard_fab2(sch_1):page106_i37@mstr_discrete.cap(chips)!CAP_0402-0.22UF,16V,10%,X7R,A3A!C1R3!//jf4cfls225.pdx.intel.com/apd_proj/ppg_lib/epg_masterlib/logical/mstr_discrete/cap/chips/chips.prt!CAP!CAP_0402-0.22UF,16V,10%,X7R,A36096-155!CAP_0402!!!F3994!!PCIE_STEERING!!
S!@baseboard_fab2_lib.baseboard_fab2(sch_1):page106_i142@mstr_discrete.cap(chips)!CAP_0402-0.22UF,16V,10%,X7R,A3A!C2R10!//jf4cfls225.pdx.intel.com/apd_proj/ppg_lib/epg_masterlib/logical/mstr_discrete/cap/chips/chips.prt!CAP!CAP_0402-0.22UF,16V,10%,X7R,A36096-155!CAP_0402!!!F3978!!PCIE_STEERING!!
S!@baseboard_fab2_lib.baseboard_fab2(sch_1):page106_i147@mstr_discrete.cap(chips)!CAP_0402-0.22UF,16V,10%,X7R,A3A!C2R9!//jf4cfls225.pdx.intel.com/apd_proj/ppg_lib/epg_masterlib/logical/mstr_discrete/cap/chips/chips.prt!CAP!CAP_0402-0.22UF,16V,10%,X7R,A36096-155!CAP_0402!!!F3979!!PCIE_STEERING!!
S!@baseboard_fab2_lib.baseboard_fab2(sch_1):page106_i141@mstr_discrete.cap(chips)!CAP_0402-0.22UF,16V,10%,X7R,A3A!C2R8!//jf4cfls225.pdx.intel.com/apd_proj/ppg_lib/epg_masterlib/logical/mstr_discrete/cap/chips/chips.prt!CAP!CAP_0402-0.22UF,16V,10%,X7R,A36096-155!CAP_0402!!!F3980!!PCIE_STEERING!!
S!@baseboard_fab2_lib.baseboard_fab2(sch_1):page106_i123@mstr_discrete.cap(chips)!CAP_0402-0.22UF,16V,10%,X7R,A3A!C2R7!//jf4cfls225.pdx.intel.com/apd_proj/ppg_lib/epg_masterlib/logical/mstr_discrete/cap/chips/chips.prt!CAP!CAP_0402-0.22UF,16V,10%,X7R,A36096-155!CAP_0402!!!F3981!!PCIE_STEERING!!
S!@baseboard_fab2_lib.baseboard_fab2(sch_1):page106_i130@mstr_discrete.cap(chips)!CAP_0402-0.22UF,16V,10%,X7R,A3A!C2R14!//jf4cfls225.pdx.intel.com/apd_proj/ppg_lib/epg_masterlib/logical/mstr_discrete/cap/chips/chips.prt!CAP!CAP_0402-0.22UF,16V,10%,X7R,A36096-155!CAP_0402!!!F3985!!PCIE_STEERING!!
S!@baseboard_fab2_lib.baseboard_fab2(sch_1):page106_i10@mstr_discrete.cap(chips)!CAP_0402-0.22UF,16V,10%,X7R,A3A!C1R2!//jf4cfls225.pdx.intel.com/apd_proj/ppg_lib/epg_masterlib/logical/mstr_discrete/cap/chips/chips.prt!CAP!CAP_0402-0.22UF,16V,10%,X7R,A36096-155!CAP_0402!!!F3995!!PCIE_STEERING!!
S!@baseboard_fab2_lib.baseboard_fab2(sch_1):page106_i29@mstr_discrete.cap(chips)!CAP_0402-0.22UF,16V,10%,X7R,A3A!C1R1!//jf4cfls225.pdx.intel.com/apd_proj/ppg_lib/epg_masterlib/logical/mstr_discrete/cap/chips/chips.prt!CAP!CAP_0402-0.22UF,16V,10%,X7R,A36096-155!CAP_0402!!!F3996!!PCIE_STEERING!!
S!@baseboard_fab2_lib.baseboard_fab2(sch_1):page106_i137@mstr_discrete.cap(chips)!CAP_0402-0.22UF,16V,10%,X7R,A3A!C2R13!//jf4cfls225.pdx.intel.com/apd_proj/ppg_lib/epg_masterlib/logical/mstr_discrete/cap/chips/chips.prt!CAP!CAP_0402-0.22UF,16V,10%,X7R,A36096-155!CAP_0402!!!F3986!!PCIE_STEERING!!
S!@baseboard_fab2_lib.baseboard_fab2(sch_1):page106_i128@mstr_discrete.cap(chips)!CAP_0402-0.22UF,16V,10%,X7R,A3A!C1R10!//jf4cfls225.pdx.intel.com/apd_proj/ppg_lib/epg_masterlib/logical/mstr_discrete/cap/chips/chips.prt!CAP!CAP_0402-0.22UF,16V,10%,X7R,A36096-155!CAP_0402!!!F3987!!PCIE_STEERING!!
S!@baseboard_fab2_lib.baseboard_fab2(sch_1):page106_i134@mstr_discrete.cap(chips)!CAP_0402-0.22UF,16V,10%,X7R,A3A!C1R9!//jf4cfls225.pdx.intel.com/apd_proj/ppg_lib/epg_masterlib/logical/mstr_discrete/cap/chips/chips.prt!CAP!CAP_0402-0.22UF,16V,10%,X7R,A36096-155!CAP_0402!!!F3988!!PCIE_STEERING!!
S!@baseboard_fab2_lib.baseboard_fab2(sch_1):page106_i109@mstr_discrete.cap(chips)!CAP_0402-0.22UF,16V,10%,X7R,A3A!C1M6!//jf4cfls225.pdx.intel.com/apd_proj/ppg_lib/epg_masterlib/logical/mstr_discrete/cap/chips/chips.prt!CAP!CAP_0402-0.22UF,16V,10%,X7R,A36096-155!CAP_0402!!!F4010!!PCIE_STEERING!!
S!@baseboard_fab2_lib.baseboard_fab2(sch_1):page106_i122@mstr_discrete.cap(chips)!CAP_0402-0.22UF,16V,10%,X7R,A3A!C1M7!//jf4cfls225.pdx.intel.com/apd_proj/ppg_lib/epg_masterlib/logical/mstr_discrete/cap/chips/chips.prt!CAP!CAP_0402-0.22UF,16V,10%,X7R,A36096-155!CAP_0402!!!F4009!!PCIE_STEERING!!
S!@baseboard_fab2_lib.baseboard_fab2(sch_1):page106_i105@mstr_discrete.cap(chips)!CAP_0402-0.22UF,16V,10%,X7R,A3A!C1M8!//jf4cfls225.pdx.intel.com/apd_proj/ppg_lib/epg_masterlib/logical/mstr_discrete/cap/chips/chips.prt!CAP!CAP_0402-0.22UF,16V,10%,X7R,A36096-155!CAP_0402!!!F4008!!PCIE_STEERING!!
S!@baseboard_fab2_lib.baseboard_fab2(sch_1):page106_i114@mstr_discrete.cap(chips)!CAP_0402-0.22UF,16V,10%,X7R,A3A!C1M9!//jf4cfls225.pdx.intel.com/apd_proj/ppg_lib/epg_masterlib/logical/mstr_discrete/cap/chips/chips.prt!CAP!CAP_0402-0.22UF,16V,10%,X7R,A36096-155!CAP_0402!!!F4007!!PCIE_STEERING!!
S!@baseboard_fab2_lib.baseboard_fab2(sch_1):page106_i102@mstr_discrete.cap(chips)!CAP_0402-0.22UF,16V,10%,X7R,A3A!C1M10!//jf4cfls225.pdx.intel.com/apd_proj/ppg_lib/epg_masterlib/logical/mstr_discrete/cap/chips/chips.prt!CAP!CAP_0402-0.22UF,16V,10%,X7R,A36096-155!CAP_0402!!!F4006!!PCIE_STEERING!!
S!@baseboard_fab2_lib.baseboard_fab2(sch_1):page106_i117@mstr_discrete.cap(chips)!CAP_0402-0.22UF,16V,10%,X7R,A3A!C1M11!//jf4cfls225.pdx.intel.com/apd_proj/ppg_lib/epg_masterlib/logical/mstr_discrete/cap/chips/chips.prt!CAP!CAP_0402-0.22UF,16V,10%,X7R,A36096-155!CAP_0402!!!F4005!!PCIE_STEERING!!
S!@baseboard_fab2_lib.baseboard_fab2(sch_1):page106_i100@mstr_discrete.cap(chips)!CAP_0402-0.22UF,16V,10%,X7R,A3A!C1M12!//jf4cfls225.pdx.intel.com/apd_proj/ppg_lib/epg_masterlib/logical/mstr_discrete/cap/chips/chips.prt!CAP!CAP_0402-0.22UF,16V,10%,X7R,A36096-155!CAP_0402!!!F4004!!PCIE_STEERING!!
S!@baseboard_fab2_lib.baseboard_fab2(sch_1):page106_i111@mstr_discrete.cap(chips)!CAP_0402-0.22UF,16V,10%,X7R,A3A!C1M13!//jf4cfls225.pdx.intel.com/apd_proj/ppg_lib/epg_masterlib/logical/mstr_discrete/cap/chips/chips.prt!CAP!CAP_0402-0.22UF,16V,10%,X7R,A36096-155!CAP_0402!!!F4003!!PCIE_STEERING!!
S!@baseboard_fab2_lib.baseboard_fab2(sch_1):page106_i85@mstr_discrete.cap(chips)!CAP_0402-0.22UF,16V,10%,X7R,A3A!C1M14!//jf4cfls225.pdx.intel.com/apd_proj/ppg_lib/epg_masterlib/logical/mstr_discrete/cap/chips/chips.prt!CAP!CAP_0402-0.22UF,16V,10%,X7R,A36096-155!CAP_0402!!!F4002!!PCIE_STEERING!!
S!@baseboard_fab2_lib.baseboard_fab2(sch_1):page106_i95@mstr_discrete.cap(chips)!CAP_0402-0.22UF,16V,10%,X7R,A3A!C1M15!//jf4cfls225.pdx.intel.com/apd_proj/ppg_lib/epg_masterlib/logical/mstr_discrete/cap/chips/chips.prt!CAP!CAP_0402-0.22UF,16V,10%,X7R,A36096-155!CAP_0402!!!F4001!!PCIE_STEERING!!
S!@baseboard_fab2_lib.baseboard_fab2(sch_1):page106_i82@mstr_discrete.cap(chips)!CAP_0402-0.22UF,16V,10%,X7R,A3A!C1M16!//jf4cfls225.pdx.intel.com/apd_proj/ppg_lib/epg_masterlib/logical/mstr_discrete/cap/chips/chips.prt!CAP!CAP_0402-0.22UF,16V,10%,X7R,A36096-155!CAP_0402!!!F4000!!PCIE_STEERING!!
S!@baseboard_fab2_lib.baseboard_fab2(sch_1):page106_i92@mstr_discrete.cap(chips)!CAP_0402-0.22UF,16V,10%,X7R,A3A!C1M17!//jf4cfls225.pdx.intel.com/apd_proj/ppg_lib/epg_masterlib/logical/mstr_discrete/cap/chips/chips.prt!CAP!CAP_0402-0.22UF,16V,10%,X7R,A36096-155!CAP_0402!!!F3999!!PCIE_STEERING!!
S!@baseboard_fab2_lib.baseboard_fab2(sch_1):page106_i78@mstr_discrete.cap(chips)!CAP_0402-0.22UF,16V,10%,X7R,A3A!C1M18!//jf4cfls225.pdx.intel.com/apd_proj/ppg_lib/epg_masterlib/logical/mstr_discrete/cap/chips/chips.prt!CAP!CAP_0402-0.22UF,16V,10%,X7R,A36096-155!CAP_0402!!!F3998!!PCIE_STEERING!!
S!@baseboard_fab2_lib.baseboard_fab2(sch_1):page106_i90@mstr_discrete.cap(chips)!CAP_0402-0.22UF,16V,10%,X7R,A3A!C1M19!//jf4cfls225.pdx.intel.com/apd_proj/ppg_lib/epg_masterlib/logical/mstr_discrete/cap/chips/chips.prt!CAP!CAP_0402-0.22UF,16V,10%,X7R,A36096-155!CAP_0402!!!F3997!!PCIE_STEERING!!
S!@baseboard_fab2_lib.baseboard_fab2(sch_1):page106_i76@mstr_discrete.cap(chips)!CAP_0402-0.22UF,16V,10%,X7R,A3A!C2M14!//jf4cfls225.pdx.intel.com/apd_proj/ppg_lib/epg_masterlib/logical/mstr_discrete/cap/chips/chips.prt!CAP!CAP_0402-0.22UF,16V,10%,X7R,A36096-155!CAP_0402!!!F3983!!PCIE_STEERING!!
S!@baseboard_fab2_lib.baseboard_fab2(sch_1):page106_i86@mstr_discrete.cap(chips)!CAP_0402-0.22UF,16V,10%,X7R,A3A!C2M15!//jf4cfls225.pdx.intel.com/apd_proj/ppg_lib/epg_masterlib/logical/mstr_discrete/cap/chips/chips.prt!CAP!CAP_0402-0.22UF,16V,10%,X7R,A36096-155!CAP_0402!!!F3982!!PCIE_STEERING!!
S!@baseboard_fab2_lib.baseboard_fab2(sch_1):page105_i51@mstr_discrete.cap(chips)!CAP_0402-0.22UF,16V,10%,X7R,A3A!C7G21!//jf4cfls225.pdx.intel.com/apd_proj/ppg_lib/epg_masterlib/logical/mstr_discrete/cap/chips/chips.prt!CAP!CAP_0402-0.22UF,16V,10%,X7R,A36096-155!CAP_0402!!!F3864!!OCP_STEERING!!
S!@baseboard_fab2_lib.baseboard_fab2(sch_1):page105_i37@mstr_discrete.cap(chips)!CAP_0402-0.22UF,16V,10%,X7R,A3A!C7G22!//jf4cfls225.pdx.intel.com/apd_proj/ppg_lib/epg_masterlib/logical/mstr_discrete/cap/chips/chips.prt!CAP!CAP_0402-0.22UF,16V,10%,X7R,A36096-155!CAP_0402!!!F3863!!OCP_STEERING!!
S!@baseboard_fab2_lib.baseboard_fab2(sch_1):page105_i52@mstr_discrete.cap(chips)!CAP_0402-0.22UF,16V,10%,X7R,A3A!C7G23!//jf4cfls225.pdx.intel.com/apd_proj/ppg_lib/epg_masterlib/logical/mstr_discrete/cap/chips/chips.prt!CAP!CAP_0402-0.22UF,16V,10%,X7R,A36096-155!CAP_0402!!!F3862!!OCP_STEERING!!
S!@baseboard_fab2_lib.baseboard_fab2(sch_1):page105_i1@mstr_discrete.cap(chips)!CAP_0402-0.22UF,16V,10%,X7R,A3A!C7G24!//jf4cfls225.pdx.intel.com/apd_proj/ppg_lib/epg_masterlib/logical/mstr_discrete/cap/chips/chips.prt!CAP!CAP_0402-0.22UF,16V,10%,X7R,A36096-155!CAP_0402!!!F3861!!OCP_STEERING!!
S!@baseboard_fab2_lib.baseboard_fab2(sch_1):page105_i69@mstr_discrete.cap(chips)!CAP_0402-0.22UF,16V,10%,X7R,A3A!C7G25!//jf4cfls225.pdx.intel.com/apd_proj/ppg_lib/epg_masterlib/logical/mstr_discrete/cap/chips/chips.prt!CAP!CAP_0402-0.22UF,16V,10%,X7R,A36096-155!CAP_0402!!!F3860!!OCP_STEERING!!
S!@baseboard_fab2_lib.baseboard_fab2(sch_1):page105_i55@mstr_discrete.cap(chips)!CAP_0402-0.22UF,16V,10%,X7R,A3A!C7G26!//jf4cfls225.pdx.intel.com/apd_proj/ppg_lib/epg_masterlib/logical/mstr_discrete/cap/chips/chips.prt!CAP!CAP_0402-0.22UF,16V,10%,X7R,A36096-155!CAP_0402!!!F3859!!OCP_STEERING!!
S!@baseboard_fab2_lib.baseboard_fab2(sch_1):page105_i70@mstr_discrete.cap(chips)!CAP_0402-0.22UF,16V,10%,X7R,A3A!C8G1!//jf4cfls225.pdx.intel.com/apd_proj/ppg_lib/epg_masterlib/logical/mstr_discrete/cap/chips/chips.prt!CAP!CAP_0402-0.22UF,16V,10%,X7R,A36096-155!CAP_0402!!!F3854!!OCP_STEERING!!
S!@baseboard_fab2_lib.baseboard_fab2(sch_1):page105_i58@mstr_discrete.cap(chips)!CAP_0402-0.22UF,16V,10%,X7R,A3A!C8G2!//jf4cfls225.pdx.intel.com/apd_proj/ppg_lib/epg_masterlib/logical/mstr_discrete/cap/chips/chips.prt!CAP!CAP_0402-0.22UF,16V,10%,X7R,A36096-155!CAP_0402!!!F3853!!OCP_STEERING!!
S!@baseboard_fab2_lib.baseboard_fab2(sch_1):page105_i71@mstr_discrete.cap(chips)!CAP_0402-0.22UF,16V,10%,X7R,A3A!C8G3!//jf4cfls225.pdx.intel.com/apd_proj/ppg_lib/epg_masterlib/logical/mstr_discrete/cap/chips/chips.prt!CAP!CAP_0402-0.22UF,16V,10%,X7R,A36096-155!CAP_0402!!!F3852!!OCP_STEERING!!
S!@baseboard_fab2_lib.baseboard_fab2(sch_1):page105_i56@mstr_discrete.cap(chips)!CAP_0402-0.22UF,16V,10%,X7R,A3A!C8G4!//jf4cfls225.pdx.intel.com/apd_proj/ppg_lib/epg_masterlib/logical/mstr_discrete/cap/chips/chips.prt!CAP!CAP_0402-0.22UF,16V,10%,X7R,A36096-155!CAP_0402!!!F3851!!OCP_STEERING!!
S!@baseboard_fab2_lib.baseboard_fab2(sch_1):page105_i75@mstr_discrete.cap(chips)!CAP_0402-0.22UF,16V,10%,X7R,A3A!C8G5!//jf4cfls225.pdx.intel.com/apd_proj/ppg_lib/epg_masterlib/logical/mstr_discrete/cap/chips/chips.prt!CAP!CAP_0402-0.22UF,16V,10%,X7R,A36096-155!CAP_0402!!!F3850!!OCP_STEERING!!
S!@baseboard_fab2_lib.baseboard_fab2(sch_1):page105_i61@mstr_discrete.cap(chips)!CAP_0402-0.22UF,16V,10%,X7R,A3A!C8G6!//jf4cfls225.pdx.intel.com/apd_proj/ppg_lib/epg_masterlib/logical/mstr_discrete/cap/chips/chips.prt!CAP!CAP_0402-0.22UF,16V,10%,X7R,A36096-155!CAP_0402!!!F3849!!OCP_STEERING!!
S!@baseboard_fab2_lib.baseboard_fab2(sch_1):page105_i76@mstr_discrete.cap(chips)!CAP_0402-0.22UF,16V,10%,X7R,A3A!C8G8!//jf4cfls225.pdx.intel.com/apd_proj/ppg_lib/epg_masterlib/logical/mstr_discrete/cap/chips/chips.prt!CAP!CAP_0402-0.22UF,16V,10%,X7R,A36096-155!CAP_0402!!!F3847!!OCP_STEERING!!
S!@baseboard_fab2_lib.baseboard_fab2(sch_1):page105_i62@mstr_discrete.cap(chips)!CAP_0402-0.22UF,16V,10%,X7R,A3A!C8G7!//jf4cfls225.pdx.intel.com/apd_proj/ppg_lib/epg_masterlib/logical/mstr_discrete/cap/chips/chips.prt!CAP!CAP_0402-0.22UF,16V,10%,X7R,A36096-155!CAP_0402!!!F3848!!OCP_STEERING!!
S!@baseboard_fab2_lib.baseboard_fab2(sch_1):page105_i93@mstr_discrete.cap(chips)!CAP_0402-0.22UF,16V,10%,X7R,A3A!C8G9!//jf4cfls225.pdx.intel.com/apd_proj/ppg_lib/epg_masterlib/logical/mstr_discrete/cap/chips/chips.prt!CAP!CAP_0402-0.22UF,16V,10%,X7R,A36096-155!CAP_0402!!!F3846!!OCP_STEERING!!
S!@baseboard_fab2_lib.baseboard_fab2(sch_1):page105_i96@mstr_discrete.cap(chips)!CAP_0402-0.22UF,16V,10%,X7R,A3A!C8G10!//jf4cfls225.pdx.intel.com/apd_proj/ppg_lib/epg_masterlib/logical/mstr_discrete/cap/chips/chips.prt!CAP!CAP_0402-0.22UF,16V,10%,X7R,A36096-155!CAP_0402!!!F3845!!OCP_STEERING!!
S!@baseboard_fab2_lib.baseboard_fab2(sch_1):page105_i20@mstr_discrete.cap(chips)!CAP_0402-0.22UF,16V,10%,X7R,A3A!C7G5!//jf4cfls225.pdx.intel.com/apd_proj/ppg_lib/epg_masterlib/logical/mstr_discrete/cap/chips/chips.prt!CAP!CAP_0402-0.22UF,16V,10%,X7R,A36096-155!CAP_0402!!!F3880!!OCP_STEERING!!
S!@baseboard_fab2_lib.baseboard_fab2(sch_1):page105_i7@mstr_discrete.cap(chips)!CAP_0402-0.22UF,16V,10%,X7R,A3A!C7G7!//jf4cfls225.pdx.intel.com/apd_proj/ppg_lib/epg_masterlib/logical/mstr_discrete/cap/chips/chips.prt!CAP!CAP_0402-0.22UF,16V,10%,X7R,A36096-155!CAP_0402!!!F3878!!OCP_STEERING!!
S!@baseboard_fab2_lib.baseboard_fab2(sch_1):page105_i21@mstr_discrete.cap(chips)!CAP_0402-0.22UF,16V,10%,X7R,A3A!C7G9!//jf4cfls225.pdx.intel.com/apd_proj/ppg_lib/epg_masterlib/logical/mstr_discrete/cap/chips/chips.prt!CAP!CAP_0402-0.22UF,16V,10%,X7R,A36096-155!CAP_0402!!!F3876!!OCP_STEERING!!
S!@baseboard_fab2_lib.baseboard_fab2(sch_1):page105_i8@mstr_discrete.cap(chips)!CAP_0402-0.22UF,16V,10%,X7R,A3A!C7G10!//jf4cfls225.pdx.intel.com/apd_proj/ppg_lib/epg_masterlib/logical/mstr_discrete/cap/chips/chips.prt!CAP!CAP_0402-0.22UF,16V,10%,X7R,A36096-155!CAP_0402!!!F3875!!OCP_STEERING!!
S!@baseboard_fab2_lib.baseboard_fab2(sch_1):page105_i27@mstr_discrete.cap(chips)!CAP_0402-0.22UF,16V,10%,X7R,A3A!C7G11!//jf4cfls225.pdx.intel.com/apd_proj/ppg_lib/epg_masterlib/logical/mstr_discrete/cap/chips/chips.prt!CAP!CAP_0402-0.22UF,16V,10%,X7R,A36096-155!CAP_0402!!!F3874!!OCP_STEERING!!
S!@baseboard_fab2_lib.baseboard_fab2(sch_1):page105_i12@mstr_discrete.cap(chips)!CAP_0402-0.22UF,16V,10%,X7R,A3A!C7G12!//jf4cfls225.pdx.intel.com/apd_proj/ppg_lib/epg_masterlib/logical/mstr_discrete/cap/chips/chips.prt!CAP!CAP_0402-0.22UF,16V,10%,X7R,A36096-155!CAP_0402!!!F3873!!OCP_STEERING!!
S!@baseboard_fab2_lib.baseboard_fab2(sch_1):page105_i28@mstr_discrete.cap(chips)!CAP_0402-0.22UF,16V,10%,X7R,A3A!C7G14!//jf4cfls225.pdx.intel.com/apd_proj/ppg_lib/epg_masterlib/logical/mstr_discrete/cap/chips/chips.prt!CAP!CAP_0402-0.22UF,16V,10%,X7R,A36096-155!CAP_0402!!!F3871!!OCP_STEERING!!
S!@baseboard_fab2_lib.baseboard_fab2(sch_1):page105_i13@mstr_discrete.cap(chips)!CAP_0402-0.22UF,16V,10%,X7R,A3A!C7G13!//jf4cfls225.pdx.intel.com/apd_proj/ppg_lib/epg_masterlib/logical/mstr_discrete/cap/chips/chips.prt!CAP!CAP_0402-0.22UF,16V,10%,X7R,A36096-155!CAP_0402!!!F3872!!OCP_STEERING!!
S!@baseboard_fab2_lib.baseboard_fab2(sch_1):page105_i45@mstr_discrete.cap(chips)!CAP_0402-0.22UF,16V,10%,X7R,A3A!C7G15!//jf4cfls225.pdx.intel.com/apd_proj/ppg_lib/epg_masterlib/logical/mstr_discrete/cap/chips/chips.prt!CAP!CAP_0402-0.22UF,16V,10%,X7R,A36096-155!CAP_0402!!!F3870!!OCP_STEERING!!
S!@baseboard_fab2_lib.baseboard_fab2(sch_1):page105_i31@mstr_discrete.cap(chips)!CAP_0402-0.22UF,16V,10%,X7R,A3A!C7G16!//jf4cfls225.pdx.intel.com/apd_proj/ppg_lib/epg_masterlib/logical/mstr_discrete/cap/chips/chips.prt!CAP!CAP_0402-0.22UF,16V,10%,X7R,A36096-155!CAP_0402!!!F3869!!OCP_STEERING!!
S!@baseboard_fab2_lib.baseboard_fab2(sch_1):page105_i44@mstr_discrete.cap(chips)!CAP_0402-0.22UF,16V,10%,X7R,A3A!C7G17!//jf4cfls225.pdx.intel.com/apd_proj/ppg_lib/epg_masterlib/logical/mstr_discrete/cap/chips/chips.prt!CAP!CAP_0402-0.22UF,16V,10%,X7R,A36096-155!CAP_0402!!!F3868!!OCP_STEERING!!
S!@baseboard_fab2_lib.baseboard_fab2(sch_1):page105_i32@mstr_discrete.cap(chips)!CAP_0402-0.22UF,16V,10%,X7R,A3A!C7G18!//jf4cfls225.pdx.intel.com/apd_proj/ppg_lib/epg_masterlib/logical/mstr_discrete/cap/chips/chips.prt!CAP!CAP_0402-0.22UF,16V,10%,X7R,A36096-155!CAP_0402!!!F3867!!OCP_STEERING!!
S!@baseboard_fab2_lib.baseboard_fab2(sch_1):page105_i46@mstr_discrete.cap(chips)!CAP_0402-0.22UF,16V,10%,X7R,A3A!C7G19!//jf4cfls225.pdx.intel.com/apd_proj/ppg_lib/epg_masterlib/logical/mstr_discrete/cap/chips/chips.prt!CAP!CAP_0402-0.22UF,16V,10%,X7R,A36096-155!CAP_0402!!!F3866!!OCP_STEERING!!
S!@baseboard_fab2_lib.baseboard_fab2(sch_1):page105_i34@mstr_discrete.cap(chips)!CAP_0402-0.22UF,16V,10%,X7R,A3A!C7G20!//jf4cfls225.pdx.intel.com/apd_proj/ppg_lib/epg_masterlib/logical/mstr_discrete/cap/chips/chips.prt!CAP!CAP_0402-0.22UF,16V,10%,X7R,A36096-155!CAP_0402!!!F3865!!OCP_STEERING!!
S!@baseboard_fab2_lib.baseboard_fab2(sch_1):page105_i6@mstr_discrete.cap(chips)!CAP_0402-0.22UF,16V,10%,X7R,A3A!C7G6!//jf4cfls225.pdx.intel.com/apd_proj/ppg_lib/epg_masterlib/logical/mstr_discrete/cap/chips/chips.prt!CAP!CAP_0402-0.22UF,16V,10%,X7R,A36096-155!CAP_0402!!!F3879!!OCP_STEERING!!
S!@baseboard_fab2_lib.baseboard_fab2(sch_1):page105_i22@mstr_discrete.cap(chips)!CAP_0402-0.22UF,16V,10%,X7R,A3A!C7G8!//jf4cfls225.pdx.intel.com/apd_proj/ppg_lib/epg_masterlib/logical/mstr_discrete/cap/chips/chips.prt!CAP!CAP_0402-0.22UF,16V,10%,X7R,A36096-155!CAP_0402!!!F3877!!OCP_STEERING!!
S!@baseboard_fab2_lib.baseboard_fab2(sch_1):page182_i12@mstr_discrete.cap(chips)!CAP_0402-0.22UF,16V,10%,X7R,A3A!C9N17!//jf4cfls225.pdx.intel.com/apd_proj/ppg_lib/epg_masterlib/logical/mstr_discrete/cap/chips/chips.prt!CAP!CAP_0402-0.22UF,16V,10%,X7R,A36096-155!CAP_0402!!!F3830!!IO_SLOT!!
S!@baseboard_fab2_lib.baseboard_fab2(sch_1):page182_i16@mstr_discrete.cap(chips)!CAP_0402-0.22UF,16V,10%,X7R,A3A!C9N12!//jf4cfls225.pdx.intel.com/apd_proj/ppg_lib/epg_masterlib/logical/mstr_discrete/cap/chips/chips.prt!CAP!CAP_0402-0.22UF,16V,10%,X7R,A36096-155!CAP_0402!!!F3834!!IO_SLOT!!
S!@baseboard_fab2_lib.baseboard_fab2(sch_1):page182_i15@mstr_discrete.cap(chips)!CAP_0402-0.22UF,16V,10%,X7R,A3A!C9N2!//jf4cfls225.pdx.intel.com/apd_proj/ppg_lib/epg_masterlib/logical/mstr_discrete/cap/chips/chips.prt!CAP!CAP_0402-0.22UF,16V,10%,X7R,A36096-155!CAP_0402!!!F3843!!IO_SLOT!!
S!@baseboard_fab2_lib.baseboard_fab2(sch_1):page182_i53@mstr_discrete.cap(chips)!CAP_0402-0.22UF,16V,10%,X7R,A3A!C9N10!//jf4cfls225.pdx.intel.com/apd_proj/ppg_lib/epg_masterlib/logical/mstr_discrete/cap/chips/chips.prt!CAP!CAP_0402-0.22UF,16V,10%,X7R,A36096-155!CAP_0402!!!F3835!!IO_SLOT!!
S!@baseboard_fab2_lib.baseboard_fab2(sch_1):page182_i54@mstr_discrete.cap(chips)!CAP_0402-0.22UF,16V,10%,X7R,A3A!C9N7!//jf4cfls225.pdx.intel.com/apd_proj/ppg_lib/epg_masterlib/logical/mstr_discrete/cap/chips/chips.prt!CAP!CAP_0402-0.22UF,16V,10%,X7R,A36096-155!CAP_0402!!!F3838!!IO_SLOT!!
S!@baseboard_fab2_lib.baseboard_fab2(sch_1):page182_i55@mstr_discrete.cap(chips)!CAP_0402-0.22UF,16V,10%,X7R,A3A!C9N4!//jf4cfls225.pdx.intel.com/apd_proj/ppg_lib/epg_masterlib/logical/mstr_discrete/cap/chips/chips.prt!CAP!CAP_0402-0.22UF,16V,10%,X7R,A36096-155!CAP_0402!!!F3841!!IO_SLOT!!
S!@baseboard_fab2_lib.baseboard_fab2(sch_1):page182_i56@mstr_discrete.cap(chips)!CAP_0402-0.22UF,16V,10%,X7R,A3A!C9N14!//jf4cfls225.pdx.intel.com/apd_proj/ppg_lib/epg_masterlib/logical/mstr_discrete/cap/chips/chips.prt!CAP!CAP_0402-0.22UF,16V,10%,X7R,A36096-155!CAP_0402!!!F3833!!IO_SLOT!!
S!@baseboard_fab2_lib.baseboard_fab2(sch_1):page182_i83@mstr_discrete.cap(chips)!CAP_0402-0.22UF,16V,10%,X7R,A3A!C9N5!//jf4cfls225.pdx.intel.com/apd_proj/ppg_lib/epg_masterlib/logical/mstr_discrete/cap/chips/chips.prt!CAP!CAP_0402-0.22UF,16V,10%,X7R,A36096-155!CAP_0402!!!F3840!!IO_SLOT!!
S!@baseboard_fab2_lib.baseboard_fab2(sch_1):page182_i50@mstr_discrete.cap(chips)!CAP_0402-0.22UF,16V,10%,X7R,A3A!C9N8!//jf4cfls225.pdx.intel.com/apd_proj/ppg_lib/epg_masterlib/logical/mstr_discrete/cap/chips/chips.prt!CAP!CAP_0402-0.22UF,16V,10%,X7R,A36096-155!CAP_0402!!!F3837!!IO_SLOT!!
S!@baseboard_fab2_lib.baseboard_fab2(sch_1):page182_i49@mstr_discrete.cap(chips)!CAP_0402-0.22UF,16V,10%,X7R,A3A!C9N9!//jf4cfls225.pdx.intel.com/apd_proj/ppg_lib/epg_masterlib/logical/mstr_discrete/cap/chips/chips.prt!CAP!CAP_0402-0.22UF,16V,10%,X7R,A36096-155!CAP_0402!!!F3836!!IO_SLOT!!
S!@baseboard_fab2_lib.baseboard_fab2(sch_1):page182_i51@mstr_discrete.cap(chips)!CAP_0402-0.22UF,16V,10%,X7R,A3A!C9N3!//jf4cfls225.pdx.intel.com/apd_proj/ppg_lib/epg_masterlib/logical/mstr_discrete/cap/chips/chips.prt!CAP!CAP_0402-0.22UF,16V,10%,X7R,A36096-155!CAP_0402!!!F3842!!IO_SLOT!!
S!@baseboard_fab2_lib.baseboard_fab2(sch_1):page182_i52@mstr_discrete.cap(chips)!CAP_0402-0.22UF,16V,10%,X7R,A3A!C9N16!//jf4cfls225.pdx.intel.com/apd_proj/ppg_lib/epg_masterlib/logical/mstr_discrete/cap/chips/chips.prt!CAP!CAP_0402-0.22UF,16V,10%,X7R,A36096-155!CAP_0402!!!F3831!!IO_SLOT!!
S!@baseboard_fab2_lib.baseboard_fab2(sch_1):page182_i81@mstr_discrete.cap(chips)!CAP_0402-0.22UF,16V,10%,X7R,A3A!C9N6!//jf4cfls225.pdx.intel.com/apd_proj/ppg_lib/epg_masterlib/logical/mstr_discrete/cap/chips/chips.prt!CAP!CAP_0402-0.22UF,16V,10%,X7R,A36096-155!CAP_0402!!!F3839!!IO_SLOT!!
S!@baseboard_fab2_lib.baseboard_fab2(sch_1):page182_i9@mstr_discrete.cap(chips)!CAP_0402-0.22UF,16V,10%,X7R,A3A!C9N18!//jf4cfls225.pdx.intel.com/apd_proj/ppg_lib/epg_masterlib/logical/mstr_discrete/cap/chips/chips.prt!CAP!CAP_0402-0.22UF,16V,10%,X7R,A36096-155!CAP_0402!!!F3829!!IO_SLOT!!
S!@baseboard_fab2_lib.baseboard_fab2(sch_1):page182_i13@mstr_discrete.cap(chips)!CAP_0402-0.22UF,16V,10%,X7R,A3A!C9N15!//jf4cfls225.pdx.intel.com/apd_proj/ppg_lib/epg_masterlib/logical/mstr_discrete/cap/chips/chips.prt!CAP!CAP_0402-0.22UF,16V,10%,X7R,A36096-155!CAP_0402!!!F3832!!IO_SLOT!!
S!@baseboard_fab2_lib.baseboard_fab2(sch_1):page182_i14@mstr_discrete.cap(chips)!CAP_0402-0.22UF,16V,10%,X7R,A3A!C9N1!//jf4cfls225.pdx.intel.com/apd_proj/ppg_lib/epg_masterlib/logical/mstr_discrete/cap/chips/chips.prt!CAP!CAP_0402-0.22UF,16V,10%,X7R,A36096-155!CAP_0402!!!F3844!!IO_SLOT!!
S!@baseboard_fab2_lib.baseboard_fab2(sch_1):page236_i39@mstr_discrete.cap(chips)!CAP_0402-0.22UF,16V,10%,X7R,A3A!C7A41!//jf4cfls225.pdx.intel.com/apd_proj/ppg_lib/epg_masterlib/logical/mstr_discrete/cap/chips/chips.prt!CAP!CAP_0402-0.22UF,16V,10%,X7R,A36096-155!CAP_0402!!!F3984!!P1V05_PCH_STBY_VR!!
S!@baseboard_fab2_lib.baseboard_fab2(sch_1):page236_i16@mstr_discrete.cap(chips)!CAP_0402-0.22UF,16V,10%,X7R,A3A!C7A8!//jf4cfls225.pdx.intel.com/apd_proj/ppg_lib/epg_masterlib/logical/mstr_discrete/cap/chips/chips.prt!CAP!CAP_0402-0.22UF,16V,10%,X7R,A36096-155!CAP_0402!!!F3892!!PVNN_PCH_STBY!!
S!@baseboard_fab2_lib.baseboard_fab2(sch_1):page214_i73@mstr_discrete.cap(chips)!CAP_0402-0.22UF,16V,10%,X7R,A3A!C4E23!//jf4cfls225.pdx.intel.com/apd_proj/ppg_lib/epg_masterlib/logical/mstr_discrete/cap/chips/chips.prt!CAP!CAP_0402-0.22UF,16V,10%,X7R,A36096-155!CAP_0402!!!F3909!!PVCCIO_CPU1!!
S!@baseboard_fab2_lib.baseboard_fab2(sch_1):page203_i48@mstr_discrete.cap(chips)!CAP_0402-0.22UF,16V,10%,X7R,A3A!C4D5!//jf4cfls225.pdx.intel.com/apd_proj/ppg_lib/epg_masterlib/logical/mstr_discrete/cap/chips/chips.prt!CAP!CAP_0402-0.22UF,16V,10%,X7R,A36096-155!CAP_0402!!!F3913!!PVCCIN_CPU0_PWR_VR!!
S!@baseboard_fab2_lib.baseboard_fab2(sch_1):page203_i40@mstr_discrete.cap(chips)!CAP_0402-0.22UF,16V,10%,X7R,A3A!C4D13!//jf4cfls225.pdx.intel.com/apd_proj/ppg_lib/epg_masterlib/logical/mstr_discrete/cap/chips/chips.prt!CAP!CAP_0402-0.22UF,16V,10%,X7R,A36096-155!CAP_0402!!!F3912!!PVCCIN_CPU0_PWR_VR!!
S!@baseboard_fab2_lib.baseboard_fab2(sch_1):page185_i66@mstr_discrete.cap(chips)!CAP_0402-0.22UF,16V,10%,X7R,A3A!C2T20!//jf4cfls225.pdx.intel.com/apd_proj/ppg_lib/epg_masterlib/logical/mstr_discrete/cap/chips/chips.prt!CAP!CAP_0402-0.22UF,16V,10%,X7R,A36096-155!CAP_0402!!!F3973!!M_2!!
S!@baseboard_fab2_lib.baseboard_fab2(sch_1):page185_i67@mstr_discrete.cap(chips)!CAP_0402-0.22UF,16V,10%,X7R,A3A!C2T23!//jf4cfls225.pdx.intel.com/apd_proj/ppg_lib/epg_masterlib/logical/mstr_discrete/cap/chips/chips.prt!CAP!CAP_0402-0.22UF,16V,10%,X7R,A36096-155!CAP_0402!!!F3972!!M_2!!
S!@baseboard_fab2_lib.baseboard_fab2(sch_1):page185_i64@mstr_discrete.cap(chips)!CAP_0402-0.22UF,16V,10%,X7R,A3A!C2T13!//jf4cfls225.pdx.intel.com/apd_proj/ppg_lib/epg_masterlib/logical/mstr_discrete/cap/chips/chips.prt!CAP!CAP_0402-0.22UF,16V,10%,X7R,A36096-155!CAP_0402!!!F3975!!M_2!!
S!@baseboard_fab2_lib.baseboard_fab2(sch_1):page185_i65@mstr_discrete.cap(chips)!CAP_0402-0.22UF,16V,10%,X7R,A3A!C2T14!//jf4cfls225.pdx.intel.com/apd_proj/ppg_lib/epg_masterlib/logical/mstr_discrete/cap/chips/chips.prt!CAP!CAP_0402-0.22UF,16V,10%,X7R,A36096-155!CAP_0402!!!F3974!!M_2!!
S!@baseboard_fab2_lib.baseboard_fab2(sch_1):page185_i63@mstr_discrete.cap(chips)!CAP_0402-0.22UF,16V,10%,X7R,A3A!C2T10!//jf4cfls225.pdx.intel.com/apd_proj/ppg_lib/epg_masterlib/logical/mstr_discrete/cap/chips/chips.prt!CAP!CAP_0402-0.22UF,16V,10%,X7R,A36096-155!CAP_0402!!!F3977!!M_2!!
S!@baseboard_fab2_lib.baseboard_fab2(sch_1):page185_i62@mstr_discrete.cap(chips)!CAP_0402-0.22UF,16V,10%,X7R,A3A!C2T11!//jf4cfls225.pdx.intel.com/apd_proj/ppg_lib/epg_masterlib/logical/mstr_discrete/cap/chips/chips.prt!CAP!CAP_0402-0.22UF,16V,10%,X7R,A36096-155!CAP_0402!!!F3976!!M_2!!
S!@baseboard_fab2_lib.baseboard_fab2(sch_1):page129_i35@mstr_discrete.cap(chips)!CAP_0402-0.22UF,16V,10%,X7R,A3A!C7B25!//jf4cfls225.pdx.intel.com/apd_proj/ppg_lib/epg_masterlib/logical/mstr_discrete/cap/chips/chips.prt!CAP!CAP_0402-0.22UF,16V,10%,X7R,A36096-155!CAP_0402!!!F3889!!DMI!!
S!@baseboard_fab2_lib.baseboard_fab2(sch_1):page129_i70@mstr_discrete.cap(chips)!CAP_0402-0.22UF,16V,10%,X7R,A3A!C7B28!//jf4cfls225.pdx.intel.com/apd_proj/ppg_lib/epg_masterlib/logical/mstr_discrete/cap/chips/chips.prt!CAP!CAP_0402-0.22UF,16V,10%,X7R,A36096-155!CAP_0402!!!F3886!!DMI!!
S!@baseboard_fab2_lib.baseboard_fab2(sch_1):page129_i75@mstr_discrete.cap(chips)!CAP_0402-0.22UF,16V,10%,X7R,A3A!C3N8!//jf4cfls225.pdx.intel.com/apd_proj/ppg_lib/epg_masterlib/logical/mstr_discrete/cap/chips/chips.prt!CAP!CAP_0402-0.22UF,16V,10%,X7R,A36096-155!CAP_0402!!!F3934!!DMI!!
S!@baseboard_fab2_lib.baseboard_fab2(sch_1):page129_i73@mstr_discrete.cap(chips)!CAP_0402-0.22UF,16V,10%,X7R,A3A!C3M37!//jf4cfls225.pdx.intel.com/apd_proj/ppg_lib/epg_masterlib/logical/mstr_discrete/cap/chips/chips.prt!CAP!CAP_0402-0.22UF,16V,10%,X7R,A36096-155!CAP_0402!!!F3939!!DMI!!
S!@baseboard_fab2_lib.baseboard_fab2(sch_1):page129_i69@mstr_discrete.cap(chips)!CAP_0402-0.22UF,16V,10%,X7R,A3A!C7B27!//jf4cfls225.pdx.intel.com/apd_proj/ppg_lib/epg_masterlib/logical/mstr_discrete/cap/chips/chips.prt!CAP!CAP_0402-0.22UF,16V,10%,X7R,A36096-155!CAP_0402!!!F3887!!DMI!!
S!@baseboard_fab2_lib.baseboard_fab2(sch_1):page129_i71@mstr_discrete.cap(chips)!CAP_0402-0.22UF,16V,10%,X7R,A3A!C7C2!//jf4cfls225.pdx.intel.com/apd_proj/ppg_lib/epg_masterlib/logical/mstr_discrete/cap/chips/chips.prt!CAP!CAP_0402-0.22UF,16V,10%,X7R,A36096-155!CAP_0402!!!F3883!!DMI!!
S!@baseboard_fab2_lib.baseboard_fab2(sch_1):page129_i74@mstr_discrete.cap(chips)!CAP_0402-0.22UF,16V,10%,X7R,A3A!C3N9!//jf4cfls225.pdx.intel.com/apd_proj/ppg_lib/epg_masterlib/logical/mstr_discrete/cap/chips/chips.prt!CAP!CAP_0402-0.22UF,16V,10%,X7R,A36096-155!CAP_0402!!!F3933!!DMI!!
S!@baseboard_fab2_lib.baseboard_fab2(sch_1):page129_i72@mstr_discrete.cap(chips)!CAP_0402-0.22UF,16V,10%,X7R,A3A!C3M40!//jf4cfls225.pdx.intel.com/apd_proj/ppg_lib/epg_masterlib/logical/mstr_discrete/cap/chips/chips.prt!CAP!CAP_0402-0.22UF,16V,10%,X7R,A36096-155!CAP_0402!!!F3938!!DMI!!
S!@baseboard_fab2_lib.baseboard_fab2(sch_1):page129_i79@mstr_discrete.cap(chips)!CAP_0402-0.22UF,16V,10%,X7R,A3A!C7B26!//jf4cfls225.pdx.intel.com/apd_proj/ppg_lib/epg_masterlib/logical/mstr_discrete/cap/chips/chips.prt!CAP!CAP_0402-0.22UF,16V,10%,X7R,A36096-155!CAP_0402!!!F3888!!DMI!!
S!@baseboard_fab2_lib.baseboard_fab2(sch_1):page129_i77@mstr_discrete.cap(chips)!CAP_0402-0.22UF,16V,10%,X7R,A3A!C7C1!//jf4cfls225.pdx.intel.com/apd_proj/ppg_lib/epg_masterlib/logical/mstr_discrete/cap/chips/chips.prt!CAP!CAP_0402-0.22UF,16V,10%,X7R,A36096-155!CAP_0402!!!F3884!!DMI!!
S!@baseboard_fab2_lib.baseboard_fab2(sch_1):page129_i83@mstr_discrete.cap(chips)!CAP_0402-0.22UF,16V,10%,X7R,A3A!C3N13!//jf4cfls225.pdx.intel.com/apd_proj/ppg_lib/epg_masterlib/logical/mstr_discrete/cap/chips/chips.prt!CAP!CAP_0402-0.22UF,16V,10%,X7R,A36096-155!CAP_0402!!!F3932!!DMI!!
S!@baseboard_fab2_lib.baseboard_fab2(sch_1):page129_i81@mstr_discrete.cap(chips)!CAP_0402-0.22UF,16V,10%,X7R,A3A!C3M41!//jf4cfls225.pdx.intel.com/apd_proj/ppg_lib/epg_masterlib/logical/mstr_discrete/cap/chips/chips.prt!CAP!CAP_0402-0.22UF,16V,10%,X7R,A36096-155!CAP_0402!!!F3937!!DMI!!
S!@baseboard_fab2_lib.baseboard_fab2(sch_1):page129_i78@mstr_discrete.cap(chips)!CAP_0402-0.22UF,16V,10%,X7R,A3A!C7B29!//jf4cfls225.pdx.intel.com/apd_proj/ppg_lib/epg_masterlib/logical/mstr_discrete/cap/chips/chips.prt!CAP!CAP_0402-0.22UF,16V,10%,X7R,A36096-155!CAP_0402!!!F3885!!DMI!!
S!@baseboard_fab2_lib.baseboard_fab2(sch_1):page129_i76@mstr_discrete.cap(chips)!CAP_0402-0.22UF,16V,10%,X7R,A3A!C7C3!//jf4cfls225.pdx.intel.com/apd_proj/ppg_lib/epg_masterlib/logical/mstr_discrete/cap/chips/chips.prt!CAP!CAP_0402-0.22UF,16V,10%,X7R,A36096-155!CAP_0402!!!F3882!!DMI!!
S!@baseboard_fab2_lib.baseboard_fab2(sch_1):page129_i82@mstr_discrete.cap(chips)!CAP_0402-0.22UF,16V,10%,X7R,A3A!C3M45!//jf4cfls225.pdx.intel.com/apd_proj/ppg_lib/epg_masterlib/logical/mstr_discrete/cap/chips/chips.prt!CAP!CAP_0402-0.22UF,16V,10%,X7R,A36096-155!CAP_0402!!!F3935!!DMI!!
S!@baseboard_fab2_lib.baseboard_fab2(sch_1):page129_i80@mstr_discrete.cap(chips)!CAP_0402-0.22UF,16V,10%,X7R,A3A!C3M44!//jf4cfls225.pdx.intel.com/apd_proj/ppg_lib/epg_masterlib/logical/mstr_discrete/cap/chips/chips.prt!CAP!CAP_0402-0.22UF,16V,10%,X7R,A36096-155!CAP_0402!!!F3936!!DMI!!
S!@baseboard_fab2_lib.baseboard_fab2(sch_1):page202_i24@mstr_discrete.cap(chips)!CAP_0402-0.22UF,16V,10%,X7R,A3A!C4E27!//jf4cfls225.pdx.intel.com/apd_proj/ppg_lib/epg_masterlib/logical/mstr_discrete/cap/chips/chips.prt!CAP!CAP_0402-0.22UF,16V,10%,X7R,A36096-155!CAP_0402!!!F3911!!PVCCIN_CPU0_PWR_VR!!
S!@baseboard_fab2_lib.baseboard_fab2(sch_1):page202_i18@mstr_discrete.cap(chips)!CAP_0402-0.22UF,16V,10%,X7R,A3A!C4E5!//jf4cfls225.pdx.intel.com/apd_proj/ppg_lib/epg_masterlib/logical/mstr_discrete/cap/chips/chips.prt!CAP!CAP_0402-0.22UF,16V,10%,X7R,A36096-155!CAP_0402!!!F3910!!PVCCIN_CPU0_PWR_VR!!
S!@baseboard_fab2_lib.baseboard_fab2(sch_1):page204_i18@mstr_discrete.cap(chips)!CAP_0402-0.22UF,16V,10%,X7R,A3A!C4D47!//jf4cfls225.pdx.intel.com/apd_proj/ppg_lib/epg_masterlib/logical/mstr_discrete/cap/chips/chips.prt!CAP!CAP_0402-0.22UF,16V,10%,X7R,A36096-155!CAP_0402!!!F3914!!PVCCIN_CPU0_PWR_VR!!
S!@baseboard_fab2_lib.baseboard_fab2(sch_1):page205_i16@mstr_discrete.cap(chips)!CAP_0402-0.22UF,16V,10%,X7R,A3A!C4C5!//jf4cfls225.pdx.intel.com/apd_proj/ppg_lib/epg_masterlib/logical/mstr_discrete/cap/chips/chips.prt!CAP!CAP_0402-0.22UF,16V,10%,X7R,A36096-155!CAP_0402!!!F3915!!PVSA_CPU0_PWR_VR!!
S!@baseboard_fab2_lib.baseboard_fab2(sch_1):page216_i54@mstr_discrete.cap(chips)!CAP_0402-0.22UF,16V,10%,X7R,A3A!C7G34!//jf4cfls225.pdx.intel.com/apd_proj/ppg_lib/epg_masterlib/logical/mstr_discrete/cap/chips/chips.prt!CAP!CAP_0402-0.22UF,16V,10%,X7R,A36096-155!CAP_0402!!!F3858!!VDDQ_ABC_PWR_VR!!
S!@baseboard_fab2_lib.baseboard_fab2(sch_1):page216_i72@mstr_discrete.cap(chips)!CAP_0402-0.22UF,16V,10%,X7R,A3A!C7G41!//jf4cfls225.pdx.intel.com/apd_proj/ppg_lib/epg_masterlib/logical/mstr_discrete/cap/chips/chips.prt!CAP!CAP_0402-0.22UF,16V,10%,X7R,A36096-155!CAP_0402!!!F3857!!VDDQ_ABC_PWR_VR!!
S!@baseboard_fab2_lib.baseboard_fab2(sch_1):page219_i54@mstr_discrete.cap(chips)!CAP_0402-0.22UF,16V,10%,X7R,A3A!C7A17!//jf4cfls225.pdx.intel.com/apd_proj/ppg_lib/epg_masterlib/logical/mstr_discrete/cap/chips/chips.prt!CAP!CAP_0402-0.22UF,16V,10%,X7R,A36096-155!CAP_0402!!!F3891!!VDDQ_DEF_PWR_VR!!
S!@baseboard_fab2_lib.baseboard_fab2(sch_1):page219_i72@mstr_discrete.cap(chips)!CAP_0402-0.22UF,16V,10%,X7R,A3A!C7A25!//jf4cfls225.pdx.intel.com/apd_proj/ppg_lib/epg_masterlib/logical/mstr_discrete/cap/chips/chips.prt!CAP!CAP_0402-0.22UF,16V,10%,X7R,A36096-155!CAP_0402!!!F3890!!VDDQ_DEF_PWR_VR!!
S!@baseboard_fab2_lib.baseboard_fab2(sch_1):page227_i54@mstr_discrete.cap(chips)!CAP_0402-0.22UF,16V,10%,X7R,A3A!C1B21!//jf4cfls225.pdx.intel.com/apd_proj/ppg_lib/epg_masterlib/logical/mstr_discrete/cap/chips/chips.prt!CAP!CAP_0402-0.22UF,16V,10%,X7R,A36096-155!CAP_0402!!!F4036!!VDDQ_KLM_PWR_VR!!
S!@baseboard_fab2_lib.baseboard_fab2(sch_1):page227_i72@mstr_discrete.cap(chips)!CAP_0402-0.22UF,16V,10%,X7R,A3A!C1A13!//jf4cfls225.pdx.intel.com/apd_proj/ppg_lib/epg_masterlib/logical/mstr_discrete/cap/chips/chips.prt!CAP!CAP_0402-0.22UF,16V,10%,X7R,A36096-155!CAP_0402!!!F4035!!VDDQ_KLM_PWR_VR!!
S!@baseboard_fab2_lib.baseboard_fab2(sch_1):page224_i54@mstr_discrete.cap(chips)!CAP_0402-0.22UF,16V,10%,X7R,A3A!C1G5!//jf4cfls225.pdx.intel.com/apd_proj/ppg_lib/epg_masterlib/logical/mstr_discrete/cap/chips/chips.prt!CAP!CAP_0402-0.22UF,16V,10%,X7R,A36096-155!CAP_0402!!!F4011!!VDDQ_GHJ_PWR_VR!!
S!@baseboard_fab2_lib.baseboard_fab2(sch_1):page224_i72@mstr_discrete.cap(chips)!CAP_0402-0.22UF,16V,10%,X7R,A3A!C1G29!//jf4cfls225.pdx.intel.com/apd_proj/ppg_lib/epg_masterlib/logical/mstr_discrete/cap/chips/chips.prt!CAP!CAP_0402-0.22UF,16V,10%,X7R,A36096-155!CAP_0402!!!F4012!!VDDQ_GHJ_PWR_VR!!
S!@baseboard_fab2_lib.baseboard_fab2(sch_1):page207_i36@mstr_discrete.cap(chips)!CAP_0402-0.22UF,16V,10%,X7R,A3A!C1E25!//jf4cfls225.pdx.intel.com/apd_proj/ppg_lib/epg_masterlib/logical/mstr_discrete/cap/chips/chips.prt!CAP!CAP_0402-0.22UF,16V,10%,X7R,A36096-155!CAP_0402!!!F4030!!PVCCIN_CPU1_PWR_VR!!
S!@baseboard_fab2_lib.baseboard_fab2(sch_1):page207_i28@mstr_discrete.cap(chips)!CAP_0402-0.22UF,16V,10%,X7R,A3A!C1E7!//jf4cfls225.pdx.intel.com/apd_proj/ppg_lib/epg_masterlib/logical/mstr_discrete/cap/chips/chips.prt!CAP!CAP_0402-0.22UF,16V,10%,X7R,A36096-155!CAP_0402!!!F4029!!PVCCIN_CPU1_PWR_VR!!
S!@baseboard_fab2_lib.baseboard_fab2(sch_1):page208_i38@mstr_discrete.cap(chips)!CAP_0402-0.22UF,16V,10%,X7R,A3A!C1D16!//jf4cfls225.pdx.intel.com/apd_proj/ppg_lib/epg_masterlib/logical/mstr_discrete/cap/chips/chips.prt!CAP!CAP_0402-0.22UF,16V,10%,X7R,A36096-155!CAP_0402!!!F4031!!PVCCIN_CPU1_PWR_VR!!
S!@baseboard_fab2_lib.baseboard_fab2(sch_1):page208_i46@mstr_discrete.cap(chips)!CAP_0402-0.22UF,16V,10%,X7R,A3A!C1D6!//jf4cfls225.pdx.intel.com/apd_proj/ppg_lib/epg_masterlib/logical/mstr_discrete/cap/chips/chips.prt!CAP!CAP_0402-0.22UF,16V,10%,X7R,A36096-155!CAP_0402!!!F4032!!PVCCIN_CPU1_PWR_VR!!
S!@baseboard_fab2_lib.baseboard_fab2(sch_1):page210_i22@mstr_discrete.cap(chips)!CAP_0402-0.22UF,16V,10%,X7R,A3A!C1C4!//jf4cfls225.pdx.intel.com/apd_proj/ppg_lib/epg_masterlib/logical/mstr_discrete/cap/chips/chips.prt!CAP!CAP_0402-0.22UF,16V,10%,X7R,A36096-155!CAP_0402!!!F4034!!PVSA_CPU1_PWR_VR!!
S!@baseboard_fab2_lib.baseboard_fab2(sch_1):page181_i167@mstr_discrete.cap(chips)!CAP_0402-0.22UF,16V,10%,X7R,A3A!C1F3!//jf4cfls225.pdx.intel.com/apd_proj/ppg_lib/epg_masterlib/logical/mstr_discrete/cap/chips/chips.prt!CAP!CAP_0402-0.22UF,16V,10%,X7R,A36096-155!CAP_0402!!!F4027!!IO_SLOT!!
S!@baseboard_fab2_lib.baseboard_fab2(sch_1):page181_i168@mstr_discrete.cap(chips)!CAP_0402-0.22UF,16V,10%,X7R,A3A!C1F12!//jf4cfls225.pdx.intel.com/apd_proj/ppg_lib/epg_masterlib/logical/mstr_discrete/cap/chips/chips.prt!CAP!CAP_0402-0.22UF,16V,10%,X7R,A36096-155!CAP_0402!!!F4020!!IO_SLOT!!
S!@baseboard_fab2_lib.baseboard_fab2(sch_1):page181_i169@mstr_discrete.cap(chips)!CAP_0402-0.22UF,16V,10%,X7R,A3A!C1F11!//jf4cfls225.pdx.intel.com/apd_proj/ppg_lib/epg_masterlib/logical/mstr_discrete/cap/chips/chips.prt!CAP!CAP_0402-0.22UF,16V,10%,X7R,A36096-155!CAP_0402!!!F4021!!IO_SLOT!!
S!@baseboard_fab2_lib.baseboard_fab2(sch_1):page181_i170@mstr_discrete.cap(chips)!CAP_0402-0.22UF,16V,10%,X7R,A3A!C1F8!//jf4cfls225.pdx.intel.com/apd_proj/ppg_lib/epg_masterlib/logical/mstr_discrete/cap/chips/chips.prt!CAP!CAP_0402-0.22UF,16V,10%,X7R,A36096-155!CAP_0402!!!F4023!!IO_SLOT!!
S!@baseboard_fab2_lib.baseboard_fab2(sch_1):page181_i171@mstr_discrete.cap(chips)!CAP_0402-0.22UF,16V,10%,X7R,A3A!C1F18!//jf4cfls225.pdx.intel.com/apd_proj/ppg_lib/epg_masterlib/logical/mstr_discrete/cap/chips/chips.prt!CAP!CAP_0402-0.22UF,16V,10%,X7R,A36096-155!CAP_0402!!!F4014!!IO_SLOT!!
S!@baseboard_fab2_lib.baseboard_fab2(sch_1):page181_i173@mstr_discrete.cap(chips)!CAP_0402-0.22UF,16V,10%,X7R,A3A!C1F17!//jf4cfls225.pdx.intel.com/apd_proj/ppg_lib/epg_masterlib/logical/mstr_discrete/cap/chips/chips.prt!CAP!CAP_0402-0.22UF,16V,10%,X7R,A36096-155!CAP_0402!!!F4015!!IO_SLOT!!
S!@baseboard_fab2_lib.baseboard_fab2(sch_1):page181_i175@mstr_discrete.cap(chips)!CAP_0402-0.22UF,16V,10%,X7R,A3A!C1F14!//jf4cfls225.pdx.intel.com/apd_proj/ppg_lib/epg_masterlib/logical/mstr_discrete/cap/chips/chips.prt!CAP!CAP_0402-0.22UF,16V,10%,X7R,A36096-155!CAP_0402!!!F4018!!IO_SLOT!!
S!@baseboard_fab2_lib.baseboard_fab2(sch_1):page181_i161@mstr_discrete.cap(chips)!CAP_0402-0.22UF,16V,10%,X7R,A3A!C1F5!//jf4cfls225.pdx.intel.com/apd_proj/ppg_lib/epg_masterlib/logical/mstr_discrete/cap/chips/chips.prt!CAP!CAP_0402-0.22UF,16V,10%,X7R,A36096-155!CAP_0402!!!F4025!!IO_SLOT!!
S!@baseboard_fab2_lib.baseboard_fab2(sch_1):page181_i160@mstr_discrete.cap(chips)!CAP_0402-0.22UF,16V,10%,X7R,A3A!C1F4!//jf4cfls225.pdx.intel.com/apd_proj/ppg_lib/epg_masterlib/logical/mstr_discrete/cap/chips/chips.prt!CAP!CAP_0402-0.22UF,16V,10%,X7R,A36096-155!CAP_0402!!!F4026!!IO_SLOT!!
S!@baseboard_fab2_lib.baseboard_fab2(sch_1):page181_i162@mstr_discrete.cap(chips)!CAP_0402-0.22UF,16V,10%,X7R,A3A!C1F2!//jf4cfls225.pdx.intel.com/apd_proj/ppg_lib/epg_masterlib/logical/mstr_discrete/cap/chips/chips.prt!CAP!CAP_0402-0.22UF,16V,10%,X7R,A36096-155!CAP_0402!!!F4028!!IO_SLOT!!
S!@baseboard_fab2_lib.baseboard_fab2(sch_1):page181_i163@mstr_discrete.cap(chips)!CAP_0402-0.22UF,16V,10%,X7R,A3A!C1F13!//jf4cfls225.pdx.intel.com/apd_proj/ppg_lib/epg_masterlib/logical/mstr_discrete/cap/chips/chips.prt!CAP!CAP_0402-0.22UF,16V,10%,X7R,A36096-155!CAP_0402!!!F4019!!IO_SLOT!!
S!@baseboard_fab2_lib.baseboard_fab2(sch_1):page181_i164@mstr_discrete.cap(chips)!CAP_0402-0.22UF,16V,10%,X7R,A3A!C1F10!//jf4cfls225.pdx.intel.com/apd_proj/ppg_lib/epg_masterlib/logical/mstr_discrete/cap/chips/chips.prt!CAP!CAP_0402-0.22UF,16V,10%,X7R,A36096-155!CAP_0402!!!F4022!!IO_SLOT!!
S!@baseboard_fab2_lib.baseboard_fab2(sch_1):page181_i165@mstr_discrete.cap(chips)!CAP_0402-0.22UF,16V,10%,X7R,A3A!C1F6!//jf4cfls225.pdx.intel.com/apd_proj/ppg_lib/epg_masterlib/logical/mstr_discrete/cap/chips/chips.prt!CAP!CAP_0402-0.22UF,16V,10%,X7R,A36096-155!CAP_0402!!!F4024!!IO_SLOT!!
S!@baseboard_fab2_lib.baseboard_fab2(sch_1):page181_i166@mstr_discrete.cap(chips)!CAP_0402-0.22UF,16V,10%,X7R,A3A!C1F20!//jf4cfls225.pdx.intel.com/apd_proj/ppg_lib/epg_masterlib/logical/mstr_discrete/cap/chips/chips.prt!CAP!CAP_0402-0.22UF,16V,10%,X7R,A36096-155!CAP_0402!!!F4013!!IO_SLOT!!
S!@baseboard_fab2_lib.baseboard_fab2(sch_1):page181_i172@mstr_discrete.cap(chips)!CAP_0402-0.22UF,16V,10%,X7R,A3A!C1F16!//jf4cfls225.pdx.intel.com/apd_proj/ppg_lib/epg_masterlib/logical/mstr_discrete/cap/chips/chips.prt!CAP!CAP_0402-0.22UF,16V,10%,X7R,A36096-155!CAP_0402!!!F4016!!IO_SLOT!!
S!@baseboard_fab2_lib.baseboard_fab2(sch_1):page181_i174@mstr_discrete.cap(chips)!CAP_0402-0.22UF,16V,10%,X7R,A3A!C1F15!//jf4cfls225.pdx.intel.com/apd_proj/ppg_lib/epg_masterlib/logical/mstr_discrete/cap/chips/chips.prt!CAP!CAP_0402-0.22UF,16V,10%,X7R,A36096-155!CAP_0402!!!F4017!!IO_SLOT!!
S!@baseboard_fab2_lib.baseboard_fab2(sch_1):page209_i22@mstr_discrete.cap(chips)!CAP_0402-0.22UF,16V,10%,X7R,A3A!C1D33!//jf4cfls225.pdx.intel.com/apd_proj/ppg_lib/epg_masterlib/logical/mstr_discrete/cap/chips/chips.prt!CAP!CAP_0402-0.22UF,16V,10%,X7R,A36096-155!CAP_0402!!!F4033!!PVCCIN_CPU1_PWR_VR!!
S!@baseboard_fab2_lib.baseboard_fab2(sch_1):page212_i33@mstr_discrete.cap(chips)!CAP_0402-0.22UF,16V,10%,X7R,A3A!C7C18!//jf4cfls225.pdx.intel.com/apd_proj/ppg_lib/epg_masterlib/logical/mstr_discrete/cap/chips/chips.prt!CAP!CAP_0402-0.22UF,16V,10%,X7R,A36096-155!CAP_0402!!!F3881!!PVCCIO_CPU0!!
S!@baseboard_fab2_lib.baseboard_fab2(sch_1):page141_i48@mstr_discrete.cap(chips)!CAP_0402-1.0UF,16V,10%,X7S,G71A!C9G5!//jf4cfls225.pdx.intel.com/apd_proj/ppg_lib/epg_masterlib/logical/mstr_discrete/cap/chips/chips.prt!CAP!CAP_0402-1.0UF,16V,10%,X7S,G71842-007!CAP_0402!!!F3758!!NIC_SPRV!!
S!@baseboard_fab2_lib.baseboard_fab2(sch_1):page236_i65@mstr_discrete.cap(chips)!CAP_1210-100UF,16V,20%,X5R,644A!C7A14!//jf4cfls225.pdx.intel.com/apd_proj/ppg_lib/epg_masterlib/logical/mstr_discrete/cap/chips/chips.prt!CAP!CAP_1210-100UF,16V,20%,X5R,644066-127!CAP!!!F2278!!PVNN_PCH_STBY!!
S!@baseboard_fab2_lib.baseboard_fab2(sch_1):page236_i63@mstr_discrete.cap(chips)!CAP_1210-100UF,16V,20%,X5R,644A!C7A13!//jf4cfls225.pdx.intel.com/apd_proj/ppg_lib/epg_masterlib/logical/mstr_discrete/cap/chips/chips.prt!CAP!CAP_1210-100UF,16V,20%,X5R,644066-127!CAP!!!F2279!!PVNN_PCH_STBY!!
S!@baseboard_fab2_lib.baseboard_fab2(sch_1):page212_i54@mstr_discrete.cap(chips)!CAP_1210-100UF,16V,20%,X5R,644A!C7C7!//jf4cfls225.pdx.intel.com/apd_proj/ppg_lib/epg_masterlib/logical/mstr_discrete/cap/chips/chips.prt!CAP!CAP_1210-100UF,16V,20%,X5R,644066-127!CAP!!!F2277!!PVCCIO_CPU1!!
S!@baseboard_fab2_lib.baseboard_fab2(sch_1):page212_i51@mstr_discrete.cap(chips)!CAP_1210-100UF,16V,20%,X5R,644A!C7C8!//jf4cfls225.pdx.intel.com/apd_proj/ppg_lib/epg_masterlib/logical/mstr_discrete/cap/chips/chips.prt!CAP!CAP_1210-100UF,16V,20%,X5R,644066-127!CAP!!!F2276!!PVCCIO_CPU1!!
S!@baseboard_fab2_lib.baseboard_fab2(sch_1):page214_i29@mstr_discrete.cap(chips)!CAP_1210-100UF,16V,20%,X5R,644A!C4E8!//jf4cfls225.pdx.intel.com/apd_proj/ppg_lib/epg_masterlib/logical/mstr_discrete/cap/chips/chips.prt!CAP!CAP_1210-100UF,16V,20%,X5R,644066-127!CAP!!!F2282!!PVCCIO_CPU1!!
S!@baseboard_fab2_lib.baseboard_fab2(sch_1):page214_i8@mstr_discrete.cap(chips)!CAP_1210-100UF,16V,20%,X5R,644A!C4E9!//jf4cfls225.pdx.intel.com/apd_proj/ppg_lib/epg_masterlib/logical/mstr_discrete/cap/chips/chips.prt!CAP!CAP_1210-100UF,16V,20%,X5R,644066-127!CAP!!!F2281!!PVCCIO_CPU1!!
S!@baseboard_fab2_lib.baseboard_fab2(sch_1):page214_i31@mstr_discrete.cap(chips)!CAP_1210-100UF,16V,20%,X5R,644A!C4E14!//jf4cfls225.pdx.intel.com/apd_proj/ppg_lib/epg_masterlib/logical/mstr_discrete/cap/chips/chips.prt!CAP!CAP_1210-100UF,16V,20%,X5R,644066-127!CAP!!!F2280!!PVCCIO_CPU1!!
S!@baseboard_fab2_lib.baseboard_fab2(sch_1):page161_i99@mstr_discrete.res(chips)!RES_0402-221,1.0%,1/16W,CHIP,GA!R2U42!//jf4cfls225.pdx.intel.com/apd_proj/ppg_lib/epg_masterlib/logical/mstr_discrete/res/chips/chips.prt!RES!RES_0402-221,1.0%,1/16W,CHIP,G21796-271!RES!!!F853!!CPU_FANS!!
S!@baseboard_fab2_lib.baseboard_fab2(sch_1):page161_i102@mstr_discrete.res(chips)!RES_0402-221,1.0%,1/16W,CHIP,GA!R2U44!//jf4cfls225.pdx.intel.com/apd_proj/ppg_lib/epg_masterlib/logical/mstr_discrete/res/chips/chips.prt!RES!RES_0402-221,1.0%,1/16W,CHIP,G21796-271!RES!!!F852!!CPU_FANS!!
S!@baseboard_fab2_lib.baseboard_fab2(sch_1):page177_i72@mstr_discrete.res(chips)!RES_0402-221,1.0%,1/16W,CHIP,GA!R9F28!//jf4cfls225.pdx.intel.com/apd_proj/ppg_lib/epg_masterlib/logical/mstr_discrete/res/chips/chips.prt!RES!RES_0402-221,1.0%,1/16W,CHIP,G21796-271!RES!!!F846!!BMC!!
S!@baseboard_fab2_lib.baseboard_fab2(sch_1):page119_i178@mstr_discrete.res(chips)!RES_0402-221,1.0%,1/16W,CHIP,GA!R9A20!//jf4cfls225.pdx.intel.com/apd_proj/ppg_lib/epg_masterlib/logical/mstr_discrete/res/chips/chips.prt!RES!RES_0402-221,1.0%,1/16W,CHIP,G21796-271!RES!!!F848!!SB!!
S!@baseboard_fab2_lib.baseboard_fab2(sch_1):page21_i152@mstr_discrete.res(chips)!RES_0402-221,1.0%,1/16W,CHIP,GA!R6B3!//jf4cfls225.pdx.intel.com/apd_proj/ppg_lib/epg_masterlib/logical/mstr_discrete/res/chips/chips.prt!RES!RES_0402-221,1.0%,1/16W,CHIP,G21796-271!RES!!!F850!!CPU0!!
S!@baseboard_fab2_lib.baseboard_fab2(sch_1):page21_i149@mstr_discrete.res(chips)!RES_0402-221,1.0%,1/16W,CHIP,GA!R6N10!//jf4cfls225.pdx.intel.com/apd_proj/ppg_lib/epg_masterlib/logical/mstr_discrete/res/chips/chips.prt!RES!RES_0402-221,1.0%,1/16W,CHIP,G21796-271!RES!!!F849!!CPU0!!
S!@baseboard_fab2_lib.baseboard_fab2(sch_1):page55_i26@mstr_discrete.res(chips)!RES_0402-221,1.0%,1/16W,CHIP,GA!R1C1!//jf4cfls225.pdx.intel.com/apd_proj/ppg_lib/epg_masterlib/logical/mstr_discrete/res/chips/chips.prt!RES!RES_0402-221,1.0%,1/16W,CHIP,G21796-271!RES!!!F855!!CPU1!!
S!@baseboard_fab2_lib.baseboard_fab2(sch_1):page55_i27@mstr_discrete.res(chips)!RES_0402-221,1.0%,1/16W,CHIP,GA!R3B1!//jf4cfls225.pdx.intel.com/apd_proj/ppg_lib/epg_masterlib/logical/mstr_discrete/res/chips/chips.prt!RES!RES_0402-221,1.0%,1/16W,CHIP,G21796-271!RES!!!F851!!CPU1!!
S!@baseboard_fab2_lib.baseboard_fab2(sch_1):page147_i57@mstr_discrete.res(chips)!RES_0402-221,1.0%,1/16W,CHIP,GA!R9E24!//jf4cfls225.pdx.intel.com/apd_proj/ppg_lib/epg_masterlib/logical/mstr_discrete/res/chips/chips.prt!RES!RES_0402-221,1.0%,1/16W,CHIP,G21796-271!RES!!!F847!!BMC!!
S!@baseboard_fab2_lib.baseboard_fab2(sch_1):page175_i45@mstr_discrete.res(chips)!RES_0402-221,1.0%,1/16W,CHIP,GA!R1L33!//jf4cfls225.pdx.intel.com/apd_proj/ppg_lib/epg_masterlib/logical/mstr_discrete/res/chips/chips.prt!RES!RES_0402-221,1.0%,1/16W,CHIP,G21796-271!RES!!!F854!!MIO_CHASSIS!!
S!@baseboard_fab2_lib.baseboard_fab2(sch_1):page138_i91@mstr_discrete.res(chips)!RES_0402-3.3K,5%,1/16W,CHIP,G2A!R8C16!//jf4cfls225.pdx.intel.com/apd_proj/ppg_lib/epg_masterlib/logical/mstr_discrete/res/chips/chips.prt!RES!RES_0402-3.3K,5%,1/16W,CHIP,G21497-013!RES!!!F763!!SMBUS!!
S!@baseboard_fab2_lib.baseboard_fab2(sch_1):page138_i92@mstr_discrete.res(chips)!RES_0402-3.3K,5%,1/16W,CHIP,G2A!R8C15!//jf4cfls225.pdx.intel.com/apd_proj/ppg_lib/epg_masterlib/logical/mstr_discrete/res/chips/chips.prt!RES!RES_0402-3.3K,5%,1/16W,CHIP,G21497-013!RES!!!F764!!SMBUS!!
S!@baseboard_fab2_lib.baseboard_fab2(sch_1):page138_i95@mstr_discrete.res(chips)!RES_0402-3.3K,5%,1/16W,CHIP,G2A!R8B24!//jf4cfls225.pdx.intel.com/apd_proj/ppg_lib/epg_masterlib/logical/mstr_discrete/res/chips/chips.prt!RES!RES_0402-3.3K,5%,1/16W,CHIP,G21497-013!RES!!!F766!!SMBUS!!
S!@baseboard_fab2_lib.baseboard_fab2(sch_1):page138_i96@mstr_discrete.res(chips)!RES_0402-3.3K,5%,1/16W,CHIP,G2A!R8B26!//jf4cfls225.pdx.intel.com/apd_proj/ppg_lib/epg_masterlib/logical/mstr_discrete/res/chips/chips.prt!RES!RES_0402-3.3K,5%,1/16W,CHIP,G21497-013!RES!!!F765!!SMBUS!!
S!@baseboard_fab2_lib.baseboard_fab2(sch_1):page237_i15@mstr_discrete.res(chips)!RES_0603-475.0,1%,1/10W,CHIP,GA!R8A12!//jf4cfls225.pdx.intel.com/apd_proj/ppg_lib/epg_masterlib/logical/mstr_discrete/res/chips/chips.prt!RES!RES_0603-475.0,1%,1/10W,CHIP,G22026-030!RES!!!F256!!P1V8_PCH_STBY_VR!!
S!@baseboard_fab2_lib.baseboard_fab2(sch_1):page200_i218@mstr_discrete.res(chips)!RES_0402-4.99K,1%,1/16W,CHIP,GA!R9P12!//jf4cfls225.pdx.intel.com/apd_proj/ppg_lib/epg_masterlib/logical/mstr_discrete/res/chips/chips.prt!RES!RES_0402-4.99K,1%,1/16W,CHIP,G21796-013!RES!!!F495!!HOT_SWAP!!
S!@baseboard_fab2_lib.baseboard_fab2(sch_1):page139_i174@mstr_discrete.res(chips)!RES_0402-4.99K,1%,1/16W,CHIP,GA!R9E23!//jf4cfls225.pdx.intel.com/apd_proj/ppg_lib/epg_masterlib/logical/mstr_discrete/res/chips/chips.prt!RES!RES_0402-4.99K,1%,1/16W,CHIP,G21796-013!RES!!!F496!!NIC_SPRV!!
S!@baseboard_fab2_lib.baseboard_fab2(sch_1):page139_i140@mstr_discrete.cap(chips)!CAP_1210-47UF,16V,20%,EMPTY,D3A!C9F2!//jf4cfls225.pdx.intel.com/apd_proj/ppg_lib/epg_masterlib/logical/mstr_discrete/cap/chips/chips.prt!CAP!CAP_1210-47UF,16V,20%,EMPTY,D38464-007!CAP!!!F2274!!NIC_SPRV!!
S!@baseboard_fab2_lib.baseboard_fab2(sch_1):page139_i155@mstr_discrete.cap(chips)!CAP_1210-47UF,16V,20%,EMPTY,D3A!C9E6!//jf4cfls225.pdx.intel.com/apd_proj/ppg_lib/epg_masterlib/logical/mstr_discrete/cap/chips/chips.prt!CAP!CAP_1210-47UF,16V,20%,EMPTY,D38464-007!CAP!!!F2275!!NIC_SPRV!!
S!@baseboard_fab2_lib.baseboard_fab2(sch_1):page114_i49@mstr_discrete.crystal(chips)!CRYSTAL_2013-48.000MHZ,IC,D717A!Y7C1!//jf4cfls225.pdx.intel.com/apd_proj/ppg_lib/epg_masterlib/logical/mstr_discrete/crystal/chips/chips.prt!CRYSTAL!CRYSTAL_2013-48.000MHZ,IC,D71700-058!CRYSTAL_2013!!!F2230!!SB!!
S!@baseboard_fab2_lib.baseboard_fab2(sch_1):page101_i52@mstr_discrete.crystal(chips)!CRYSTAL_2013LF-25.000MHZ,IC,D7B!Y8F1!//jf4cfls225.pdx.intel.com/apd_proj/ppg_lib/epg_masterlib/logical/mstr_discrete/crystal/chips/chips.prt!CRYSTAL!CRYSTAL_2013LF-25.000MHZ,IC,D71700-033!CRYSTAL_2013LF!!!F2229!!SYS_CLOCK!!
S!@baseboard_fab2_lib.baseboard_fab2(sch_1):page114_i55@mstr_discrete.crystal(chips)!CRYSTAL_SM-32.768KHZ,IC,C13544A!Y7C2!//jf4cfls225.pdx.intel.com/apd_proj/ppg_lib/epg_masterlib/logical/mstr_discrete/crystal/chips/chips.prt!CRYSTAL!CRYSTAL_SM-32.768KHZ,IC,C13544-023!CRYSTAL_SM!!!F2227!!SB!!
S!@baseboard_fab2_lib.baseboard_fab2(sch_1):page168_i2@mstr_discrete.diode(chips)!DIODE_SM-1N4148W,IC,D89194-001!CR1L1!//jf4cfls225.pdx.intel.com/apd_proj/ppg_lib/epg_masterlib/logical/mstr_discrete/diode/chips/chips.prt!DIODE!DIODE_SM-1N4148W,IC,D89194-001!DIODE_SM!!!F2222!!UART_MUX!!
S!@baseboard_fab2_lib.baseboard_fab2(sch_1):page168_i3@mstr_discrete.diode(chips)!DIODE_SM-1N4148W,IC,D89194-001!CR1L2!//jf4cfls225.pdx.intel.com/apd_proj/ppg_lib/epg_masterlib/logical/mstr_discrete/diode/chips/chips.prt!DIODE!DIODE_SM-1N4148W,IC,D89194-001!DIODE_SM!!!F2221!!UART_MUX!!
S!@baseboard_fab2_lib.baseboard_fab2(sch_1):page168_i4@mstr_discrete.diode(chips)!DIODE_SM-1N4148W,IC,D89194-001!CR1L3!//jf4cfls225.pdx.intel.com/apd_proj/ppg_lib/epg_masterlib/logical/mstr_discrete/diode/chips/chips.prt!DIODE!DIODE_SM-1N4148W,IC,D89194-001!DIODE_SM!!!F2220!!UART_MUX!!
S!@baseboard_fab2_lib.baseboard_fab2(sch_1):page168_i5@mstr_discrete.diode(chips)!DIODE_SM-1N4148W,IC,D89194-001!CR1L4!//jf4cfls225.pdx.intel.com/apd_proj/ppg_lib/epg_masterlib/logical/mstr_discrete/diode/chips/chips.prt!DIODE!DIODE_SM-1N4148W,IC,D89194-001!DIODE_SM!!!F2219!!UART_MUX!!
S!@baseboard_fab2_lib.baseboard_fab2(sch_1):page102_i8@mstr_discrete.ferrite(chips)!FERRITE_SMLF-600,FB,656554-043!FB6P1!//jf4cfls225.pdx.intel.com/apd_proj/ppg_lib/epg_masterlib/logical/mstr_discrete/ferrite/chips/chips.prt!FERRITE!FERRITE_SMLF-600,FB,656554-043!FERRITE!!!F2183!!DB1200ZL!!
S!@baseboard_fab2_lib.baseboard_fab2(sch_1):page101_i114@mstr_discrete.ferrite(chips)!FERRITE_SMLF-600,FB,656554-043!FB2T2!//jf4cfls225.pdx.intel.com/apd_proj/ppg_lib/epg_masterlib/logical/mstr_discrete/ferrite/chips/chips.prt!FERRITE!FERRITE_SMLF-600,FB,656554-043!FERRITE!!!F2184!!SYS_CLOCK!!
S!@baseboard_fab2_lib.baseboard_fab2(sch_1):page101_i34@mstr_clock.ics9fgp204(chips)!ICS9FGP204_MLFP-IC,E95226-001!EU8F2!//jf4cfls225.pdx.intel.com/apd_proj/ppg_lib/epg_masterlib/logical/mstr_clock/ics9fgp204/chips/chips.prt!ICS9FGP204!ICS9FGP204_MLFP-IC,E95226-001!ICS9FGP204_MLFP!!!F2119!!SYS_CLOCK!!
S!@baseboard_fab2_lib.baseboard_fab2(sch_1):page102_i26@mstr_discrete.res(chips)!RES_0603-2.2,1.0%,1/10W,CHIP,GA!R6P25!//jf4cfls225.pdx.intel.com/apd_proj/ppg_lib/epg_masterlib/logical/mstr_discrete/res/chips/chips.prt!RES!RES_0603-2.2,1.0%,1/10W,CHIP,G22026-127!RES!!!F258!!DB1200ZL!!
S!@baseboard_fab2_lib.baseboard_fab2(sch_1):page102_i21@mstr_discrete.res(chips)!RES_0603-2.2,1.0%,1/10W,CHIP,GA!R3D14!//jf4cfls225.pdx.intel.com/apd_proj/ppg_lib/epg_masterlib/logical/mstr_discrete/res/chips/chips.prt!RES!RES_0603-2.2,1.0%,1/10W,CHIP,G22026-127!RES!!!F259!!DB1200ZL!!
S!@baseboard_fab2_lib.baseboard_fab2(sch_1):page101_i105@mstr_discrete.res(chips)!RES_0603-2.2,1.0%,1/10W,CHIP,GA!R2T21!//jf4cfls225.pdx.intel.com/apd_proj/ppg_lib/epg_masterlib/logical/mstr_discrete/res/chips/chips.prt!RES!RES_0603-2.2,1.0%,1/10W,CHIP,G22026-127!RES!!!F262!!SYS_CLOCK!!
S!@baseboard_fab2_lib.baseboard_fab2(sch_1):page101_i95@mstr_discrete.res(chips)!RES_0603-2.2,1.0%,1/10W,CHIP,GA!R2T52!//jf4cfls225.pdx.intel.com/apd_proj/ppg_lib/epg_masterlib/logical/mstr_discrete/res/chips/chips.prt!RES!RES_0603-2.2,1.0%,1/10W,CHIP,G22026-127!RES!!!F260!!SYS_CLOCK!!
S!@baseboard_fab2_lib.baseboard_fab2(sch_1):page101_i94@mstr_discrete.res(chips)!RES_0603-2.2,1.0%,1/10W,CHIP,GA!R2T23!//jf4cfls225.pdx.intel.com/apd_proj/ppg_lib/epg_masterlib/logical/mstr_discrete/res/chips/chips.prt!RES!RES_0603-2.2,1.0%,1/10W,CHIP,G22026-127!RES!!!F261!!SYS_CLOCK!!
S!@baseboard_fab2_lib.baseboard_fab2(sch_1):page139_i76@mstr_discrete.cap(chips)!CAP_0402LF-0.039UF,25V,10%,X7RA!C9E7!//jf4cfls225.pdx.intel.com/apd_proj/ppg_lib/epg_masterlib/logical/mstr_discrete/cap/chips/chips.prt!CAP!CAP_0402LF-0.039UF,25V,10%,X7R,A36096-063!CAP!!!F3490!!NIC_SPRV!!
S!@baseboard_fab2_lib.baseboard_fab2(sch_1):page177_i42@mstr_discrete.led(chips)!LED_1NCLF-GREEN,IC,C96565-011!DS9A2!//jf4cfls225.pdx.intel.com/apd_proj/ppg_lib/epg_masterlib/logical/mstr_discrete/led/chips/chips.prt!LED!LED_1NCLF-GREEN,IC,C96565-011!LED_1NCLF!!!F2037!!MIO_CHASSIS!!
S!@baseboard_fab2_lib.baseboard_fab2(sch_1):page139_i72@mstr_intel.springville(chips)!SPRINGVILLE_SM1-IC,G47144-004!EU9E1!//jf4cfls225.pdx.intel.com/apd_proj/ppg_lib/epg_masterlib/logical/mstr_intel/springville/chips/chips.prt!SPRINGVILLE!SPRINGVILLE_SM1-IC,G47144-004!SPRINGVILLE_SM1!!!F67!!NIC_SPRV!!
S!@baseboard_fab2_lib.baseboard_fab2(sch_1):page195_i56@mstr_misc.mtg_keyhole(chips)!MTG_KEYHOLE_TH-EMPTY,NA!TH1A1!//jf4cfls225.pdx.intel.com/apd_proj/ppg_lib/epg_masterlib/logical/mstr_misc/mtg_keyhole/chips/chips.prt!MTG_KEYHOLE!MTG_KEYHOLE_TH-EMPTY,NA!MTG_KEYHOLE_TH!!!F2013!!MOUNTING_HOLES!!
S!@baseboard_fab2_lib.baseboard_fab2(sch_1):page195_i62@mstr_misc.mtg_keyhole(chips)!MTG_KEYHOLE_TH-EMPTY,NA!TH4A1!//jf4cfls225.pdx.intel.com/apd_proj/ppg_lib/epg_masterlib/logical/mstr_misc/mtg_keyhole/chips/chips.prt!MTG_KEYHOLE!MTG_KEYHOLE_TH-EMPTY,NA!MTG_KEYHOLE_TH!!!F2012!!MOUNTING_HOLES!!
S!@baseboard_fab2_lib.baseboard_fab2(sch_1):page195_i65@mstr_misc.mtg_keyhole(chips)!MTG_KEYHOLE_TH-EMPTY,NA!TH7A1!//jf4cfls225.pdx.intel.com/apd_proj/ppg_lib/epg_masterlib/logical/mstr_misc/mtg_keyhole/chips/chips.prt!MTG_KEYHOLE!MTG_KEYHOLE_TH-EMPTY,NA!MTG_KEYHOLE_TH!!!F2010!!MOUNTING_HOLES!!
S!@baseboard_fab2_lib.baseboard_fab2(sch_1):page195_i54@mstr_misc.mtg_keyhole(chips)!MTG_KEYHOLE_TH-EMPTY,NA!TH9A1!//jf4cfls225.pdx.intel.com/apd_proj/ppg_lib/epg_masterlib/logical/mstr_misc/mtg_keyhole/chips/chips.prt!MTG_KEYHOLE!MTG_KEYHOLE_TH-EMPTY,NA!MTG_KEYHOLE_TH!!!F2008!!MOUNTING_HOLES!!
S!@baseboard_fab2_lib.baseboard_fab2(sch_1):page195_i49@mstr_misc.mtg_keyhole(chips)!MTG_KEYHOLE_TH-EMPTY,NA!TH4G1!//jf4cfls225.pdx.intel.com/apd_proj/ppg_lib/epg_masterlib/logical/mstr_misc/mtg_keyhole/chips/chips.prt!MTG_KEYHOLE!MTG_KEYHOLE_TH-EMPTY,NA!MTG_KEYHOLE_TH!!!F2011!!MOUNTING_HOLES!!
S!@baseboard_fab2_lib.baseboard_fab2(sch_1):page195_i67@mstr_misc.mtg_keyhole(chips)!MTG_KEYHOLE_TH-EMPTY,NA!TH7G1!//jf4cfls225.pdx.intel.com/apd_proj/ppg_lib/epg_masterlib/logical/mstr_misc/mtg_keyhole/chips/chips.prt!MTG_KEYHOLE!MTG_KEYHOLE_TH-EMPTY,NA!MTG_KEYHOLE_TH!!!F2009!!MOUNTING_HOLES!!
S!@baseboard_fab2_lib.baseboard_fab2(sch_1):page195_i52@mstr_misc.mtg_keyhole(chips)!MTG_KEYHOLE_TH-EMPTY,NA!TH9G1!//jf4cfls225.pdx.intel.com/apd_proj/ppg_lib/epg_masterlib/logical/mstr_misc/mtg_keyhole/chips/chips.prt!MTG_KEYHOLE!MTG_KEYHOLE_TH-EMPTY,NA!MTG_KEYHOLE_TH!!!F2007!!MOUNTING_HOLES!!
S!@baseboard_fab2_lib.baseboard_fab2(sch_1):page213_i30@mstr_discrete.res(chips)!RES_0402-110,1%,1/16W,EMPTY,G2A!R6P33!//jf4cfls225.pdx.intel.com/apd_proj/ppg_lib/epg_masterlib/logical/mstr_discrete/res/chips/chips.prt!RES!RES_0402-110,1%,1/16W,EMPTY,G21796-203!RES!!!F1110!!PVCCIO_CPU1!!
S!@baseboard_fab2_lib.baseboard_fab2(sch_1):page115_i90@mstr_discrete.res(chips)!RES_0402-113,1%,1/16W,CHIP,G21A!R8B9!//jf4cfls225.pdx.intel.com/apd_proj/ppg_lib/epg_masterlib/logical/mstr_discrete/res/chips/chips.prt!RES!RES_0402-113,1%,1/16W,CHIP,G21796-341!RES!!!F1109!!SB!!
S!@baseboard_fab2_lib.baseboard_fab2(sch_1):page199_i13@mstr_discrete.res(chips)!RES_0402-11K,1%,1/16W,CHIP,G21A!R1D42!//jf4cfls225.pdx.intel.com/apd_proj/ppg_lib/epg_masterlib/logical/mstr_discrete/res/chips/chips.prt!RES!RES_0402-11K,1%,1/16W,CHIP,G21796-220!RES!!!F1108!!HOT_SWAP!!
S!@baseboard_fab2_lib.baseboard_fab2(sch_1):page169_i163@mstr_discrete.res(chips)!RES_0402-2.7K,1%,1/16W,CHIP,G2A!R1U49!//jf4cfls225.pdx.intel.com/apd_proj/ppg_lib/epg_masterlib/logical/mstr_discrete/res/chips/chips.prt!RES!RES_0402-2.7K,1%,1/16W,CHIP,G21796-344!RES!!!F991!!BMC_VOLT_MONITOR!!
S!@baseboard_fab2_lib.baseboard_fab2(sch_1):page169_i164@mstr_discrete.res(chips)!RES_0402-2.7K,1%,1/16W,CHIP,G2A!R9G35!//jf4cfls225.pdx.intel.com/apd_proj/ppg_lib/epg_masterlib/logical/mstr_discrete/res/chips/chips.prt!RES!RES_0402-2.7K,1%,1/16W,CHIP,G21796-344!RES!!!F987!!!!
S!@baseboard_fab2_lib.baseboard_fab2(sch_1):page164_i14@mstr_discrete.res(chips)!RES_0402-2.7K,1%,1/16W,CHIP,G2A!R1T4!//jf4cfls225.pdx.intel.com/apd_proj/ppg_lib/epg_masterlib/logical/mstr_discrete/res/chips/chips.prt!RES!RES_0402-2.7K,1%,1/16W,CHIP,G21796-344!RES!!!F994!!BMC_MISC!!
S!@baseboard_fab2_lib.baseboard_fab2(sch_1):page164_i28@mstr_discrete.res(chips)!RES_0402-2.7K,1%,1/16W,CHIP,G2A!R1U23!//jf4cfls225.pdx.intel.com/apd_proj/ppg_lib/epg_masterlib/logical/mstr_discrete/res/chips/chips.prt!RES!RES_0402-2.7K,1%,1/16W,CHIP,G21796-344!RES!!!F993!!BMC_MISC!!
S!@baseboard_fab2_lib.baseboard_fab2(sch_1):page164_i25@mstr_discrete.res(chips)!RES_0402-2.7K,1%,1/16W,CHIP,G2A!R1U24!//jf4cfls225.pdx.intel.com/apd_proj/ppg_lib/epg_masterlib/logical/mstr_discrete/res/chips/chips.prt!RES!RES_0402-2.7K,1%,1/16W,CHIP,G21796-344!RES!!!F992!!BMC_MISC!!
S!@baseboard_fab2_lib.baseboard_fab2(sch_1):page200_i210@mstr_discrete.res(chips)!RES_0402-2.7K,1%,1/16W,CHIP,G2A!R9P4!//jf4cfls225.pdx.intel.com/apd_proj/ppg_lib/epg_masterlib/logical/mstr_discrete/res/chips/chips.prt!RES!RES_0402-2.7K,1%,1/16W,CHIP,G21796-344!RES!!!F989!!HOT_SWAP!!
S!@baseboard_fab2_lib.baseboard_fab2(sch_1):page200_i86@mstr_discrete.res(chips)!RES_0402-2.7K,1%,1/16W,CHIP,G2A!R9P20!//jf4cfls225.pdx.intel.com/apd_proj/ppg_lib/epg_masterlib/logical/mstr_discrete/res/chips/chips.prt!RES!RES_0402-2.7K,1%,1/16W,CHIP,G21796-344!RES!!!F988!!HOT_SWAP!!
S!@baseboard_fab2_lib.baseboard_fab2(sch_1):page144_i457@mstr_discrete.res(chips)!RES_0402-2.7K,1%,1/16W,CHIP,G2A!R9G8!//jf4cfls225.pdx.intel.com/apd_proj/ppg_lib/epg_masterlib/logical/mstr_discrete/res/chips/chips.prt!RES!RES_0402-2.7K,1%,1/16W,CHIP,G21796-344!RES!!!F990!!BMC!!
S!@baseboard_fab2_lib.baseboard_fab2(sch_1):page21_i217@chpset_lib.socket_p_mech_a(chips)!SOCKET_P_MECH_A_LEFT-P0,PLASTIA!XLU1!//jf4cfls225.pdx.intel.com/apd_proj/ppg_lib/chpset_lib/logical/socket_p_mech_a/chips/chips.prt!SOCKET_P_MECH_A!SOCKET_P_MECH_A_LEFT-P0,PLASTIC,H37604-201!SOCKET_P_MECH_A_LEFT!!!TF-6347!!CPU0!!
S!@baseboard_fab2_lib.baseboard_fab2(sch_1):page55_i153@chpset_lib.socket_p_mech_a(chips)!SOCKET_P_MECH_A_LEFT-P0,PLASTIA!XLU2!//jf4cfls225.pdx.intel.com/apd_proj/ppg_lib/chpset_lib/logical/socket_p_mech_a/chips/chips.prt!SOCKET_P_MECH_A!SOCKET_P_MECH_A_LEFT-P0,PLASTIC,H37604-201!SOCKET_P_MECH_A_LEFT!!!TF-6346!!CPU1!!
S!@baseboard_fab2_lib.baseboard_fab2(sch_1):page21_i216@chpset_lib.socket_p_mech_a(chips)!SOCKET_P_MECH_A_RIGHT-P0,PLASTA!XRU1!//jf4cfls225.pdx.intel.com/apd_proj/ppg_lib/chpset_lib/logical/socket_p_mech_a/chips/chips.prt!SOCKET_P_MECH_A!SOCKET_P_MECH_A_RIGHT-P0,PLASTIC,H37604-101!SOCKET_P_MECH_A_RIGHT!!!TF-6345!!CPU0!!
S!@baseboard_fab2_lib.baseboard_fab2(sch_1):page55_i152@chpset_lib.socket_p_mech_a(chips)!SOCKET_P_MECH_A_RIGHT-P0,PLASTA!XRU2!//jf4cfls225.pdx.intel.com/apd_proj/ppg_lib/chpset_lib/logical/socket_p_mech_a/chips/chips.prt!SOCKET_P_MECH_A!SOCKET_P_MECH_A_RIGHT-P0,PLASTIC,H37604-101!SOCKET_P_MECH_A_RIGHT!!!TF-6344!!CPU1!!
S!@baseboard_fab2_lib.baseboard_fab2(sch_1):page149_i140@mstr_discrete.ferrite(chips)!FERRITE_SMLF-300,FB,693286-046!FB1U1!//jf4cfls225.pdx.intel.com/apd_proj/ppg_lib/epg_masterlib/logical/mstr_discrete/ferrite/chips/chips.prt!FERRITE!FERRITE_SMLF-300,FB,693286-046!FERRITE!!!F2187!!BMC!!
S!@baseboard_fab2_lib.baseboard_fab2(sch_1):page149_i107@mstr_discrete.ferrite(chips)!FERRITE_SMLF-300,FB,693286-046!FB9F1!//jf4cfls225.pdx.intel.com/apd_proj/ppg_lib/epg_masterlib/logical/mstr_discrete/ferrite/chips/chips.prt!FERRITE!FERRITE_SMLF-300,FB,693286-046!FERRITE!!!F2186!!BMC!!
S!@baseboard_fab2_lib.baseboard_fab2(sch_1):page149_i122@mstr_discrete.ferrite(chips)!FERRITE_SMLF-300,FB,693286-046!FB1T2!//jf4cfls225.pdx.intel.com/apd_proj/ppg_lib/epg_masterlib/logical/mstr_discrete/ferrite/chips/chips.prt!FERRITE!FERRITE_SMLF-300,FB,693286-046!FERRITE!!!F2188!!BMC!!
S!@baseboard_fab2_lib.baseboard_fab2(sch_1):page236_i45@mstr_discrete.inductor(chips)!INDUCTOR_SM-0.3UH,IND,D92183-0A!L7A4!//jf4cfls225.pdx.intel.com/apd_proj/ppg_lib/epg_masterlib/logical/mstr_discrete/inductor/chips/chips.prt!INDUCTOR!INDUCTOR_SM-0.3UH,IND,D92183-036!INDUCTOR!!!F2097!!P1V05_PCH_STBY_VR!!
S!@baseboard_fab2_lib.baseboard_fab2(sch_1):page236_i10@mstr_discrete.inductor(chips)!INDUCTOR_SM-0.3UH,IND,D92183-0A!L7A2!//jf4cfls225.pdx.intel.com/apd_proj/ppg_lib/epg_masterlib/logical/mstr_discrete/inductor/chips/chips.prt!INDUCTOR!INDUCTOR_SM-0.3UH,IND,D92183-036!INDUCTOR!!!F2098!!PVNN_PCH_STBY!!
S!@baseboard_fab2_lib.baseboard_fab2(sch_1):page205_i7@mstr_discrete.inductor(chips)!INDUCTOR_SM-0.3UH,IND,D92183-0A!L4C2!//jf4cfls225.pdx.intel.com/apd_proj/ppg_lib/epg_masterlib/logical/mstr_discrete/inductor/chips/chips.prt!INDUCTOR!INDUCTOR_SM-0.3UH,IND,D92183-036!INDUCTOR!!!F2099!!PVSA_CPU0_PWR_VR!!
S!@baseboard_fab2_lib.baseboard_fab2(sch_1):page210_i10@mstr_discrete.inductor(chips)!INDUCTOR_SM-0.3UH,IND,D92183-0A!L1C1!//jf4cfls225.pdx.intel.com/apd_proj/ppg_lib/epg_masterlib/logical/mstr_discrete/inductor/chips/chips.prt!INDUCTOR!INDUCTOR_SM-0.3UH,IND,D92183-036!INDUCTOR!!!F2100!!PVSA_CPU1_PWR_VR!!
S!@baseboard_fab2_lib.baseboard_fab2(sch_1):page232_i239@mstr_discrete.inductor(chips)!INDUCTOR_SM-0.47UH,IND,E13358-A!L7B1!//jf4cfls225.pdx.intel.com/apd_proj/ppg_lib/epg_masterlib/logical/mstr_discrete/inductor/chips/chips.prt!INDUCTOR!INDUCTOR_SM-0.47UH,IND,E13358-018!INDUCTOR!!!F2094!!PVPP_KLM_VR!!
S!@baseboard_fab2_lib.baseboard_fab2(sch_1):page233_i277@mstr_discrete.inductor(chips)!INDUCTOR_SM-0.47UH,IND,E13358-A!L4G1!//jf4cfls225.pdx.intel.com/apd_proj/ppg_lib/epg_masterlib/logical/mstr_discrete/inductor/chips/chips.prt!INDUCTOR!INDUCTOR_SM-0.47UH,IND,E13358-018!INDUCTOR!!!F2095!!PVPP_GHJ_VR!!
S!@baseboard_fab2_lib.baseboard_fab2(sch_1):page234_i164@mstr_discrete.inductor(chips)!INDUCTOR_SM-0.47UH,IND,E13358-A!L4A1!//jf4cfls225.pdx.intel.com/apd_proj/ppg_lib/epg_masterlib/logical/mstr_discrete/inductor/chips/chips.prt!INDUCTOR!INDUCTOR_SM-0.47UH,IND,E13358-018!INDUCTOR!!!F2096!!PVPP_KLM_VR!!
S!@baseboard_fab2_lib.baseboard_fab2(sch_1):page231_i178@mstr_discrete.inductor(chips)!INDUCTOR_SM-0.47UH,IND,E13358-A!L7F1!//jf4cfls225.pdx.intel.com/apd_proj/ppg_lib/epg_masterlib/logical/mstr_discrete/inductor/chips/chips.prt!INDUCTOR!INDUCTOR_SM-0.47UH,IND,E13358-018!INDUCTOR!!!F2093!!PVPP_KLM_VR!!
S!@baseboard_fab2_lib.baseboard_fab2(sch_1):page195_i78@mstr_conn.conn12_g98257001(chips)!CONN12_G98257001_THMT-CONN,G98A!J1D1!//jf4cfls225.pdx.intel.com/apd_proj/ppg_lib/epg_masterlib/logical/mstr_conn/conn12_g98257001/chips/chips.prt!CONN12_G98257001!CONN12_G98257001_THMT-CONN,G98257-001!CONN12_G98257001_THMT!!!F2255!!HOT_SWAP!!
S!@baseboard_fab2_lib.baseboard_fab2(sch_1):page195_i29@mstr_conn.conn12_g98257001(chips)!CONN12_G98257001_THMT-CONN,G98A!J1E1!//jf4cfls225.pdx.intel.com/apd_proj/ppg_lib/epg_masterlib/logical/mstr_conn/conn12_g98257001/chips/chips.prt!CONN12_G98257001!CONN12_G98257001_THMT-CONN,G98257-001!CONN12_G98257001_THMT!!!F2254!!HOT_SWAP!!
S!@baseboard_fab2_lib.baseboard_fab2(sch_1):page127_i8@mstr_discrete.ferrite(chips)!FERRITE_SM-120,FB,693286-027!FB3M1!//jf4cfls225.pdx.intel.com/apd_proj/ppg_lib/epg_masterlib/logical/mstr_discrete/ferrite/chips/chips.prt!FERRITE!FERRITE_SM-120,FB,693286-027!FERRITE_SM!!!F2202!!SB_FILTER_PLL0!!
S!@baseboard_fab2_lib.baseboard_fab2(sch_1):page127_i17@mstr_discrete.ferrite(chips)!FERRITE_SM-120,FB,693286-027!FB3M2!//jf4cfls225.pdx.intel.com/apd_proj/ppg_lib/epg_masterlib/logical/mstr_discrete/ferrite/chips/chips.prt!FERRITE!FERRITE_SM-120,FB,693286-027!FERRITE_SM!!!F2201!!SB_FILTER_PLL1!!
S!@baseboard_fab2_lib.baseboard_fab2(sch_1):page127_i26@mstr_discrete.ferrite(chips)!FERRITE_SM-120,FB,693286-027!FB3M3!//jf4cfls225.pdx.intel.com/apd_proj/ppg_lib/epg_masterlib/logical/mstr_discrete/ferrite/chips/chips.prt!FERRITE!FERRITE_SM-120,FB,693286-027!FERRITE_SM!!!F2200!!SB_FILTER_XTAL!!
S!@baseboard_fab2_lib.baseboard_fab2(sch_1):page127_i56@mstr_discrete.ferrite(chips)!FERRITE_SM-120,FB,693286-027!FB3M4!//jf4cfls225.pdx.intel.com/apd_proj/ppg_lib/epg_masterlib/logical/mstr_discrete/ferrite/chips/chips.prt!FERRITE!FERRITE_SM-120,FB,693286-027!FERRITE_SM!!!F2199!!SB_FILTER_ISCLK!!
S!@baseboard_fab2_lib.baseboard_fab2(sch_1):page127_i46@mstr_discrete.ferrite(chips)!FERRITE_SM-120,FB,693286-027!FB2M1!//jf4cfls225.pdx.intel.com/apd_proj/ppg_lib/epg_masterlib/logical/mstr_discrete/ferrite/chips/chips.prt!FERRITE!FERRITE_SM-120,FB,693286-027!FERRITE_SM!!!F2204!!SB_FILTER_VM20!!
S!@baseboard_fab2_lib.baseboard_fab2(sch_1):page127_i69@mstr_discrete.ferrite(chips)!FERRITE_SM-120,FB,693286-027!FB2M2!//jf4cfls225.pdx.intel.com/apd_proj/ppg_lib/epg_masterlib/logical/mstr_discrete/ferrite/chips/chips.prt!FERRITE!FERRITE_SM-120,FB,693286-027!FERRITE_SM!!!F2203!!SB_FILTER_VM26!!
S!@baseboard_fab2_lib.baseboard_fab2(sch_1):page141_i28@mstr_discrete.res(chips)!RES_0402-330.0,5%,1/16W,CHIP,GA!R9G3!//jf4cfls225.pdx.intel.com/apd_proj/ppg_lib/epg_masterlib/logical/mstr_discrete/res/chips/chips.prt!RES!RES_0402-330.0,5%,1/16W,CHIP,G21497-028!RES!!!F661!!NIC_SPRV!!
S!@baseboard_fab2_lib.baseboard_fab2(sch_1):page141_i30@mstr_discrete.res(chips)!RES_0402-330.0,5%,1/16W,CHIP,GA!R9G2!//jf4cfls225.pdx.intel.com/apd_proj/ppg_lib/epg_masterlib/logical/mstr_discrete/res/chips/chips.prt!RES!RES_0402-330.0,5%,1/16W,CHIP,G21497-028!RES!!!F662!!NIC_SPRV!!
S!@baseboard_fab2_lib.baseboard_fab2(sch_1):page141_i54@mstr_discrete.res(chips)!RES_0402-330.0,5%,1/16W,CHIP,GA!R9G1!//jf4cfls225.pdx.intel.com/apd_proj/ppg_lib/epg_masterlib/logical/mstr_discrete/res/chips/chips.prt!RES!RES_0402-330.0,5%,1/16W,CHIP,G21497-028!RES!!!F663!!NIC_SPRV!!
S!@baseboard_fab2_lib.baseboard_fab2(sch_1):page164_i5@mstr_discrete.res(chips)!RES_0402-1.00K,1%,1/16W,EMPTY,A!R1T10!//jf4cfls225.pdx.intel.com/apd_proj/ppg_lib/epg_masterlib/logical/mstr_discrete/res/chips/chips.prt!RES!RES_0402-1.00K,1%,1/16W,EMPTY,G21796-026!RES!!!F1428!!BMC_MISC!!
S!@baseboard_fab2_lib.baseboard_fab2(sch_1):page164_i21@mstr_discrete.res(chips)!RES_0402-1.00K,1%,1/16W,EMPTY,A!R1U17!//jf4cfls225.pdx.intel.com/apd_proj/ppg_lib/epg_masterlib/logical/mstr_discrete/res/chips/chips.prt!RES!RES_0402-1.00K,1%,1/16W,EMPTY,G21796-026!RES!!!F1427!!BMC_MISC!!
S!@baseboard_fab2_lib.baseboard_fab2(sch_1):page164_i19@mstr_discrete.res(chips)!RES_0402-1.00K,1%,1/16W,EMPTY,A!R1U18!//jf4cfls225.pdx.intel.com/apd_proj/ppg_lib/epg_masterlib/logical/mstr_discrete/res/chips/chips.prt!RES!RES_0402-1.00K,1%,1/16W,EMPTY,G21796-026!RES!!!F1426!!BMC_MISC!!
S!@baseboard_fab2_lib.baseboard_fab2(sch_1):page192_i57@mstr_discrete.res(chips)!RES_0402-1.00K,1%,1/16W,EMPTY,A!R7E19!//jf4cfls225.pdx.intel.com/apd_proj/ppg_lib/epg_masterlib/logical/mstr_discrete/res/chips/chips.prt!RES!RES_0402-1.00K,1%,1/16W,EMPTY,G21796-026!RES!!!F1410!!CPLD!!
S!@baseboard_fab2_lib.baseboard_fab2(sch_1):page113_i199@mstr_discrete.res(chips)!RES_0402-1.00K,1%,1/16W,EMPTY,A!R1M23!//jf4cfls225.pdx.intel.com/apd_proj/ppg_lib/epg_masterlib/logical/mstr_discrete/res/chips/chips.prt!RES!RES_0402-1.00K,1%,1/16W,EMPTY,G21796-026!RES!!!F1411!!DEBUG!!
S!@baseboard_fab2_lib.baseboard_fab2(sch_1):page125_i83@mstr_discrete.res(chips)!RES_0402-1.00K,1%,1/16W,EMPTY,A!R2N14!//jf4cfls225.pdx.intel.com/apd_proj/ppg_lib/epg_masterlib/logical/mstr_discrete/res/chips/chips.prt!RES!RES_0402-1.00K,1%,1/16W,EMPTY,G21796-026!RES!!!F1425!!SB!!
S!@baseboard_fab2_lib.baseboard_fab2(sch_1):page126_i6@mstr_discrete.res(chips)!RES_0402-1.00K,1%,1/16W,EMPTY,A!R7D19!//jf4cfls225.pdx.intel.com/apd_proj/ppg_lib/epg_masterlib/logical/mstr_discrete/res/chips/chips.prt!RES!RES_0402-1.00K,1%,1/16W,EMPTY,G21796-026!RES!!!F1418!!SB!!
S!@baseboard_fab2_lib.baseboard_fab2(sch_1):page125_i21@mstr_discrete.res(chips)!RES_0402-1.00K,1%,1/16W,EMPTY,A!R8E6!//jf4cfls225.pdx.intel.com/apd_proj/ppg_lib/epg_masterlib/logical/mstr_discrete/res/chips/chips.prt!RES!RES_0402-1.00K,1%,1/16W,EMPTY,G21796-026!RES!!!F1414!!SB!!
S!@baseboard_fab2_lib.baseboard_fab2(sch_1):page125_i78@mstr_discrete.res(chips)!RES_0402-1.00K,1%,1/16W,EMPTY,A!R3N17!//jf4cfls225.pdx.intel.com/apd_proj/ppg_lib/epg_masterlib/logical/mstr_discrete/res/chips/chips.prt!RES!RES_0402-1.00K,1%,1/16W,EMPTY,G21796-026!RES!!!F1421!!SB!!
S!@baseboard_fab2_lib.baseboard_fab2(sch_1):page134_i18@mstr_discrete.res(chips)!RES_0402-1.00K,1%,1/16W,EMPTY,A!R2N24!//jf4cfls225.pdx.intel.com/apd_proj/ppg_lib/epg_masterlib/logical/mstr_discrete/res/chips/chips.prt!RES!RES_0402-1.00K,1%,1/16W,EMPTY,G21796-026!RES!!!F1424!!SB!!
S!@baseboard_fab2_lib.baseboard_fab2(sch_1):page170_i63@mstr_discrete.res(chips)!RES_0402-1.00K,1%,1/16W,EMPTY,A!R2P11!//jf4cfls225.pdx.intel.com/apd_proj/ppg_lib/epg_masterlib/logical/mstr_discrete/res/chips/chips.prt!RES!RES_0402-1.00K,1%,1/16W,EMPTY,G21796-026!RES!!!F1423!!PROC_SIDEBAND!!
S!@baseboard_fab2_lib.baseboard_fab2(sch_1):page111_i95@mstr_discrete.res(chips)!RES_0402-1.00K,1%,1/16W,EMPTY,A!R9A1!//jf4cfls225.pdx.intel.com/apd_proj/ppg_lib/epg_masterlib/logical/mstr_discrete/res/chips/chips.prt!RES!RES_0402-1.00K,1%,1/16W,EMPTY,G21796-026!RES!!!F1412!!DEBUG!!
S!@baseboard_fab2_lib.baseboard_fab2(sch_1):page162_i24@mstr_discrete.res(chips)!RES_0402-1.00K,1%,1/16W,EMPTY,A!R8F35!//jf4cfls225.pdx.intel.com/apd_proj/ppg_lib/epg_masterlib/logical/mstr_discrete/res/chips/chips.prt!RES!RES_0402-1.00K,1%,1/16W,EMPTY,G21796-026!RES!!!F1413!!BMC_BOOT_SPI!!
S!@baseboard_fab2_lib.baseboard_fab2(sch_1):page125_i41@mstr_discrete.res(chips)!RES_0402-1.00K,1%,1/16W,EMPTY,A!R8C17!//jf4cfls225.pdx.intel.com/apd_proj/ppg_lib/epg_masterlib/logical/mstr_discrete/res/chips/chips.prt!RES!RES_0402-1.00K,1%,1/16W,EMPTY,G21796-026!RES!!!F1417!!SB!!
S!@baseboard_fab2_lib.baseboard_fab2(sch_1):page125_i24@mstr_discrete.res(chips)!RES_0402-1.00K,1%,1/16W,EMPTY,A!R8E4!//jf4cfls225.pdx.intel.com/apd_proj/ppg_lib/epg_masterlib/logical/mstr_discrete/res/chips/chips.prt!RES!RES_0402-1.00K,1%,1/16W,EMPTY,G21796-026!RES!!!F1415!!SB!!
S!@baseboard_fab2_lib.baseboard_fab2(sch_1):page125_i11@mstr_discrete.res(chips)!RES_0402-1.00K,1%,1/16W,EMPTY,A!R2R11!//jf4cfls225.pdx.intel.com/apd_proj/ppg_lib/epg_masterlib/logical/mstr_discrete/res/chips/chips.prt!RES!RES_0402-1.00K,1%,1/16W,EMPTY,G21796-026!RES!!!F1422!!SB!!
S!@baseboard_fab2_lib.baseboard_fab2(sch_1):page125_i50@mstr_discrete.res(chips)!RES_0402-1.00K,1%,1/16W,EMPTY,A!R8D5!//jf4cfls225.pdx.intel.com/apd_proj/ppg_lib/epg_masterlib/logical/mstr_discrete/res/chips/chips.prt!RES!RES_0402-1.00K,1%,1/16W,EMPTY,G21796-026!RES!!!F1416!!SB!!
S!@baseboard_fab2_lib.baseboard_fab2(sch_1):page209_i3@mstr_discrete.res(chips)!RES_0402-1.00K,1%,1/16W,EMPTY,A!R1E5!//jf4cfls225.pdx.intel.com/apd_proj/ppg_lib/epg_masterlib/logical/mstr_discrete/res/chips/chips.prt!RES!RES_0402-1.00K,1%,1/16W,EMPTY,G21796-026!RES!!!F1429!!PVCCIN_CPU1_VSENSE_VR!!
S!@baseboard_fab2_lib.baseboard_fab2(sch_1):page205_i37@mstr_discrete.res(chips)!RES_0402-1.00K,1%,1/16W,EMPTY,A!R4C3!//jf4cfls225.pdx.intel.com/apd_proj/ppg_lib/epg_masterlib/logical/mstr_discrete/res/chips/chips.prt!RES!RES_0402-1.00K,1%,1/16W,EMPTY,G21796-026!RES!!!F1420!!PVSA_CPU0_VSENSE_VR!!
S!@baseboard_fab2_lib.baseboard_fab2(sch_1):page204_i63@mstr_discrete.res(chips)!RES_0402-1.00K,1%,1/16W,EMPTY,A!R4E15!//jf4cfls225.pdx.intel.com/apd_proj/ppg_lib/epg_masterlib/logical/mstr_discrete/res/chips/chips.prt!RES!RES_0402-1.00K,1%,1/16W,EMPTY,G21796-026!RES!!!F1419!!PVCCIN_CPU0_VSENSE_VR!!
S!@baseboard_fab2_lib.baseboard_fab2(sch_1):page210_i34@mstr_discrete.res(chips)!RES_0402-1.00K,1%,1/16W,EMPTY,A!R1C6!//jf4cfls225.pdx.intel.com/apd_proj/ppg_lib/epg_masterlib/logical/mstr_discrete/res/chips/chips.prt!RES!RES_0402-1.00K,1%,1/16W,EMPTY,G21796-026!RES!!!F1430!!PVSA_CPU1_VSENSE_VR!!
S!@baseboard_fab2_lib.baseboard_fab2(sch_1):page126_i10@mstr_discrete.res(chips)!RES_0402-1.0M,1%,1/16W,CHIP,G2A!R2N10!//jf4cfls225.pdx.intel.com/apd_proj/ppg_lib/epg_masterlib/logical/mstr_discrete/res/chips/chips.prt!RES!RES_0402-1.0M,1%,1/16W,CHIP,G21796-021!RES!!!F1401!!SB_HEADERS!!
S!@baseboard_fab2_lib.baseboard_fab2(sch_1):page222_i37@mstr_discrete.res(chips)!RES_0402-1.0M,1%,1/16W,EMPTY,GA!R6L4!//jf4cfls225.pdx.intel.com/apd_proj/ppg_lib/epg_masterlib/logical/mstr_discrete/res/chips/chips.prt!RES!RES_0402-1.0M,1%,1/16W,EMPTY,G21796-021!RES!!!F1400!!VTT_DEF_PWR_VR!!
S!@baseboard_fab2_lib.baseboard_fab2(sch_1):page229_i34@mstr_discrete.res(chips)!RES_0402-1.0M,1%,1/16W,EMPTY,GA!R6U3!//jf4cfls225.pdx.intel.com/apd_proj/ppg_lib/epg_masterlib/logical/mstr_discrete/res/chips/chips.prt!RES!RES_0402-1.0M,1%,1/16W,EMPTY,G21796-021!RES!!!F1398!!VTT_GHJ_PWR_VR!!
S!@baseboard_fab2_lib.baseboard_fab2(sch_1):page221_i37@mstr_discrete.res(chips)!RES_0402-1.0M,1%,1/16W,EMPTY,GA!R6U15!//jf4cfls225.pdx.intel.com/apd_proj/ppg_lib/epg_masterlib/logical/mstr_discrete/res/chips/chips.prt!RES!RES_0402-1.0M,1%,1/16W,EMPTY,G21796-021!RES!!!F1397!!VTT_ABC_PWR_VR!!
S!@baseboard_fab2_lib.baseboard_fab2(sch_1):page230_i37@mstr_discrete.res(chips)!RES_0402-1.0M,1%,1/16W,EMPTY,GA!R6L5!//jf4cfls225.pdx.intel.com/apd_proj/ppg_lib/epg_masterlib/logical/mstr_discrete/res/chips/chips.prt!RES!RES_0402-1.0M,1%,1/16W,EMPTY,G21796-021!RES!!!F1399!!VTT_KLM_PWR_VR!!
S!@baseboard_fab2_lib.baseboard_fab2(sch_1):page137_i11@mstr_discrete.res(chips)!RES_0402-1.0M,1%,1/16W,EMPTY,GA!R7C11!//jf4cfls225.pdx.intel.com/apd_proj/ppg_lib/epg_masterlib/logical/mstr_discrete/res/chips/chips.prt!RES!RES_0402-1.0M,1%,1/16W,EMPTY,G21796-021!RES!!!F1396!!SB!!
S!@baseboard_fab2_lib.baseboard_fab2(sch_1):page226_i58@mstr_discrete.res(chips)!RES_0402-1.5K,1%,1/16W,CHIP,G2A!R1B9!//jf4cfls225.pdx.intel.com/apd_proj/ppg_lib/epg_masterlib/logical/mstr_discrete/res/chips/chips.prt!RES!RES_0402-1.5K,1%,1/16W,CHIP,G21796-003!RES!!!F1394!!VDDQ_KLM_PWR_VR!!
S!@baseboard_fab2_lib.baseboard_fab2(sch_1):page206_i56@mstr_discrete.res(chips)!RES_0402-1.5K,1%,1/16W,CHIP,G2A!R1C16!//jf4cfls225.pdx.intel.com/apd_proj/ppg_lib/epg_masterlib/logical/mstr_discrete/res/chips/chips.prt!RES!RES_0402-1.5K,1%,1/16W,CHIP,G21796-003!RES!!!F1393!!PVCCIN_CPU1_VR!!
S!@baseboard_fab2_lib.baseboard_fab2(sch_1):page223_i58@mstr_discrete.res(chips)!RES_0402-1.5K,1%,1/16W,CHIP,G2A!R1G24!//jf4cfls225.pdx.intel.com/apd_proj/ppg_lib/epg_masterlib/logical/mstr_discrete/res/chips/chips.prt!RES!RES_0402-1.5K,1%,1/16W,CHIP,G21796-003!RES!!!F1392!!VDDQ_GHJ_PWR_VR!!
S!@baseboard_fab2_lib.baseboard_fab2(sch_1):page235_i166@mstr_discrete.res(chips)!RES_0402-1.5K,1%,1/16W,CHIP,G2A!R2L10!//jf4cfls225.pdx.intel.com/apd_proj/ppg_lib/epg_masterlib/logical/mstr_discrete/res/chips/chips.prt!RES!RES_0402-1.5K,1%,1/16W,CHIP,G21796-003!RES!!!F1390!!PVNN_PCH_STBY!!
S!@baseboard_fab2_lib.baseboard_fab2(sch_1):page211_i32@mstr_discrete.res(chips)!RES_0402-1.5K,1%,1/16W,CHIP,G2A!R3P16!//jf4cfls225.pdx.intel.com/apd_proj/ppg_lib/epg_masterlib/logical/mstr_discrete/res/chips/chips.prt!RES!RES_0402-1.5K,1%,1/16W,CHIP,G21796-003!RES!!!F1389!!PVCCIO_CPU0!!
S!@baseboard_fab2_lib.baseboard_fab2(sch_1):page201_i55@mstr_discrete.res(chips)!RES_0402-1.5K,1%,1/16W,CHIP,G2A!R4D32!//jf4cfls225.pdx.intel.com/apd_proj/ppg_lib/epg_masterlib/logical/mstr_discrete/res/chips/chips.prt!RES!RES_0402-1.5K,1%,1/16W,CHIP,G21796-003!RES!!!F1388!!PVCCIN_CPU0_VR!!
S!@baseboard_fab2_lib.baseboard_fab2(sch_1):page213_i32@mstr_discrete.res(chips)!RES_0402-1.5K,1%,1/16W,CHIP,G2A!R4D57!//jf4cfls225.pdx.intel.com/apd_proj/ppg_lib/epg_masterlib/logical/mstr_discrete/res/chips/chips.prt!RES!RES_0402-1.5K,1%,1/16W,CHIP,G21796-003!RES!!!F1387!!PVCCIO_CPU1!!
S!@baseboard_fab2_lib.baseboard_fab2(sch_1):page218_i54@mstr_discrete.res(chips)!RES_0402-1.5K,1%,1/16W,CHIP,G2A!R7A16!//jf4cfls225.pdx.intel.com/apd_proj/ppg_lib/epg_masterlib/logical/mstr_discrete/res/chips/chips.prt!RES!RES_0402-1.5K,1%,1/16W,CHIP,G21796-003!RES!!!F1386!!VDDQ_DEF_PWR_VR!!
S!@baseboard_fab2_lib.baseboard_fab2(sch_1):page215_i337@mstr_discrete.res(chips)!RES_0402-1.5K,1%,1/16W,CHIP,G2A!R7G3!//jf4cfls225.pdx.intel.com/apd_proj/ppg_lib/epg_masterlib/logical/mstr_discrete/res/chips/chips.prt!RES!RES_0402-1.5K,1%,1/16W,CHIP,G21796-003!RES!!!F1385!!VDDQ_ABC_PWR_VR!!
S!@baseboard_fab2_lib.baseboard_fab2(sch_1):page144_i557@mstr_discrete.res(chips)!RES_0402-1.5K,1%,1/16W,CHIP,G2A!R1U52!//jf4cfls225.pdx.intel.com/apd_proj/ppg_lib/epg_masterlib/logical/mstr_discrete/res/chips/chips.prt!RES!RES_0402-1.5K,1%,1/16W,CHIP,G21796-003!RES!!!F1391!!BMC!!
S!@baseboard_fab2_lib.baseboard_fab2(sch_1):page181_i183@mstr_discrete.res(chips)!RES_0402-15.0K,1%,1/16W,CHIP,GA!R9T6!//jf4cfls225.pdx.intel.com/apd_proj/ppg_lib/epg_masterlib/logical/mstr_discrete/res/chips/chips.prt!RES!RES_0402-15.0K,1%,1/16W,CHIP,G21796-107!RES!!!F1103!!IO_SLOT!!
S!@baseboard_fab2_lib.baseboard_fab2(sch_1):page199_i41@mstr_discrete.res(chips)!RES_0402-15.0K,1%,1/16W,CHIP,GA!R9P18!//jf4cfls225.pdx.intel.com/apd_proj/ppg_lib/epg_masterlib/logical/mstr_discrete/res/chips/chips.prt!RES!RES_0402-15.0K,1%,1/16W,CHIP,G21796-107!RES!!!F1104!!HOT_SWAP!!
S!@baseboard_fab2_lib.baseboard_fab2(sch_1):page163_i15@mstr_discrete.res(chips)!RES_0402-2.0K,1%,1/16W,CHIP,G2A!R9M17!//jf4cfls225.pdx.intel.com/apd_proj/ppg_lib/epg_masterlib/logical/mstr_discrete/res/chips/chips.prt!RES!RES_0402-2.0K,1%,1/16W,CHIP,G21796-001!RES!!!F1037!!SMB_PE_HP_CPU1!!
S!@baseboard_fab2_lib.baseboard_fab2(sch_1):page163_i16@mstr_discrete.res(chips)!RES_0402-2.0K,1%,1/16W,CHIP,G2A!R9M16!//jf4cfls225.pdx.intel.com/apd_proj/ppg_lib/epg_masterlib/logical/mstr_discrete/res/chips/chips.prt!RES!RES_0402-2.0K,1%,1/16W,CHIP,G21796-001!RES!!!F1038!!SMB_PE_HP_CPU1!!
S!@baseboard_fab2_lib.baseboard_fab2(sch_1):page138_i87@mstr_discrete.res(chips)!RES_0402-2.0K,1%,1/16W,CHIP,G2A!R8D17!//jf4cfls225.pdx.intel.com/apd_proj/ppg_lib/epg_masterlib/logical/mstr_discrete/res/chips/chips.prt!RES!RES_0402-2.0K,1%,1/16W,CHIP,G21796-001!RES!!!F1039!!SMBUS!!
S!@baseboard_fab2_lib.baseboard_fab2(sch_1):page138_i88@mstr_discrete.res(chips)!RES_0402-2.0K,1%,1/16W,CHIP,G2A!R8D15!//jf4cfls225.pdx.intel.com/apd_proj/ppg_lib/epg_masterlib/logical/mstr_discrete/res/chips/chips.prt!RES!RES_0402-2.0K,1%,1/16W,CHIP,G21796-001!RES!!!F1040!!SMBUS!!
S!@baseboard_fab2_lib.baseboard_fab2(sch_1):page133_i120@mstr_discrete.res(chips)!RES_0402-2.0K,1%,1/16W,CHIP,G2A!R3N3!//jf4cfls225.pdx.intel.com/apd_proj/ppg_lib/epg_masterlib/logical/mstr_discrete/res/chips/chips.prt!RES!RES_0402-2.0K,1%,1/16W,CHIP,G21796-001!RES!!!F1041!!SB!!
S!@baseboard_fab2_lib.baseboard_fab2(sch_1):page178_i2@mstr_discrete.res(chips)!RES_0402-2.0K,1%,1/16W,CHIP,G2A!R2L12!//jf4cfls225.pdx.intel.com/apd_proj/ppg_lib/epg_masterlib/logical/mstr_discrete/res/chips/chips.prt!RES!RES_0402-2.0K,1%,1/16W,CHIP,G21796-001!RES!!!F1045!!ST_SATA!!
S!@baseboard_fab2_lib.baseboard_fab2(sch_1):page178_i20@mstr_discrete.res(chips)!RES_0402-2.0K,1%,1/16W,CHIP,G2A!R2L5!//jf4cfls225.pdx.intel.com/apd_proj/ppg_lib/epg_masterlib/logical/mstr_discrete/res/chips/chips.prt!RES!RES_0402-2.0K,1%,1/16W,CHIP,G21796-001!RES!!!F1048!!ST_SATA!!
S!@baseboard_fab2_lib.baseboard_fab2(sch_1):page178_i18@mstr_discrete.res(chips)!RES_0402-2.0K,1%,1/16W,CHIP,G2A!R2L4!//jf4cfls225.pdx.intel.com/apd_proj/ppg_lib/epg_masterlib/logical/mstr_discrete/res/chips/chips.prt!RES!RES_0402-2.0K,1%,1/16W,CHIP,G21796-001!RES!!!F1049!!ST_SATA!!
S!@baseboard_fab2_lib.baseboard_fab2(sch_1):page178_i12@mstr_discrete.res(chips)!RES_0402-2.0K,1%,1/16W,CHIP,G2A!R2L15!//jf4cfls225.pdx.intel.com/apd_proj/ppg_lib/epg_masterlib/logical/mstr_discrete/res/chips/chips.prt!RES!RES_0402-2.0K,1%,1/16W,CHIP,G21796-001!RES!!!F1044!!ST_SATA!!
S!@baseboard_fab2_lib.baseboard_fab2(sch_1):page178_i17@mstr_discrete.res(chips)!RES_0402-2.0K,1%,1/16W,CHIP,G2A!R2L6!//jf4cfls225.pdx.intel.com/apd_proj/ppg_lib/epg_masterlib/logical/mstr_discrete/res/chips/chips.prt!RES!RES_0402-2.0K,1%,1/16W,CHIP,G21796-001!RES!!!F1047!!ST_SATA!!
S!@baseboard_fab2_lib.baseboard_fab2(sch_1):page178_i13@mstr_discrete.res(chips)!RES_0402-2.0K,1%,1/16W,CHIP,G2A!R2L11!//jf4cfls225.pdx.intel.com/apd_proj/ppg_lib/epg_masterlib/logical/mstr_discrete/res/chips/chips.prt!RES!RES_0402-2.0K,1%,1/16W,CHIP,G21796-001!RES!!!F1046!!ST_SATA!!
S!@baseboard_fab2_lib.baseboard_fab2(sch_1):page173_i263@mstr_discrete.res(chips)!RES_0402-2.0K,1%,1/16W,CHIP,G2A!R2L21!//jf4cfls225.pdx.intel.com/apd_proj/ppg_lib/epg_masterlib/logical/mstr_discrete/res/chips/chips.prt!RES!RES_0402-2.0K,1%,1/16W,CHIP,G21796-001!RES!!!F1043!!ST_SATA!!
S!@baseboard_fab2_lib.baseboard_fab2(sch_1):page173_i261@mstr_discrete.res(chips)!RES_0402-2.0K,1%,1/16W,CHIP,G2A!R2L23!//jf4cfls225.pdx.intel.com/apd_proj/ppg_lib/epg_masterlib/logical/mstr_discrete/res/chips/chips.prt!RES!RES_0402-2.0K,1%,1/16W,CHIP,G21796-001!RES!!!F1042!!ST_SATA!!
S!@baseboard_fab2_lib.baseboard_fab2(sch_1):page174_i25@mstr_discrete.res(chips)!RES_0402-2.0K,1%,1/16W,CHIP,G2A!R1L1!//jf4cfls225.pdx.intel.com/apd_proj/ppg_lib/epg_masterlib/logical/mstr_discrete/res/chips/chips.prt!RES!RES_0402-2.0K,1%,1/16W,CHIP,G21796-001!RES!!!F1050!!ST_SATA!!
S!@baseboard_fab2_lib.baseboard_fab2(sch_1):page155_i80@mstr_discrete.res(chips)!RES_0402-2.21K,1%,1/16W,CHIP,GA!R9A7!//jf4cfls225.pdx.intel.com/apd_proj/ppg_lib/epg_masterlib/logical/mstr_discrete/res/chips/chips.prt!RES!RES_0402-2.21K,1%,1/16W,CHIP,G21796-112!RES!!!F1026!!BMC_DEBUG_HEADER!!
S!@baseboard_fab2_lib.baseboard_fab2(sch_1):page188_i88@mstr_discrete.res(chips)!RES_0402-2.21K,1%,1/16W,CHIP,GA!R1R18!//jf4cfls225.pdx.intel.com/apd_proj/ppg_lib/epg_masterlib/logical/mstr_discrete/res/chips/chips.prt!RES!RES_0402-2.21K,1%,1/16W,CHIP,G21796-112!RES!!!F1023!!!!
S!@baseboard_fab2_lib.baseboard_fab2(sch_1):page188_i89@mstr_discrete.res(chips)!RES_0402-2.21K,1%,1/16W,CHIP,GA!R1R19!//jf4cfls225.pdx.intel.com/apd_proj/ppg_lib/epg_masterlib/logical/mstr_discrete/res/chips/chips.prt!RES!RES_0402-2.21K,1%,1/16W,CHIP,G21796-112!RES!!!F1022!!!!
S!@baseboard_fab2_lib.baseboard_fab2(sch_1):page188_i91@mstr_discrete.res(chips)!RES_0402-2.21K,1%,1/16W,CHIP,GA!R1R20!//jf4cfls225.pdx.intel.com/apd_proj/ppg_lib/epg_masterlib/logical/mstr_discrete/res/chips/chips.prt!RES!RES_0402-2.21K,1%,1/16W,CHIP,G21796-112!RES!!!F1021!!!!
S!@baseboard_fab2_lib.baseboard_fab2(sch_1):page188_i90@mstr_discrete.res(chips)!RES_0402-2.21K,1%,1/16W,CHIP,GA!R1R21!//jf4cfls225.pdx.intel.com/apd_proj/ppg_lib/epg_masterlib/logical/mstr_discrete/res/chips/chips.prt!RES!RES_0402-2.21K,1%,1/16W,CHIP,G21796-112!RES!!!F1020!!!!
S!@baseboard_fab2_lib.baseboard_fab2(sch_1):page188_i93@mstr_discrete.res(chips)!RES_0402-2.21K,1%,1/16W,CHIP,GA!R1R16!//jf4cfls225.pdx.intel.com/apd_proj/ppg_lib/epg_masterlib/logical/mstr_discrete/res/chips/chips.prt!RES!RES_0402-2.21K,1%,1/16W,CHIP,G21796-112!RES!!!F1019!!!!
S!@baseboard_fab2_lib.baseboard_fab2(sch_1):page188_i94@mstr_discrete.res(chips)!RES_0402-2.21K,1%,1/16W,CHIP,GA!R1R17!//jf4cfls225.pdx.intel.com/apd_proj/ppg_lib/epg_masterlib/logical/mstr_discrete/res/chips/chips.prt!RES!RES_0402-2.21K,1%,1/16W,CHIP,G21796-112!RES!!!F1018!!!!
S!@baseboard_fab2_lib.baseboard_fab2(sch_1):page188_i95@mstr_discrete.res(chips)!RES_0402-2.21K,1%,1/16W,CHIP,GA!R1R23!//jf4cfls225.pdx.intel.com/apd_proj/ppg_lib/epg_masterlib/logical/mstr_discrete/res/chips/chips.prt!RES!RES_0402-2.21K,1%,1/16W,CHIP,G21796-112!RES!!!F1017!!!!
S!@baseboard_fab2_lib.baseboard_fab2(sch_1):page188_i92@mstr_discrete.res(chips)!RES_0402-2.21K,1%,1/16W,CHIP,GA!R1R22!//jf4cfls225.pdx.intel.com/apd_proj/ppg_lib/epg_masterlib/logical/mstr_discrete/res/chips/chips.prt!RES!RES_0402-2.21K,1%,1/16W,CHIP,G21796-112!RES!!!F1016!!!!
S!@baseboard_fab2_lib.baseboard_fab2(sch_1):page94_i100@mstr_discrete.res(chips)!RES_0402-2.21K,1%,1/16W,CHIP,GA!R4U2!//jf4cfls225.pdx.intel.com/apd_proj/ppg_lib/epg_masterlib/logical/mstr_discrete/res/chips/chips.prt!RES!RES_0402-2.21K,1%,1/16W,CHIP,G21796-112!RES!!!F1028!!PROC_SIDEBAND!!
S!@baseboard_fab2_lib.baseboard_fab2(sch_1):page157_i296@mstr_discrete.res(chips)!RES_0402-2.21K,1%,1/16W,CHIP,GA!R8F23!//jf4cfls225.pdx.intel.com/apd_proj/ppg_lib/epg_masterlib/logical/mstr_discrete/res/chips/chips.prt!RES!RES_0402-2.21K,1%,1/16W,CHIP,G21796-112!RES!!!F1027!!BMC_MISC!!
S!@baseboard_fab2_lib.baseboard_fab2(sch_1):page157_i298@mstr_discrete.res(chips)!RES_0402-2.21K,1%,1/16W,CHIP,GA!R2T29!//jf4cfls225.pdx.intel.com/apd_proj/ppg_lib/epg_masterlib/logical/mstr_discrete/res/chips/chips.prt!RES!RES_0402-2.21K,1%,1/16W,CHIP,G21796-112!RES!!!F1029!!BMC_MISC!!
S!@baseboard_fab2_lib.baseboard_fab2(sch_1):page134_i12@mstr_discrete.res(chips)!RES_0402-2.21K,1%,1/16W,CHIP,GA!R9A16!//jf4cfls225.pdx.intel.com/apd_proj/ppg_lib/epg_masterlib/logical/mstr_discrete/res/chips/chips.prt!RES!RES_0402-2.21K,1%,1/16W,CHIP,G21796-112!RES!!!F1024!!SB!!
S!@baseboard_fab2_lib.baseboard_fab2(sch_1):page134_i11@mstr_discrete.res(chips)!RES_0402-2.21K,1%,1/16W,CHIP,GA!R9A12!//jf4cfls225.pdx.intel.com/apd_proj/ppg_lib/epg_masterlib/logical/mstr_discrete/res/chips/chips.prt!RES!RES_0402-2.21K,1%,1/16W,CHIP,G21796-112!RES!!!F1025!!SB!!
S!@baseboard_fab2_lib.baseboard_fab2(sch_1):page159_i212@mstr_discrete.res(chips)!RES_0402-2.26K,1.0%,1/16W,EMPTA!R8G6!//jf4cfls225.pdx.intel.com/apd_proj/ppg_lib/epg_masterlib/logical/mstr_discrete/res/chips/chips.prt!RES!RES_0402-2.26K,1.0%,1/16W,EMPTY,G21796-311!RES!!!F996!!SMBUS!!
S!@baseboard_fab2_lib.baseboard_fab2(sch_1):page159_i210@mstr_discrete.res(chips)!RES_0402-2.26K,1.0%,1/16W,EMPTA!R8G3!//jf4cfls225.pdx.intel.com/apd_proj/ppg_lib/epg_masterlib/logical/mstr_discrete/res/chips/chips.prt!RES!RES_0402-2.26K,1.0%,1/16W,EMPTY,G21796-311!RES!!!F997!!SMBUS!!
S!@baseboard_fab2_lib.baseboard_fab2(sch_1):page159_i216@mstr_discrete.res(chips)!RES_0402-2.26K,1.0%,1/16W,EMPTA!R2U13!//jf4cfls225.pdx.intel.com/apd_proj/ppg_lib/epg_masterlib/logical/mstr_discrete/res/chips/chips.prt!RES!RES_0402-2.26K,1.0%,1/16W,EMPTY,G21796-311!RES!!!F1005!!SMBUS!!
S!@baseboard_fab2_lib.baseboard_fab2(sch_1):page159_i214@mstr_discrete.res(chips)!RES_0402-2.26K,1.0%,1/16W,EMPTA!R2U5!//jf4cfls225.pdx.intel.com/apd_proj/ppg_lib/epg_masterlib/logical/mstr_discrete/res/chips/chips.prt!RES!RES_0402-2.26K,1.0%,1/16W,EMPTY,G21796-311!RES!!!F1006!!SMBUS!!
S!@baseboard_fab2_lib.baseboard_fab2(sch_1):page235_i148@mstr_discrete.res(chips)!RES_0402-2.26K,1.0%,1/16W,EMPTA!R2L24!//jf4cfls225.pdx.intel.com/apd_proj/ppg_lib/epg_masterlib/logical/mstr_discrete/res/chips/chips.prt!RES!RES_0402-2.26K,1.0%,1/16W,EMPTY,G21796-311!RES!!!F998!!PVNN_PCH_STBY!!
S!@baseboard_fab2_lib.baseboard_fab2(sch_1):page213_i14@mstr_discrete.res(chips)!RES_0402-2.26K,1.0%,1/16W,EMPTA!R6P49!//jf4cfls225.pdx.intel.com/apd_proj/ppg_lib/epg_masterlib/logical/mstr_discrete/res/chips/chips.prt!RES!RES_0402-2.26K,1.0%,1/16W,EMPTY,G21796-311!RES!!!F1001!!PVCCIO_CPU1!!
S!@baseboard_fab2_lib.baseboard_fab2(sch_1):page211_i60@mstr_discrete.res(chips)!RES_0402-2.26K,1.0%,1/16W,EMPTA!R3N23!//jf4cfls225.pdx.intel.com/apd_proj/ppg_lib/epg_masterlib/logical/mstr_discrete/res/chips/chips.prt!RES!RES_0402-2.26K,1.0%,1/16W,EMPTY,G21796-311!RES!!!F1004!!PVCCIO_CPU0!!
S!@baseboard_fab2_lib.baseboard_fab2(sch_1):page218_i14@mstr_discrete.res(chips)!RES_0402-2.26K,1.0%,1/16W,EMPTA!R7A9!//jf4cfls225.pdx.intel.com/apd_proj/ppg_lib/epg_masterlib/logical/mstr_discrete/res/chips/chips.prt!RES!RES_0402-2.26K,1.0%,1/16W,EMPTY,G21796-311!RES!!!F1000!!VDDQ_DEF_PWR_VR!!
S!@baseboard_fab2_lib.baseboard_fab2(sch_1):page223_i13@mstr_discrete.res(chips)!RES_0402-2.26K,1.0%,1/16W,EMPTA!R1G6!//jf4cfls225.pdx.intel.com/apd_proj/ppg_lib/epg_masterlib/logical/mstr_discrete/res/chips/chips.prt!RES!RES_0402-2.26K,1.0%,1/16W,EMPTY,G21796-311!RES!!!F1007!!VDDQ_GHJ_PWR_VR!!
S!@baseboard_fab2_lib.baseboard_fab2(sch_1):page226_i13@mstr_discrete.res(chips)!RES_0402-2.26K,1.0%,1/16W,EMPTA!R1B13!//jf4cfls225.pdx.intel.com/apd_proj/ppg_lib/epg_masterlib/logical/mstr_discrete/res/chips/chips.prt!RES!RES_0402-2.26K,1.0%,1/16W,EMPTY,G21796-311!RES!!!F1010!!VDDQ_KLM_PWR_VR!!
S!@baseboard_fab2_lib.baseboard_fab2(sch_1):page201_i116@mstr_discrete.res(chips)!RES_0402-2.26K,1.0%,1/16W,EMPTA!R4E20!//jf4cfls225.pdx.intel.com/apd_proj/ppg_lib/epg_masterlib/logical/mstr_discrete/res/chips/chips.prt!RES!RES_0402-2.26K,1.0%,1/16W,EMPTY,G21796-311!RES!!!F1003!!PVCCIN_CPU0_VR!!
S!@baseboard_fab2_lib.baseboard_fab2(sch_1):page215_i300@mstr_discrete.res(chips)!RES_0402-2.26K,1.0%,1/16W,EMPTA!R7F36!//jf4cfls225.pdx.intel.com/apd_proj/ppg_lib/epg_masterlib/logical/mstr_discrete/res/chips/chips.prt!RES!RES_0402-2.26K,1.0%,1/16W,EMPTY,G21796-311!RES!!!F999!!VDDQ_ABC_PWR_VR!!
S!@baseboard_fab2_lib.baseboard_fab2(sch_1):page201_i22@mstr_discrete.res(chips)!RES_0402-2.26K,1.0%,1/16W,EMPTA!R4D31!//jf4cfls225.pdx.intel.com/apd_proj/ppg_lib/epg_masterlib/logical/mstr_discrete/res/chips/chips.prt!RES!RES_0402-2.26K,1.0%,1/16W,EMPTY,G21796-311!RES!!!F1002!!PVCCIN_CPU0_VR!!
S!@baseboard_fab2_lib.baseboard_fab2(sch_1):page206_i33@mstr_discrete.res(chips)!RES_0402-2.26K,1.0%,1/16W,EMPTA!R1D53!//jf4cfls225.pdx.intel.com/apd_proj/ppg_lib/epg_masterlib/logical/mstr_discrete/res/chips/chips.prt!RES!RES_0402-2.26K,1.0%,1/16W,EMPTY,G21796-311!RES!!!F1009!!PVCCIN_CPU1_VR!!
S!@baseboard_fab2_lib.baseboard_fab2(sch_1):page206_i34@mstr_discrete.res(chips)!RES_0402-2.26K,1.0%,1/16W,EMPTA!R1C18!//jf4cfls225.pdx.intel.com/apd_proj/ppg_lib/epg_masterlib/logical/mstr_discrete/res/chips/chips.prt!RES!RES_0402-2.26K,1.0%,1/16W,EMPTY,G21796-311!RES!!!F1008!!PVCCIN_CPU1_VR!!
S!@baseboard_fab2_lib.baseboard_fab2(sch_1):page140_i12@mstr_discrete.res(chips)!RES_0402-20.0K,1%,1/16W,CHIP,GA!R1R7!//jf4cfls225.pdx.intel.com/apd_proj/ppg_lib/epg_masterlib/logical/mstr_discrete/res/chips/chips.prt!RES!RES_0402-20.0K,1%,1/16W,CHIP,G21796-040!RES!!!F909!!NIC_SPRV!!
S!@baseboard_fab2_lib.baseboard_fab2(sch_1):page231_i167@mstr_discrete.res(chips)!RES_0402-20.0K,1%,1/16W,CHIP,GA!R7F13!//jf4cfls225.pdx.intel.com/apd_proj/ppg_lib/epg_masterlib/logical/mstr_discrete/res/chips/chips.prt!RES!RES_0402-20.0K,1%,1/16W,CHIP,G21796-040!RES!!!F903!!PVPP_KLM_VR!!
S!@baseboard_fab2_lib.baseboard_fab2(sch_1):page232_i303@mstr_discrete.res(chips)!RES_0402-20.0K,1%,1/16W,CHIP,GA!R7B15!//jf4cfls225.pdx.intel.com/apd_proj/ppg_lib/epg_masterlib/logical/mstr_discrete/res/chips/chips.prt!RES!RES_0402-20.0K,1%,1/16W,CHIP,G21796-040!RES!!!F905!!PVPP_KLM_VR!!
S!@baseboard_fab2_lib.baseboard_fab2(sch_1):page233_i270@mstr_discrete.res(chips)!RES_0402-20.0K,1%,1/16W,CHIP,GA!R4G7!//jf4cfls225.pdx.intel.com/apd_proj/ppg_lib/epg_masterlib/logical/mstr_discrete/res/chips/chips.prt!RES!RES_0402-20.0K,1%,1/16W,CHIP,G21796-040!RES!!!F906!!PVPP_KLM_VR!!
S!@baseboard_fab2_lib.baseboard_fab2(sch_1):page234_i215@mstr_discrete.res(chips)!RES_0402-20.0K,1%,1/16W,CHIP,GA!R4B5!//jf4cfls225.pdx.intel.com/apd_proj/ppg_lib/epg_masterlib/logical/mstr_discrete/res/chips/chips.prt!RES!RES_0402-20.0K,1%,1/16W,CHIP,G21796-040!RES!!!F907!!PVPP_KLM_VR!!
S!@baseboard_fab2_lib.baseboard_fab2(sch_1):page155_i136@mstr_discrete.res(chips)!RES_0402-20.0K,1%,1/16W,CHIP,GA!R9A5!//jf4cfls225.pdx.intel.com/apd_proj/ppg_lib/epg_masterlib/logical/mstr_discrete/res/chips/chips.prt!RES!RES_0402-20.0K,1%,1/16W,CHIP,G21796-040!RES!!!F902!!BMC_DEBUG_HEADER!!
S!@baseboard_fab2_lib.baseboard_fab2(sch_1):page137_i19@mstr_discrete.res(chips)!RES_0402-20.0K,1%,1/16W,CHIP,GA!R3N4!//jf4cfls225.pdx.intel.com/apd_proj/ppg_lib/epg_masterlib/logical/mstr_discrete/res/chips/chips.prt!RES!RES_0402-20.0K,1%,1/16W,CHIP,G21796-040!RES!!!F908!!SB!!
S!@baseboard_fab2_lib.baseboard_fab2(sch_1):page137_i13@mstr_discrete.res(chips)!RES_0402-20.0K,1%,1/16W,CHIP,GA!R7C10!//jf4cfls225.pdx.intel.com/apd_proj/ppg_lib/epg_masterlib/logical/mstr_discrete/res/chips/chips.prt!RES!RES_0402-20.0K,1%,1/16W,CHIP,G21796-040!RES!!!F904!!SB!!
S!@baseboard_fab2_lib.baseboard_fab2(sch_1):page147_i116@mstr_discrete.res(chips)!RES_0402-22.1,1.0%,1/16W,CHIP,A!R8F33!//jf4cfls225.pdx.intel.com/apd_proj/ppg_lib/epg_masterlib/logical/mstr_discrete/res/chips/chips.prt!RES!RES_0402-22.1,1.0%,1/16W,CHIP,G21796-250!RES!!!F860!!BMC!!
S!@baseboard_fab2_lib.baseboard_fab2(sch_1):page147_i154@mstr_discrete.res(chips)!RES_0402-22.1,1.0%,1/16W,CHIP,A!R8F30!//jf4cfls225.pdx.intel.com/apd_proj/ppg_lib/epg_masterlib/logical/mstr_discrete/res/chips/chips.prt!RES!RES_0402-22.1,1.0%,1/16W,CHIP,G21796-250!RES!!!F862!!BMC!!
S!@baseboard_fab2_lib.baseboard_fab2(sch_1):page101_i125@mstr_discrete.res(chips)!RES_0402-22.1,1.0%,1/16W,CHIP,A!R2T46!//jf4cfls225.pdx.intel.com/apd_proj/ppg_lib/epg_masterlib/logical/mstr_discrete/res/chips/chips.prt!RES!RES_0402-22.1,1.0%,1/16W,CHIP,G21796-250!RES!!!F878!!SYS_CLOCK!!
S!@baseboard_fab2_lib.baseboard_fab2(sch_1):page101_i124@mstr_discrete.res(chips)!RES_0402-22.1,1.0%,1/16W,CHIP,A!R2T42!//jf4cfls225.pdx.intel.com/apd_proj/ppg_lib/epg_masterlib/logical/mstr_discrete/res/chips/chips.prt!RES!RES_0402-22.1,1.0%,1/16W,CHIP,G21796-250!RES!!!F880!!SYS_CLOCK!!
S!@baseboard_fab2_lib.baseboard_fab2(sch_1):page213_i13@mstr_discrete.res(chips)!RES_0402-22.1,1.0%,1/16W,CHIP,A!R4D46!//jf4cfls225.pdx.intel.com/apd_proj/ppg_lib/epg_masterlib/logical/mstr_discrete/res/chips/chips.prt!RES!RES_0402-22.1,1.0%,1/16W,CHIP,G21796-250!RES!!!F874!!PVCCIO_CPU1!!
S!@baseboard_fab2_lib.baseboard_fab2(sch_1):page238_i41@mstr_discrete.res(chips)!RES_0402-22.1,1.0%,1/16W,CHIP,A!R9F11!//jf4cfls225.pdx.intel.com/apd_proj/ppg_lib/epg_masterlib/logical/mstr_discrete/res/chips/chips.prt!RES!RES_0402-22.1,1.0%,1/16W,CHIP,G21796-250!RES!!!F856!!P1V26_BMC_STBY_VR!!
S!@baseboard_fab2_lib.baseboard_fab2(sch_1):page239_i72@mstr_discrete.res(chips)!RES_0402-22.1,1.0%,1/16W,CHIP,A!R1T9!//jf4cfls225.pdx.intel.com/apd_proj/ppg_lib/epg_masterlib/logical/mstr_discrete/res/chips/chips.prt!RES!RES_0402-22.1,1.0%,1/16W,CHIP,G21796-250!RES!!!F885!!P1V538_BMC_STBY_VR!!
S!@baseboard_fab2_lib.baseboard_fab2(sch_1):page237_i90@mstr_discrete.res(chips)!RES_0402-22.1,1.0%,1/16W,CHIP,A!R8A11!//jf4cfls225.pdx.intel.com/apd_proj/ppg_lib/epg_masterlib/logical/mstr_discrete/res/chips/chips.prt!RES!RES_0402-22.1,1.0%,1/16W,CHIP,G21796-250!RES!!!F867!!P1V8_PCH_STBY_VR!!
S!@baseboard_fab2_lib.baseboard_fab2(sch_1):page240_i171@mstr_discrete.res(chips)!RES_0402-22.1,1.0%,1/16W,CHIP,A!R8F10!//jf4cfls225.pdx.intel.com/apd_proj/ppg_lib/epg_masterlib/logical/mstr_discrete/res/chips/chips.prt!RES!RES_0402-22.1,1.0%,1/16W,CHIP,G21796-250!RES!!!F865!!P3V3_STBY_VR!!
S!@baseboard_fab2_lib.baseboard_fab2(sch_1):page241_i89@mstr_discrete.res(chips)!RES_0402-22.1,1.0%,1/16W,CHIP,A!R7E15!//jf4cfls225.pdx.intel.com/apd_proj/ppg_lib/epg_masterlib/logical/mstr_discrete/res/chips/chips.prt!RES!RES_0402-22.1,1.0%,1/16W,CHIP,G21796-250!RES!!!F870!!P5V_STBY_VR!!
S!@baseboard_fab2_lib.baseboard_fab2(sch_1):page206_i113@mstr_discrete.res(chips)!RES_0402-22.1,1.0%,1/16W,CHIP,A!R1C30!//jf4cfls225.pdx.intel.com/apd_proj/ppg_lib/epg_masterlib/logical/mstr_discrete/res/chips/chips.prt!RES!RES_0402-22.1,1.0%,1/16W,CHIP,G21796-250!RES!!!F887!!PVCCIN_CPU1_VR!!
S!@baseboard_fab2_lib.baseboard_fab2(sch_1):page232_i257@mstr_discrete.res(chips)!RES_0402-22.1,1.0%,1/16W,CHIP,A!R7B12!//jf4cfls225.pdx.intel.com/apd_proj/ppg_lib/epg_masterlib/logical/mstr_discrete/res/chips/chips.prt!RES!RES_0402-22.1,1.0%,1/16W,CHIP,G21796-250!RES!!!F871!!PVPP_DEF_VR!!
S!@baseboard_fab2_lib.baseboard_fab2(sch_1):page233_i247@mstr_discrete.res(chips)!RES_0402-22.1,1.0%,1/16W,CHIP,A!R4G12!//jf4cfls225.pdx.intel.com/apd_proj/ppg_lib/epg_masterlib/logical/mstr_discrete/res/chips/chips.prt!RES!RES_0402-22.1,1.0%,1/16W,CHIP,G21796-250!RES!!!F872!!PVPP_GHJ_VR!!
S!@baseboard_fab2_lib.baseboard_fab2(sch_1):page231_i208@mstr_discrete.res(chips)!RES_0402-22.1,1.0%,1/16W,CHIP,A!R7F16!//jf4cfls225.pdx.intel.com/apd_proj/ppg_lib/epg_masterlib/logical/mstr_discrete/res/chips/chips.prt!RES!RES_0402-22.1,1.0%,1/16W,CHIP,G21796-250!RES!!!F869!!PVPP_KLM_VR!!
S!@baseboard_fab2_lib.baseboard_fab2(sch_1):page234_i201@mstr_discrete.res(chips)!RES_0402-22.1,1.0%,1/16W,CHIP,A!R4B7!//jf4cfls225.pdx.intel.com/apd_proj/ppg_lib/epg_masterlib/logical/mstr_discrete/res/chips/chips.prt!RES!RES_0402-22.1,1.0%,1/16W,CHIP,G21796-250!RES!!!F875!!PVPP_KLM_VR!!
S!@baseboard_fab2_lib.baseboard_fab2(sch_1):page201_i124@mstr_discrete.res(chips)!RES_0402-22.1,1.0%,1/16W,CHIP,A!R4D63!//jf4cfls225.pdx.intel.com/apd_proj/ppg_lib/epg_masterlib/logical/mstr_discrete/res/chips/chips.prt!RES!RES_0402-22.1,1.0%,1/16W,CHIP,G21796-250!RES!!!F873!!PVCCIN_CPU0_VR!!
S!@baseboard_fab2_lib.baseboard_fab2(sch_1):page215_i296@mstr_discrete.res(chips)!RES_0402-22.1,1.0%,1/16W,CHIP,A!R7F24!//jf4cfls225.pdx.intel.com/apd_proj/ppg_lib/epg_masterlib/logical/mstr_discrete/res/chips/chips.prt!RES!RES_0402-22.1,1.0%,1/16W,CHIP,G21796-250!RES!!!F868!!VDDQ_ABC_PWR_VR!!
S!@baseboard_fab2_lib.baseboard_fab2(sch_1):page218_i11@mstr_discrete.res(chips)!RES_0402-22.1,1.0%,1/16W,CHIP,A!R3M3!//jf4cfls225.pdx.intel.com/apd_proj/ppg_lib/epg_masterlib/logical/mstr_discrete/res/chips/chips.prt!RES!RES_0402-22.1,1.0%,1/16W,CHIP,G21796-250!RES!!!F877!!VDDQ_DEF_PWR_VR!!
S!@baseboard_fab2_lib.baseboard_fab2(sch_1):page223_i14@mstr_discrete.res(chips)!RES_0402-22.1,1.0%,1/16W,CHIP,A!R1G12!//jf4cfls225.pdx.intel.com/apd_proj/ppg_lib/epg_masterlib/logical/mstr_discrete/res/chips/chips.prt!RES!RES_0402-22.1,1.0%,1/16W,CHIP,G21796-250!RES!!!F886!!VDDQ_GHJ_PWR_VR!!
S!@baseboard_fab2_lib.baseboard_fab2(sch_1):page226_i14@mstr_discrete.res(chips)!RES_0402-22.1,1.0%,1/16W,CHIP,A!R1B5!//jf4cfls225.pdx.intel.com/apd_proj/ppg_lib/epg_masterlib/logical/mstr_discrete/res/chips/chips.prt!RES!RES_0402-22.1,1.0%,1/16W,CHIP,G21796-250!RES!!!F888!!VDDQ_KLM_PWR_VR!!
S!@baseboard_fab2_lib.baseboard_fab2(sch_1):page211_i58@mstr_discrete.res(chips)!RES_0402-22.1,1.0%,1/16W,CHIP,A!R3P20!//jf4cfls225.pdx.intel.com/apd_proj/ppg_lib/epg_masterlib/logical/mstr_discrete/res/chips/chips.prt!RES!RES_0402-22.1,1.0%,1/16W,CHIP,G21796-250!RES!!!F876!!PVCCIO_CPU0!!
S!@baseboard_fab2_lib.baseboard_fab2(sch_1):page235_i147@mstr_discrete.res(chips)!RES_0402-22.1,1.0%,1/16W,CHIP,A!R2L16!//jf4cfls225.pdx.intel.com/apd_proj/ppg_lib/epg_masterlib/logical/mstr_discrete/res/chips/chips.prt!RES!RES_0402-22.1,1.0%,1/16W,CHIP,G21796-250!RES!!!F882!!PVNN_PCH_STBY!!
S!@baseboard_fab2_lib.baseboard_fab2(sch_1):page145_i203@mstr_discrete.res(chips)!RES_0402-22.1,1.0%,1/16W,CHIP,A!R2T41!//jf4cfls225.pdx.intel.com/apd_proj/ppg_lib/epg_masterlib/logical/mstr_discrete/res/chips/chips.prt!RES!RES_0402-22.1,1.0%,1/16W,CHIP,G21796-250!RES!!!F881!!BMC!!
S!@baseboard_fab2_lib.baseboard_fab2(sch_1):page146_i35@mstr_discrete.res(chips)!RES_0402-22.1,1.0%,1/16W,CHIP,A!R1T26!//jf4cfls225.pdx.intel.com/apd_proj/ppg_lib/epg_masterlib/logical/mstr_discrete/res/chips/chips.prt!RES!RES_0402-22.1,1.0%,1/16W,CHIP,G21796-250!RES!!!F884!!BMC!!
S!@baseboard_fab2_lib.baseboard_fab2(sch_1):page147_i115@mstr_discrete.res(chips)!RES_0402-22.1,1.0%,1/16W,CHIP,A!R2T45!//jf4cfls225.pdx.intel.com/apd_proj/ppg_lib/epg_masterlib/logical/mstr_discrete/res/chips/chips.prt!RES!RES_0402-22.1,1.0%,1/16W,CHIP,G21796-250!RES!!!F879!!BMC!!
S!@baseboard_fab2_lib.baseboard_fab2(sch_1):page147_i125@mstr_discrete.res(chips)!RES_0402-22.1,1.0%,1/16W,CHIP,A!R8F28!//jf4cfls225.pdx.intel.com/apd_proj/ppg_lib/epg_masterlib/logical/mstr_discrete/res/chips/chips.prt!RES!RES_0402-22.1,1.0%,1/16W,CHIP,G21796-250!RES!!!F863!!BMC!!
S!@baseboard_fab2_lib.baseboard_fab2(sch_1):page147_i126@mstr_discrete.res(chips)!RES_0402-22.1,1.0%,1/16W,CHIP,A!R8F31!//jf4cfls225.pdx.intel.com/apd_proj/ppg_lib/epg_masterlib/logical/mstr_discrete/res/chips/chips.prt!RES!RES_0402-22.1,1.0%,1/16W,CHIP,G21796-250!RES!!!F861!!BMC!!
S!@baseboard_fab2_lib.baseboard_fab2(sch_1):page139_i229@mstr_discrete.res(chips)!RES_0402-22.1,1.0%,1/16W,CHIP,A!R9E17!//jf4cfls225.pdx.intel.com/apd_proj/ppg_lib/epg_masterlib/logical/mstr_discrete/res/chips/chips.prt!RES!RES_0402-22.1,1.0%,1/16W,CHIP,G21796-250!RES!!!F859!!BMC!!
S!@baseboard_fab2_lib.baseboard_fab2(sch_1):page139_i228@mstr_discrete.res(chips)!RES_0402-22.1,1.0%,1/16W,CHIP,A!R9E19!//jf4cfls225.pdx.intel.com/apd_proj/ppg_lib/epg_masterlib/logical/mstr_discrete/res/chips/chips.prt!RES!RES_0402-22.1,1.0%,1/16W,CHIP,G21796-250!RES!!!F858!!BMC!!
S!@baseboard_fab2_lib.baseboard_fab2(sch_1):page147_i121@mstr_discrete.res(chips)!RES_0402-22.1,1.0%,1/16W,CHIP,A!R1T28!//jf4cfls225.pdx.intel.com/apd_proj/ppg_lib/epg_masterlib/logical/mstr_discrete/res/chips/chips.prt!RES!RES_0402-22.1,1.0%,1/16W,CHIP,G21796-250!RES!!!F883!!BMC!!
S!@baseboard_fab2_lib.baseboard_fab2(sch_1):page139_i225@mstr_discrete.res(chips)!RES_0402-22.1,1.0%,1/16W,CHIP,A!R9F1!//jf4cfls225.pdx.intel.com/apd_proj/ppg_lib/epg_masterlib/logical/mstr_discrete/res/chips/chips.prt!RES!RES_0402-22.1,1.0%,1/16W,CHIP,G21796-250!RES!!!F857!!!!
S!@baseboard_fab2_lib.baseboard_fab2(sch_1):page196_i90@mstr_discrete.res(chips)!RES_0402-22.1,1.0%,1/16W,CHIP,A!R8E7!//jf4cfls225.pdx.intel.com/apd_proj/ppg_lib/epg_masterlib/logical/mstr_discrete/res/chips/chips.prt!RES!RES_0402-22.1,1.0%,1/16W,CHIP,G21796-250!RES!!!F866!!V_SUPER!!
S!@baseboard_fab2_lib.baseboard_fab2(sch_1):page101_i129@mstr_discrete.res(chips)!RES_0402-22.1,1.0%,1/16W,CHIP,A!R8F27!//jf4cfls225.pdx.intel.com/apd_proj/ppg_lib/epg_masterlib/logical/mstr_discrete/res/chips/chips.prt!RES!RES_0402-22.1,1.0%,1/16W,CHIP,G21796-250!RES!!!F864!!SYS_CLOCK!!
S!@baseboard_fab2_lib.baseboard_fab2(sch_1):page139_i193@mstr_discrete.res(chips)!RES_0402-3.32K,1%,1/16W,CHIP,GA!R9E7!//jf4cfls225.pdx.intel.com/apd_proj/ppg_lib/epg_masterlib/logical/mstr_discrete/res/chips/chips.prt!RES!RES_0402-3.32K,1%,1/16W,CHIP,G21796-027!RES!!!F771!!NIC_SPRV!!
S!@baseboard_fab2_lib.baseboard_fab2(sch_1):page140_i11@mstr_discrete.res(chips)!RES_0402-3.32K,1%,1/16W,CHIP,GA!R1R3!//jf4cfls225.pdx.intel.com/apd_proj/ppg_lib/epg_masterlib/logical/mstr_discrete/res/chips/chips.prt!RES!RES_0402-3.32K,1%,1/16W,CHIP,G21796-027!RES!!!F773!!NIC_SPRV!!
S!@baseboard_fab2_lib.baseboard_fab2(sch_1):page140_i10@mstr_discrete.res(chips)!RES_0402-3.32K,1%,1/16W,CHIP,GA!R1R9!//jf4cfls225.pdx.intel.com/apd_proj/ppg_lib/epg_masterlib/logical/mstr_discrete/res/chips/chips.prt!RES!RES_0402-3.32K,1%,1/16W,CHIP,G21796-027!RES!!!F772!!NIC_SPRV!!
S!@baseboard_fab2_lib.baseboard_fab2(sch_1):page139_i173@mstr_discrete.res(chips)!RES_0402-3.32K,1%,1/16W,CHIP,GA!R9F5!//jf4cfls225.pdx.intel.com/apd_proj/ppg_lib/epg_masterlib/logical/mstr_discrete/res/chips/chips.prt!RES!RES_0402-3.32K,1%,1/16W,CHIP,G21796-027!RES!!!F770!!NIC_SPRV!!
S!@baseboard_fab2_lib.baseboard_fab2(sch_1):page169_i142@mstr_discrete.res(chips)!RES_0402-3.48K,1.0%,1/16W,CHIPA!R1U28!//jf4cfls225.pdx.intel.com/apd_proj/ppg_lib/epg_masterlib/logical/mstr_discrete/res/chips/chips.prt!RES!RES_0402-3.48K,1.0%,1/16W,CHIP,G21796-279!RES!!!F762!!BMC_VOLT_MONITOR!!
S!@baseboard_fab2_lib.baseboard_fab2(sch_1):page169_i116@mstr_discrete.res(chips)!RES_0402-3.48K,1.0%,1/16W,CHIPA!R1U44!//jf4cfls225.pdx.intel.com/apd_proj/ppg_lib/epg_masterlib/logical/mstr_discrete/res/chips/chips.prt!RES!RES_0402-3.48K,1.0%,1/16W,CHIP,G21796-279!RES!!!F761!!BMC_VOLT_MONITOR!!
S!@baseboard_fab2_lib.baseboard_fab2(sch_1):page150_i43@mstr_discrete.res(chips)!RES_0402-4.75K,1%,1/16W,EMPTY,A!R1T13!//jf4cfls225.pdx.intel.com/apd_proj/ppg_lib/epg_masterlib/logical/mstr_discrete/res/chips/chips.prt!RES!RES_0402-4.75K,1%,1/16W,EMPTY,G21796-072!RES!!!F525!!BMC!!
S!@baseboard_fab2_lib.baseboard_fab2(sch_1):page150_i48@mstr_discrete.res(chips)!RES_0402-4.75K,1%,1/16W,EMPTY,A!R1T18!//jf4cfls225.pdx.intel.com/apd_proj/ppg_lib/epg_masterlib/logical/mstr_discrete/res/chips/chips.prt!RES!RES_0402-4.75K,1%,1/16W,EMPTY,G21796-072!RES!!!F522!!BMC!!
S!@baseboard_fab2_lib.baseboard_fab2(sch_1):page166_i14@mstr_discrete.res(chips)!RES_0402-4.75K,1%,1/16W,EMPTY,A!R7C22!//jf4cfls225.pdx.intel.com/apd_proj/ppg_lib/epg_masterlib/logical/mstr_discrete/res/chips/chips.prt!RES!RES_0402-4.75K,1%,1/16W,EMPTY,G21796-072!RES!!!F513!!PECI!!
S!@baseboard_fab2_lib.baseboard_fab2(sch_1):page192_i55@mstr_discrete.res(chips)!RES_0402-4.75K,1%,1/16W,EMPTY,A!R7E18!//jf4cfls225.pdx.intel.com/apd_proj/ppg_lib/epg_masterlib/logical/mstr_discrete/res/chips/chips.prt!RES!RES_0402-4.75K,1%,1/16W,EMPTY,G21796-072!RES!!!F497!!CPLD!!
S!@baseboard_fab2_lib.baseboard_fab2(sch_1):page150_i112@mstr_discrete.res(chips)!RES_0402-4.75K,1%,1/16W,EMPTY,A!R1T17!//jf4cfls225.pdx.intel.com/apd_proj/ppg_lib/epg_masterlib/logical/mstr_discrete/res/chips/chips.prt!RES!RES_0402-4.75K,1%,1/16W,EMPTY,G21796-072!RES!!!F523!!BMC!!
S!@baseboard_fab2_lib.baseboard_fab2(sch_1):page175_i24@mstr_discrete.res(chips)!RES_0402-4.75K,1%,1/16W,EMPTY,A!R1L19!//jf4cfls225.pdx.intel.com/apd_proj/ppg_lib/epg_masterlib/logical/mstr_discrete/res/chips/chips.prt!RES!RES_0402-4.75K,1%,1/16W,EMPTY,G21796-072!RES!!!F526!!MIO_CHASSIS!!
S!@baseboard_fab2_lib.baseboard_fab2(sch_1):page198_i78@mstr_discrete.res(chips)!RES_0402-4.75K,1%,1/16W,EMPTY,A!R8E12!//jf4cfls225.pdx.intel.com/apd_proj/ppg_lib/epg_masterlib/logical/mstr_discrete/res/chips/chips.prt!RES!RES_0402-4.75K,1%,1/16W,EMPTY,G21796-072!RES!!!F511!!IO_SLOT!!
S!@baseboard_fab2_lib.baseboard_fab2(sch_1):page125_i72@mstr_discrete.res(chips)!RES_0402-4.75K,1%,1/16W,EMPTY,A!R3N2!//jf4cfls225.pdx.intel.com/apd_proj/ppg_lib/epg_masterlib/logical/mstr_discrete/res/chips/chips.prt!RES!RES_0402-4.75K,1%,1/16W,EMPTY,G21796-072!RES!!!F517!!BMC_MISC!!
S!@baseboard_fab2_lib.baseboard_fab2(sch_1):page102_i47@mstr_discrete.res(chips)!RES_0402-4.75K,1%,1/16W,EMPTY,A!R6P22!//jf4cfls225.pdx.intel.com/apd_proj/ppg_lib/epg_masterlib/logical/mstr_discrete/res/chips/chips.prt!RES!RES_0402-4.75K,1%,1/16W,EMPTY,G21796-072!RES!!!F515!!DB1200ZL!!
S!@baseboard_fab2_lib.baseboard_fab2(sch_1):page183_i14@mstr_discrete.res(chips)!RES_0402-4.75K,1%,1/16W,EMPTY,A!R9F49!//jf4cfls225.pdx.intel.com/apd_proj/ppg_lib/epg_masterlib/logical/mstr_discrete/res/chips/chips.prt!RES!RES_0402-4.75K,1%,1/16W,EMPTY,G21796-072!RES!!!F500!!LBG!!
S!@baseboard_fab2_lib.baseboard_fab2(sch_1):page183_i13@mstr_discrete.res(chips)!RES_0402-4.75K,1%,1/16W,EMPTY,A!R9F48!//jf4cfls225.pdx.intel.com/apd_proj/ppg_lib/epg_masterlib/logical/mstr_discrete/res/chips/chips.prt!RES!RES_0402-4.75K,1%,1/16W,EMPTY,G21796-072!RES!!!F501!!LBG!!
S!@baseboard_fab2_lib.baseboard_fab2(sch_1):page150_i44@mstr_discrete.res(chips)!RES_0402-4.75K,1%,1/16W,EMPTY,A!R9F36!//jf4cfls225.pdx.intel.com/apd_proj/ppg_lib/epg_masterlib/logical/mstr_discrete/res/chips/chips.prt!RES!RES_0402-4.75K,1%,1/16W,EMPTY,G21796-072!RES!!!F505!!BMC!!
S!@baseboard_fab2_lib.baseboard_fab2(sch_1):page150_i46@mstr_discrete.res(chips)!RES_0402-4.75K,1%,1/16W,EMPTY,A!R9F17!//jf4cfls225.pdx.intel.com/apd_proj/ppg_lib/epg_masterlib/logical/mstr_discrete/res/chips/chips.prt!RES!RES_0402-4.75K,1%,1/16W,EMPTY,G21796-072!RES!!!F508!!BMC!!
S!@baseboard_fab2_lib.baseboard_fab2(sch_1):page150_i49@mstr_discrete.res(chips)!RES_0402-4.75K,1%,1/16W,EMPTY,A!R1T20!//jf4cfls225.pdx.intel.com/apd_proj/ppg_lib/epg_masterlib/logical/mstr_discrete/res/chips/chips.prt!RES!RES_0402-4.75K,1%,1/16W,EMPTY,G21796-072!RES!!!F520!!BMC!!
S!@baseboard_fab2_lib.baseboard_fab2(sch_1):page150_i50@mstr_discrete.res(chips)!RES_0402-4.75K,1%,1/16W,EMPTY,A!R1T22!//jf4cfls225.pdx.intel.com/apd_proj/ppg_lib/epg_masterlib/logical/mstr_discrete/res/chips/chips.prt!RES!RES_0402-4.75K,1%,1/16W,EMPTY,G21796-072!RES!!!F518!!BMC!!
S!@baseboard_fab2_lib.baseboard_fab2(sch_1):page150_i53@mstr_discrete.res(chips)!RES_0402-4.75K,1%,1/16W,EMPTY,A!R1T21!//jf4cfls225.pdx.intel.com/apd_proj/ppg_lib/epg_masterlib/logical/mstr_discrete/res/chips/chips.prt!RES!RES_0402-4.75K,1%,1/16W,EMPTY,G21796-072!RES!!!F519!!BMC!!
S!@baseboard_fab2_lib.baseboard_fab2(sch_1):page150_i55@mstr_discrete.res(chips)!RES_0402-4.75K,1%,1/16W,EMPTY,A!R9F37!//jf4cfls225.pdx.intel.com/apd_proj/ppg_lib/epg_masterlib/logical/mstr_discrete/res/chips/chips.prt!RES!RES_0402-4.75K,1%,1/16W,EMPTY,G21796-072!RES!!!F504!!BMC!!
S!@baseboard_fab2_lib.baseboard_fab2(sch_1):page150_i57@mstr_discrete.res(chips)!RES_0402-4.75K,1%,1/16W,EMPTY,A!R1T19!//jf4cfls225.pdx.intel.com/apd_proj/ppg_lib/epg_masterlib/logical/mstr_discrete/res/chips/chips.prt!RES!RES_0402-4.75K,1%,1/16W,EMPTY,G21796-072!RES!!!F521!!BMC!!
S!@baseboard_fab2_lib.baseboard_fab2(sch_1):page150_i59@mstr_discrete.res(chips)!RES_0402-4.75K,1%,1/16W,EMPTY,A!R9F38!//jf4cfls225.pdx.intel.com/apd_proj/ppg_lib/epg_masterlib/logical/mstr_discrete/res/chips/chips.prt!RES!RES_0402-4.75K,1%,1/16W,EMPTY,G21796-072!RES!!!F503!!BMC!!
S!@baseboard_fab2_lib.baseboard_fab2(sch_1):page150_i60@mstr_discrete.res(chips)!RES_0402-4.75K,1%,1/16W,EMPTY,A!R9F10!//jf4cfls225.pdx.intel.com/apd_proj/ppg_lib/epg_masterlib/logical/mstr_discrete/res/chips/chips.prt!RES!RES_0402-4.75K,1%,1/16W,EMPTY,G21796-072!RES!!!F509!!BMC!!
S!@baseboard_fab2_lib.baseboard_fab2(sch_1):page150_i61@mstr_discrete.res(chips)!RES_0402-4.75K,1%,1/16W,EMPTY,A!R1T16!//jf4cfls225.pdx.intel.com/apd_proj/ppg_lib/epg_masterlib/logical/mstr_discrete/res/chips/chips.prt!RES!RES_0402-4.75K,1%,1/16W,EMPTY,G21796-072!RES!!!F524!!BMC!!
S!@baseboard_fab2_lib.baseboard_fab2(sch_1):page150_i62@mstr_discrete.res(chips)!RES_0402-4.75K,1%,1/16W,EMPTY,A!R9F18!//jf4cfls225.pdx.intel.com/apd_proj/ppg_lib/epg_masterlib/logical/mstr_discrete/res/chips/chips.prt!RES!RES_0402-4.75K,1%,1/16W,EMPTY,G21796-072!RES!!!F507!!BMC!!
S!@baseboard_fab2_lib.baseboard_fab2(sch_1):page150_i63@mstr_discrete.res(chips)!RES_0402-4.75K,1%,1/16W,EMPTY,A!R9F19!//jf4cfls225.pdx.intel.com/apd_proj/ppg_lib/epg_masterlib/logical/mstr_discrete/res/chips/chips.prt!RES!RES_0402-4.75K,1%,1/16W,EMPTY,G21796-072!RES!!!F506!!BMC!!
S!@baseboard_fab2_lib.baseboard_fab2(sch_1):page150_i64@mstr_discrete.res(chips)!RES_0402-4.75K,1%,1/16W,EMPTY,A!R9F39!//jf4cfls225.pdx.intel.com/apd_proj/ppg_lib/epg_masterlib/logical/mstr_discrete/res/chips/chips.prt!RES!RES_0402-4.75K,1%,1/16W,EMPTY,G21796-072!RES!!!F502!!BMC!!
S!@baseboard_fab2_lib.baseboard_fab2(sch_1):page199_i37@mstr_discrete.res(chips)!RES_0402-4.75K,1%,1/16W,EMPTY,A!R1D29!//jf4cfls225.pdx.intel.com/apd_proj/ppg_lib/epg_masterlib/logical/mstr_discrete/res/chips/chips.prt!RES!RES_0402-4.75K,1%,1/16W,EMPTY,G21796-072!RES!!!F527!!HOT_SWAP!!
S!@baseboard_fab2_lib.baseboard_fab2(sch_1):page199_i38@mstr_discrete.res(chips)!RES_0402-4.75K,1%,1/16W,EMPTY,A!R1D27!//jf4cfls225.pdx.intel.com/apd_proj/ppg_lib/epg_masterlib/logical/mstr_discrete/res/chips/chips.prt!RES!RES_0402-4.75K,1%,1/16W,EMPTY,G21796-072!RES!!!F528!!HOT_SWAP!!
S!@baseboard_fab2_lib.baseboard_fab2(sch_1):page102_i46@mstr_discrete.res(chips)!RES_0402-4.75K,1%,1/16W,EMPTY,A!R6P23!//jf4cfls225.pdx.intel.com/apd_proj/ppg_lib/epg_masterlib/logical/mstr_discrete/res/chips/chips.prt!RES!RES_0402-4.75K,1%,1/16W,EMPTY,G21796-072!RES!!!F514!!DB1200ZL!!
S!@baseboard_fab2_lib.baseboard_fab2(sch_1):page165_i58@mstr_discrete.res(chips)!RES_0402-4.75K,1%,1/16W,EMPTY,A!R9G25!//jf4cfls225.pdx.intel.com/apd_proj/ppg_lib/epg_masterlib/logical/mstr_discrete/res/chips/chips.prt!RES!RES_0402-4.75K,1%,1/16W,EMPTY,G21796-072!RES!!!F498!!HEC_VOLT_MONITOR!!
S!@baseboard_fab2_lib.baseboard_fab2(sch_1):page165_i57@mstr_discrete.res(chips)!RES_0402-4.75K,1%,1/16W,EMPTY,A!R9G23!//jf4cfls225.pdx.intel.com/apd_proj/ppg_lib/epg_masterlib/logical/mstr_discrete/res/chips/chips.prt!RES!RES_0402-4.75K,1%,1/16W,EMPTY,G21796-072!RES!!!F499!!HEC_VOLT_MONITOR!!
S!@baseboard_fab2_lib.baseboard_fab2(sch_1):page153_i150@mstr_discrete.res(chips)!RES_0402-4.75K,1%,1/16W,EMPTY,A!R3T3!//jf4cfls225.pdx.intel.com/apd_proj/ppg_lib/epg_masterlib/logical/mstr_discrete/res/chips/chips.prt!RES!RES_0402-4.75K,1%,1/16W,EMPTY,G21796-072!RES!!!F516!!SB_SPI!!
S!@baseboard_fab2_lib.baseboard_fab2(sch_1):page162_i8@mstr_discrete.res(chips)!RES_0402-4.75K,1%,1/16W,EMPTY,A!R8F16!//jf4cfls225.pdx.intel.com/apd_proj/ppg_lib/epg_masterlib/logical/mstr_discrete/res/chips/chips.prt!RES!RES_0402-4.75K,1%,1/16W,EMPTY,G21796-072!RES!!!F510!!BMC_BOOT_SPI!!
S!@baseboard_fab2_lib.baseboard_fab2(sch_1):page153_i90@mstr_discrete.res(chips)!RES_0402-4.75K,1%,1/16W,EMPTY,A!R7F6!//jf4cfls225.pdx.intel.com/apd_proj/ppg_lib/epg_masterlib/logical/mstr_discrete/res/chips/chips.prt!RES!RES_0402-4.75K,1%,1/16W,EMPTY,G21796-072!RES!!!F512!!SB_SPI!!
S!@baseboard_fab2_lib.baseboard_fab2(sch_1):page101_i28@mstr_discrete.res(chips)!RES_0402-475.0,1%,1/16W,CHIP,GA!R8F25!//jf4cfls225.pdx.intel.com/apd_proj/ppg_lib/epg_masterlib/logical/mstr_discrete/res/chips/chips.prt!RES!RES_0402-475.0,1%,1/16W,CHIP,G21796-077!RES!!!F467!!SYS_CLOCK!!
S!@baseboard_fab2_lib.baseboard_fab2(sch_1):page111_i55@mstr_discrete.res(chips)!RES_0402-475.0,1%,1/16W,CHIP,GA!R9A4!//jf4cfls225.pdx.intel.com/apd_proj/ppg_lib/epg_masterlib/logical/mstr_discrete/res/chips/chips.prt!RES!RES_0402-475.0,1%,1/16W,CHIP,G21796-077!RES!!!F466!!DEBUG!!
S!@baseboard_fab2_lib.baseboard_fab2(sch_1):page237_i3@mstr_discrete.res(chips)!RES_0402-5.11K,1%,1/16W,CHIP,GA!R8A10!//jf4cfls225.pdx.intel.com/apd_proj/ppg_lib/epg_masterlib/logical/mstr_discrete/res/chips/chips.prt!RES!RES_0402-5.11K,1%,1/16W,CHIP,G21796-140!RES!!!F390!!P1V8_PCH_STBY_VR!!
S!@baseboard_fab2_lib.baseboard_fab2(sch_1):page169_i141@mstr_discrete.res(chips)!RES_0402-5.11K,1%,1/16W,CHIP,GA!R1U29!//jf4cfls225.pdx.intel.com/apd_proj/ppg_lib/epg_masterlib/logical/mstr_discrete/res/chips/chips.prt!RES!RES_0402-5.11K,1%,1/16W,CHIP,G21796-140!RES!!!F394!!BMC_VOLT_MONITOR!!
S!@baseboard_fab2_lib.baseboard_fab2(sch_1):page169_i148@mstr_discrete.res(chips)!RES_0402-5.11K,1%,1/16W,CHIP,GA!R1U26!//jf4cfls225.pdx.intel.com/apd_proj/ppg_lib/epg_masterlib/logical/mstr_discrete/res/chips/chips.prt!RES!RES_0402-5.11K,1%,1/16W,CHIP,G21796-140!RES!!!F395!!BMC_VOLT_MONITOR!!
S!@baseboard_fab2_lib.baseboard_fab2(sch_1):page169_i115@mstr_discrete.res(chips)!RES_0402-5.11K,1%,1/16W,CHIP,GA!R1U47!//jf4cfls225.pdx.intel.com/apd_proj/ppg_lib/epg_masterlib/logical/mstr_discrete/res/chips/chips.prt!RES!RES_0402-5.11K,1%,1/16W,CHIP,G21796-140!RES!!!F391!!BMC_VOLT_MONITOR!!
S!@baseboard_fab2_lib.baseboard_fab2(sch_1):page169_i82@mstr_discrete.res(chips)!RES_0402-5.11K,1%,1/16W,CHIP,GA!R1U32!//jf4cfls225.pdx.intel.com/apd_proj/ppg_lib/epg_masterlib/logical/mstr_discrete/res/chips/chips.prt!RES!RES_0402-5.11K,1%,1/16W,CHIP,G21796-140!RES!!!F393!!BMC_VOLT_MONITOR!!
S!@baseboard_fab2_lib.baseboard_fab2(sch_1):page169_i88@mstr_discrete.res(chips)!RES_0402-5.11K,1%,1/16W,CHIP,GA!R1U39!//jf4cfls225.pdx.intel.com/apd_proj/ppg_lib/epg_masterlib/logical/mstr_discrete/res/chips/chips.prt!RES!RES_0402-5.11K,1%,1/16W,CHIP,G21796-140!RES!!!F392!!BMC_VOLT_MONITOR!!
S!@baseboard_fab2_lib.baseboard_fab2(sch_1):page221_i55@mstr_discrete.res(chips)!RES_0402-51.1,1.0%,1/16W,CHIP,A!R6U16!//jf4cfls225.pdx.intel.com/apd_proj/ppg_lib/epg_masterlib/logical/mstr_discrete/res/chips/chips.prt!RES!RES_0402-51.1,1.0%,1/16W,CHIP,G21796-208!RES!!!F377!!!!
S!@baseboard_fab2_lib.baseboard_fab2(sch_1):page222_i52@mstr_discrete.res(chips)!RES_0402-51.1,1.0%,1/16W,CHIP,A!R4A1!//jf4cfls225.pdx.intel.com/apd_proj/ppg_lib/epg_masterlib/logical/mstr_discrete/res/chips/chips.prt!RES!RES_0402-51.1,1.0%,1/16W,CHIP,G21796-208!RES!!!F381!!!!
S!@baseboard_fab2_lib.baseboard_fab2(sch_1):page229_i52@mstr_discrete.res(chips)!RES_0402-51.1,1.0%,1/16W,CHIP,A!R6U8!//jf4cfls225.pdx.intel.com/apd_proj/ppg_lib/epg_masterlib/logical/mstr_discrete/res/chips/chips.prt!RES!RES_0402-51.1,1.0%,1/16W,CHIP,G21796-208!RES!!!F378!!!!
S!@baseboard_fab2_lib.baseboard_fab2(sch_1):page230_i52@mstr_discrete.res(chips)!RES_0402-51.1,1.0%,1/16W,CHIP,A!R6L7!//jf4cfls225.pdx.intel.com/apd_proj/ppg_lib/epg_masterlib/logical/mstr_discrete/res/chips/chips.prt!RES!RES_0402-51.1,1.0%,1/16W,CHIP,G21796-208!RES!!!F380!!!!
S!@baseboard_fab2_lib.baseboard_fab2(sch_1):page214_i109@mstr_discrete.res(chips)!RES_0402-51.1,1.0%,1/16W,CHIP,A!R7R1!//jf4cfls225.pdx.intel.com/apd_proj/ppg_lib/epg_masterlib/logical/mstr_discrete/res/chips/chips.prt!RES!RES_0402-51.1,1.0%,1/16W,CHIP,G21796-208!RES!!!F374!!!!
S!@baseboard_fab2_lib.baseboard_fab2(sch_1):page205_i45@mstr_discrete.res(chips)!RES_0402-51.1,1.0%,1/16W,CHIP,A!R6N4!//jf4cfls225.pdx.intel.com/apd_proj/ppg_lib/epg_masterlib/logical/mstr_discrete/res/chips/chips.prt!RES!RES_0402-51.1,1.0%,1/16W,CHIP,G21796-208!RES!!!F379!!!!
S!@baseboard_fab2_lib.baseboard_fab2(sch_1):page210_i45@mstr_discrete.res(chips)!RES_0402-51.1,1.0%,1/16W,CHIP,A!R9N4!//jf4cfls225.pdx.intel.com/apd_proj/ppg_lib/epg_masterlib/logical/mstr_discrete/res/chips/chips.prt!RES!RES_0402-51.1,1.0%,1/16W,CHIP,G21796-208!RES!!!F372!!!!
S!@baseboard_fab2_lib.baseboard_fab2(sch_1):page212_i78@mstr_discrete.res(chips)!RES_0402-51.1,1.0%,1/16W,CHIP,A!R7C3!//jf4cfls225.pdx.intel.com/apd_proj/ppg_lib/epg_masterlib/logical/mstr_discrete/res/chips/chips.prt!RES!RES_0402-51.1,1.0%,1/16W,CHIP,G21796-208!RES!!!F376!!!!
S!@baseboard_fab2_lib.baseboard_fab2(sch_1):page157_i302@mstr_discrete.res(chips)!RES_0402-51.1,1.0%,1/16W,CHIP,A!R2N25!//jf4cfls225.pdx.intel.com/apd_proj/ppg_lib/epg_masterlib/logical/mstr_discrete/res/chips/chips.prt!RES!RES_0402-51.1,1.0%,1/16W,CHIP,G21796-208!RES!!!F382!!BMC_MISC!!
S!@baseboard_fab2_lib.baseboard_fab2(sch_1):page112_i61@mstr_discrete.res(chips)!RES_0402-51.1,1.0%,1/16W,CHIP,A!R7P29!//jf4cfls225.pdx.intel.com/apd_proj/ppg_lib/epg_masterlib/logical/mstr_discrete/res/chips/chips.prt!RES!RES_0402-51.1,1.0%,1/16W,CHIP,G21796-208!RES!!!F375!!DEBUG!!
S!@baseboard_fab2_lib.baseboard_fab2(sch_1):page112_i95@mstr_discrete.res(chips)!RES_0402-51.1,1.0%,1/16W,CHIP,A!R8B1!//jf4cfls225.pdx.intel.com/apd_proj/ppg_lib/epg_masterlib/logical/mstr_discrete/res/chips/chips.prt!RES!RES_0402-51.1,1.0%,1/16W,CHIP,G21796-208!RES!!!F373!!DEBUG!!
S!@baseboard_fab2_lib.baseboard_fab2(sch_1):page181_i185@mstr_discrete.res(chips)!RES_0402-6.19K,1%,1/16W,CHIP,GA!R9T3!//jf4cfls225.pdx.intel.com/apd_proj/ppg_lib/epg_masterlib/logical/mstr_discrete/res/chips/chips.prt!RES!RES_0402-6.19K,1%,1/16W,CHIP,G21796-161!RES!!!F370!!IO_SLOT!!
S!@baseboard_fab2_lib.baseboard_fab2(sch_1):page199_i43@mstr_discrete.res(chips)!RES_0402-6.19K,1%,1/16W,CHIP,GA!R1D31!//jf4cfls225.pdx.intel.com/apd_proj/ppg_lib/epg_masterlib/logical/mstr_discrete/res/chips/chips.prt!RES!RES_0402-6.19K,1%,1/16W,CHIP,G21796-161!RES!!!F371!!HOT_SWAP!!
S!@baseboard_fab2_lib.baseboard_fab2(sch_1):page177_i43@mstr_discrete.res(chips)!RES_0402-64.9,1.0%,1/16W,CHIP,A!R1L21!//jf4cfls225.pdx.intel.com/apd_proj/ppg_lib/epg_masterlib/logical/mstr_discrete/res/chips/chips.prt!RES!RES_0402-64.9,1.0%,1/16W,CHIP,G21796-298!RES!!!F363!!MIO_CHASSIS!!
S!@baseboard_fab2_lib.baseboard_fab2(sch_1):page96_i28@mstr_discrete.res(chips)!RES_0402-64.9,1.0%,1/16W,CHIP,A!R7M9!//jf4cfls225.pdx.intel.com/apd_proj/ppg_lib/epg_masterlib/logical/mstr_discrete/res/chips/chips.prt!RES!RES_0402-64.9,1.0%,1/16W,CHIP,G21796-298!RES!!!F359!!PROC_RSTS_PGOODS!!
S!@baseboard_fab2_lib.baseboard_fab2(sch_1):page96_i30@mstr_discrete.res(chips)!RES_0402-64.9,1.0%,1/16W,CHIP,A!R3D21!//jf4cfls225.pdx.intel.com/apd_proj/ppg_lib/epg_masterlib/logical/mstr_discrete/res/chips/chips.prt!RES!RES_0402-64.9,1.0%,1/16W,CHIP,G21796-298!RES!!!F362!!PROC_RSTS_PGOODS!!
S!@baseboard_fab2_lib.baseboard_fab2(sch_1):page96_i7@mstr_discrete.res(chips)!RES_0402-64.9,1.0%,1/16W,CHIP,A!R3P38!//jf4cfls225.pdx.intel.com/apd_proj/ppg_lib/epg_masterlib/logical/mstr_discrete/res/chips/chips.prt!RES!RES_0402-64.9,1.0%,1/16W,CHIP,G21796-298!RES!!!F360!!PROC_RSTS_PGOODS!!
S!@baseboard_fab2_lib.baseboard_fab2(sch_1):page96_i5@mstr_discrete.res(chips)!RES_0402-64.9,1.0%,1/16W,CHIP,A!R3P29!//jf4cfls225.pdx.intel.com/apd_proj/ppg_lib/epg_masterlib/logical/mstr_discrete/res/chips/chips.prt!RES!RES_0402-64.9,1.0%,1/16W,CHIP,G21796-298!RES!!!F361!!PROC_RSTS_PGOODS!!
S!@baseboard_fab2_lib.baseboard_fab2(sch_1):page160_i46@mstr_discrete.res(chips)!RES_0402-665,1.0%,1/16W,CHIP,GA!R1T3!//jf4cfls225.pdx.intel.com/apd_proj/ppg_lib/epg_masterlib/logical/mstr_discrete/res/chips/chips.prt!RES!RES_0402-665,1.0%,1/16W,CHIP,G21796-235!RES!!!F356!!SMBUS!!
S!@baseboard_fab2_lib.baseboard_fab2(sch_1):page160_i49@mstr_discrete.res(chips)!RES_0402-665,1.0%,1/16W,CHIP,GA!R1T2!//jf4cfls225.pdx.intel.com/apd_proj/ppg_lib/epg_masterlib/logical/mstr_discrete/res/chips/chips.prt!RES!RES_0402-665,1.0%,1/16W,CHIP,G21796-235!RES!!!F357!!SMBUS!!
S!@baseboard_fab2_lib.baseboard_fab2(sch_1):page138_i83@mstr_discrete.res(chips)!RES_0402-665,1.0%,1/16W,CHIP,GA!R2T53!//jf4cfls225.pdx.intel.com/apd_proj/ppg_lib/epg_masterlib/logical/mstr_discrete/res/chips/chips.prt!RES!RES_0402-665,1.0%,1/16W,CHIP,G21796-235!RES!!!F353!!SMBUS!!
S!@baseboard_fab2_lib.baseboard_fab2(sch_1):page167_i83@mstr_discrete.res(chips)!RES_0402-665,1.0%,1/16W,CHIP,GA!R2U39!//jf4cfls225.pdx.intel.com/apd_proj/ppg_lib/epg_masterlib/logical/mstr_discrete/res/chips/chips.prt!RES!RES_0402-665,1.0%,1/16W,CHIP,G21796-235!RES!!!F348!!SMBUS!!
S!@baseboard_fab2_lib.baseboard_fab2(sch_1):page138_i84@mstr_discrete.res(chips)!RES_0402-665,1.0%,1/16W,CHIP,GA!R2T54!//jf4cfls225.pdx.intel.com/apd_proj/ppg_lib/epg_masterlib/logical/mstr_discrete/res/chips/chips.prt!RES!RES_0402-665,1.0%,1/16W,CHIP,G21796-235!RES!!!F352!!SMBUS!!
S!@baseboard_fab2_lib.baseboard_fab2(sch_1):page167_i80@mstr_discrete.res(chips)!RES_0402-665,1.0%,1/16W,CHIP,GA!R2U38!//jf4cfls225.pdx.intel.com/apd_proj/ppg_lib/epg_masterlib/logical/mstr_discrete/res/chips/chips.prt!RES!RES_0402-665,1.0%,1/16W,CHIP,G21796-235!RES!!!F349!!SMBUS!!
S!@baseboard_fab2_lib.baseboard_fab2(sch_1):page138_i97@mstr_discrete.res(chips)!RES_0402-665,1.0%,1/16W,CHIP,GA!R2U11!//jf4cfls225.pdx.intel.com/apd_proj/ppg_lib/epg_masterlib/logical/mstr_discrete/res/chips/chips.prt!RES!RES_0402-665,1.0%,1/16W,CHIP,G21796-235!RES!!!F350!!SMBUS!!
S!@baseboard_fab2_lib.baseboard_fab2(sch_1):page138_i98@mstr_discrete.res(chips)!RES_0402-665,1.0%,1/16W,CHIP,GA!R2U3!//jf4cfls225.pdx.intel.com/apd_proj/ppg_lib/epg_masterlib/logical/mstr_discrete/res/chips/chips.prt!RES!RES_0402-665,1.0%,1/16W,CHIP,G21796-235!RES!!!F351!!SMBUS!!
S!@baseboard_fab2_lib.baseboard_fab2(sch_1):page138_i89@mstr_discrete.res(chips)!RES_0402-665,1.0%,1/16W,CHIP,GA!R2N8!//jf4cfls225.pdx.intel.com/apd_proj/ppg_lib/epg_masterlib/logical/mstr_discrete/res/chips/chips.prt!RES!RES_0402-665,1.0%,1/16W,CHIP,G21796-235!RES!!!F354!!SMBUS!!
S!@baseboard_fab2_lib.baseboard_fab2(sch_1):page138_i90@mstr_discrete.res(chips)!RES_0402-665,1.0%,1/16W,CHIP,GA!R2N5!//jf4cfls225.pdx.intel.com/apd_proj/ppg_lib/epg_masterlib/logical/mstr_discrete/res/chips/chips.prt!RES!RES_0402-665,1.0%,1/16W,CHIP,G21796-235!RES!!!F355!!SMBUS!!
S!@baseboard_fab2_lib.baseboard_fab2(sch_1):page99_i13@mstr_discrete.res(chips)!RES_0402-665,1.0%,1/16W,CHIP,GA!R4T7!//jf4cfls225.pdx.intel.com/apd_proj/ppg_lib/epg_masterlib/logical/mstr_discrete/res/chips/chips.prt!RES!RES_0402-665,1.0%,1/16W,CHIP,G21796-235!RES!!!F345!!MEM!!
S!@baseboard_fab2_lib.baseboard_fab2(sch_1):page99_i106@mstr_discrete.res(chips)!RES_0402-665,1.0%,1/16W,CHIP,GA!R6U17!//jf4cfls225.pdx.intel.com/apd_proj/ppg_lib/epg_masterlib/logical/mstr_discrete/res/chips/chips.prt!RES!RES_0402-665,1.0%,1/16W,CHIP,G21796-235!RES!!!F343!!MEM!!
S!@baseboard_fab2_lib.baseboard_fab2(sch_1):page99_i109@mstr_discrete.res(chips)!RES_0402-665,1.0%,1/16W,CHIP,GA!R7M1!//jf4cfls225.pdx.intel.com/apd_proj/ppg_lib/epg_masterlib/logical/mstr_discrete/res/chips/chips.prt!RES!RES_0402-665,1.0%,1/16W,CHIP,G21796-235!RES!!!F341!!MEM!!
S!@baseboard_fab2_lib.baseboard_fab2(sch_1):page99_i103@mstr_discrete.res(chips)!RES_0402-665,1.0%,1/16W,CHIP,GA!R3R5!//jf4cfls225.pdx.intel.com/apd_proj/ppg_lib/epg_masterlib/logical/mstr_discrete/res/chips/chips.prt!RES!RES_0402-665,1.0%,1/16W,CHIP,G21796-235!RES!!!F347!!MEM!!
S!@baseboard_fab2_lib.baseboard_fab2(sch_1):page99_i11@mstr_discrete.res(chips)!RES_0402-665,1.0%,1/16W,CHIP,GA!R4T8!//jf4cfls225.pdx.intel.com/apd_proj/ppg_lib/epg_masterlib/logical/mstr_discrete/res/chips/chips.prt!RES!RES_0402-665,1.0%,1/16W,CHIP,G21796-235!RES!!!F344!!MEM!!
S!@baseboard_fab2_lib.baseboard_fab2(sch_1):page99_i104@mstr_discrete.res(chips)!RES_0402-665,1.0%,1/16W,CHIP,GA!R6U18!//jf4cfls225.pdx.intel.com/apd_proj/ppg_lib/epg_masterlib/logical/mstr_discrete/res/chips/chips.prt!RES!RES_0402-665,1.0%,1/16W,CHIP,G21796-235!RES!!!F342!!MEM!!
S!@baseboard_fab2_lib.baseboard_fab2(sch_1):page99_i107@mstr_discrete.res(chips)!RES_0402-665,1.0%,1/16W,CHIP,GA!R7M6!//jf4cfls225.pdx.intel.com/apd_proj/ppg_lib/epg_masterlib/logical/mstr_discrete/res/chips/chips.prt!RES!RES_0402-665,1.0%,1/16W,CHIP,G21796-235!RES!!!F340!!MEM!!
S!@baseboard_fab2_lib.baseboard_fab2(sch_1):page99_i101@mstr_discrete.res(chips)!RES_0402-665,1.0%,1/16W,CHIP,GA!R3R12!//jf4cfls225.pdx.intel.com/apd_proj/ppg_lib/epg_masterlib/logical/mstr_discrete/res/chips/chips.prt!RES!RES_0402-665,1.0%,1/16W,CHIP,G21796-235!RES!!!F346!!MEM!!
S!@baseboard_fab2_lib.baseboard_fab2(sch_1):page235_i154@mstr_discrete.res(chips)!RES_0603-10.0,1%,1/10W,CHIP,G2A!R2L8!//jf4cfls225.pdx.intel.com/apd_proj/ppg_lib/epg_masterlib/logical/mstr_discrete/res/chips/chips.prt!RES!RES_0603-10.0,1%,1/10W,CHIP,G22026-041!RES!!!F277!!PVNN_PCH_STBY!!
S!@baseboard_fab2_lib.baseboard_fab2(sch_1):page199_i2@mstr_discrete.res(chips)!RES_0603-10.0,1%,1/10W,CHIP,G2A!R9P30!//jf4cfls225.pdx.intel.com/apd_proj/ppg_lib/epg_masterlib/logical/mstr_discrete/res/chips/chips.prt!RES!RES_0603-10.0,1%,1/10W,CHIP,G22026-041!RES!!!F276!!HOT_SWAP!!
S!@baseboard_fab2_lib.baseboard_fab2(sch_1):page203_i67@mstr_discrete.res(chips)!RES_0603-100.0,1%,1/10W,CHIP,GA!R4E13!//jf4cfls225.pdx.intel.com/apd_proj/ppg_lib/epg_masterlib/logical/mstr_discrete/res/chips/chips.prt!RES!RES_0603-100.0,1%,1/10W,CHIP,G22026-038!RES!!!F274!!PVCCIN_CPU0_DECAP_VR!!
S!@baseboard_fab2_lib.baseboard_fab2(sch_1):page208_i7@mstr_discrete.res(chips)!RES_0603-100.0,1%,1/10W,CHIP,GA!R1E3!//jf4cfls225.pdx.intel.com/apd_proj/ppg_lib/epg_masterlib/logical/mstr_discrete/res/chips/chips.prt!RES!RES_0603-100.0,1%,1/10W,CHIP,G22026-038!RES!!!F275!!PVCCIN_CPU1_DECAP_VR!!
S!@baseboard_fab2_lib.baseboard_fab2(sch_1):page114_i54@mstr_discrete.res(chips)!RES_0603-10M,1.0%,1/10W,CHIP,GA!R7C6!//jf4cfls225.pdx.intel.com/apd_proj/ppg_lib/epg_masterlib/logical/mstr_discrete/res/chips/chips.prt!RES!RES_0603-10M,1.0%,1/10W,CHIP,G22026-112!RES!!!F271!!SB!!
S!@baseboard_fab2_lib.baseboard_fab2(sch_1):page231_i177@mstr_discrete.res(chips)!RES_0603-120.0,1%,1/10W,CHIP,GA!R7F10!//jf4cfls225.pdx.intel.com/apd_proj/ppg_lib/epg_masterlib/logical/mstr_discrete/res/chips/chips.prt!RES!RES_0603-120.0,1%,1/10W,CHIP,G22026-003!RES!!!F263!!PVPP_KLM_VR!!
S!@baseboard_fab2_lib.baseboard_fab2(sch_1):page232_i227@mstr_discrete.res(chips)!RES_0603-120.0,1%,1/10W,CHIP,GA!R7B10!//jf4cfls225.pdx.intel.com/apd_proj/ppg_lib/epg_masterlib/logical/mstr_discrete/res/chips/chips.prt!RES!RES_0603-120.0,1%,1/10W,CHIP,G22026-003!RES!!!F264!!PVPP_KLM_VR!!
S!@baseboard_fab2_lib.baseboard_fab2(sch_1):page233_i211@mstr_discrete.res(chips)!RES_0603-120.0,1%,1/10W,CHIP,GA!R4G6!//jf4cfls225.pdx.intel.com/apd_proj/ppg_lib/epg_masterlib/logical/mstr_discrete/res/chips/chips.prt!RES!RES_0603-120.0,1%,1/10W,CHIP,G22026-003!RES!!!F266!!PVPP_KLM_VR!!
S!@baseboard_fab2_lib.baseboard_fab2(sch_1):page234_i183@mstr_discrete.res(chips)!RES_0603-120.0,1%,1/10W,CHIP,GA!R4B2!//jf4cfls225.pdx.intel.com/apd_proj/ppg_lib/epg_masterlib/logical/mstr_discrete/res/chips/chips.prt!RES!RES_0603-120.0,1%,1/10W,CHIP,G22026-003!RES!!!F267!!PVPP_KLM_VR!!
S!@baseboard_fab2_lib.baseboard_fab2(sch_1):page217_i58@mstr_discrete.res(chips)!RES_0603-120.0,1%,1/10W,CHIP,GA!R3U4!//jf4cfls225.pdx.intel.com/apd_proj/ppg_lib/epg_masterlib/logical/mstr_discrete/res/chips/chips.prt!RES!RES_0603-120.0,1%,1/10W,CHIP,G22026-003!RES!!!F268!!VDDQ_ABC_PWR_VR!!
S!@baseboard_fab2_lib.baseboard_fab2(sch_1):page225_i58@mstr_discrete.res(chips)!RES_0603-120.0,1%,1/10W,CHIP,GA!R1G20!//jf4cfls225.pdx.intel.com/apd_proj/ppg_lib/epg_masterlib/logical/mstr_discrete/res/chips/chips.prt!RES!RES_0603-120.0,1%,1/10W,CHIP,G22026-003!RES!!!F269!!VDDQ_GHJ_PWR_VR!!
S!@baseboard_fab2_lib.baseboard_fab2(sch_1):page228_i58@mstr_discrete.res(chips)!RES_0603-120.0,1%,1/10W,CHIP,GA!R1A1!//jf4cfls225.pdx.intel.com/apd_proj/ppg_lib/epg_masterlib/logical/mstr_discrete/res/chips/chips.prt!RES!RES_0603-120.0,1%,1/10W,CHIP,G22026-003!RES!!!F270!!VDDQ_KLM_PWR_VR!!
S!@baseboard_fab2_lib.baseboard_fab2(sch_1):page220_i58@mstr_discrete.res(chips)!RES_0603-120.0,1%,1/10W,CHIP,GA!R4L4!//jf4cfls225.pdx.intel.com/apd_proj/ppg_lib/epg_masterlib/logical/mstr_discrete/res/chips/chips.prt!RES!RES_0603-120.0,1%,1/10W,CHIP,G22026-003!RES!!!F265!!VDDQ_DEF_PWR_VR!!
S!@baseboard_fab2_lib.baseboard_fab2(sch_1):page166_i15@mstr_discrete.res(chips)!RES_0402-0.0,5%,1/16W,CHIP,G21A!R7C19!//jf4cfls225.pdx.intel.com/apd_proj/ppg_lib/epg_masterlib/logical/mstr_discrete/res/chips/chips.prt!RES!RES_0402-0.0,5%,1/16W,CHIP,G21497-005!RES!!!F1811!!PECI!!
S!@baseboard_fab2_lib.baseboard_fab2(sch_1):page145_i132@mstr_discrete.res(chips)!RES_0402-0.0,5%,1/16W,CHIP,G21A!R9F33!//jf4cfls225.pdx.intel.com/apd_proj/ppg_lib/epg_masterlib/logical/mstr_discrete/res/chips/chips.prt!RES!RES_0402-0.0,5%,1/16W,CHIP,G21497-005!RES!!!F1752!!BMC!!
S!@baseboard_fab2_lib.baseboard_fab2(sch_1):page156_i299@mstr_discrete.res(chips)!RES_0402-0.0,5%,1/16W,CHIP,G21A!R6D16!//jf4cfls225.pdx.intel.com/apd_proj/ppg_lib/epg_masterlib/logical/mstr_discrete/res/chips/chips.prt!RES!RES_0402-0.0,5%,1/16W,CHIP,G21497-005!RES!!!F1688!!BMC_MISC!!
S!@baseboard_fab2_lib.baseboard_fab2(sch_1):page156_i300@mstr_discrete.res(chips)!RES_0402-0.0,5%,1/16W,CHIP,G21A!R3D31!//jf4cfls225.pdx.intel.com/apd_proj/ppg_lib/epg_masterlib/logical/mstr_discrete/res/chips/chips.prt!RES!RES_0402-0.0,5%,1/16W,CHIP,G21497-005!RES!!!F1687!!BMC_MISC!!
S!@baseboard_fab2_lib.baseboard_fab2(sch_1):page156_i322@mstr_discrete.res(chips)!RES_0402-0.0,5%,1/16W,CHIP,G21A!R4A8!//jf4cfls225.pdx.intel.com/apd_proj/ppg_lib/epg_masterlib/logical/mstr_discrete/res/chips/chips.prt!RES!RES_0402-0.0,5%,1/16W,CHIP,G21497-005!RES!!!F1686!!CPU0!!
S!@baseboard_fab2_lib.baseboard_fab2(sch_1):page156_i324@mstr_discrete.res(chips)!RES_0402-0.0,5%,1/16W,CHIP,G21A!R4A9!//jf4cfls225.pdx.intel.com/apd_proj/ppg_lib/epg_masterlib/logical/mstr_discrete/res/chips/chips.prt!RES!RES_0402-0.0,5%,1/16W,CHIP,G21497-005!RES!!!F1685!!CPU0!!
S!@baseboard_fab2_lib.baseboard_fab2(sch_1):page156_i321@mstr_discrete.res(chips)!RES_0402-0.0,5%,1/16W,CHIP,G21A!R9M21!//jf4cfls225.pdx.intel.com/apd_proj/ppg_lib/epg_masterlib/logical/mstr_discrete/res/chips/chips.prt!RES!RES_0402-0.0,5%,1/16W,CHIP,G21497-005!RES!!!F1684!!CPU1!!
S!@baseboard_fab2_lib.baseboard_fab2(sch_1):page156_i323@mstr_discrete.res(chips)!RES_0402-0.0,5%,1/16W,CHIP,G21A!R9M20!//jf4cfls225.pdx.intel.com/apd_proj/ppg_lib/epg_masterlib/logical/mstr_discrete/res/chips/chips.prt!RES!RES_0402-0.0,5%,1/16W,CHIP,G21497-005!RES!!!F1683!!CPU1!!
S!@baseboard_fab2_lib.baseboard_fab2(sch_1):page113_i239@mstr_discrete.res(chips)!RES_0402-0.0,5%,1/16W,CHIP,G21A!R9B11!//jf4cfls225.pdx.intel.com/apd_proj/ppg_lib/epg_masterlib/logical/mstr_discrete/res/chips/chips.prt!RES!RES_0402-0.0,5%,1/16W,CHIP,G21497-005!RES!!!F1682!!!!
S!@baseboard_fab2_lib.baseboard_fab2(sch_1):page113_i240@mstr_discrete.res(chips)!RES_0402-0.0,5%,1/16W,CHIP,G21A!R9B13!//jf4cfls225.pdx.intel.com/apd_proj/ppg_lib/epg_masterlib/logical/mstr_discrete/res/chips/chips.prt!RES!RES_0402-0.0,5%,1/16W,CHIP,G21497-005!RES!!!F1681!!!!
S!@baseboard_fab2_lib.baseboard_fab2(sch_1):page145_i256@mstr_discrete.res(chips)!RES_0402-0.0,5%,1/16W,CHIP,G21A!R9F62!//jf4cfls225.pdx.intel.com/apd_proj/ppg_lib/epg_masterlib/logical/mstr_discrete/res/chips/chips.prt!RES!RES_0402-0.0,5%,1/16W,CHIP,G21497-005!RES!!!F1690!!BMC!!
S!@baseboard_fab2_lib.baseboard_fab2(sch_1):page108_i341@mstr_discrete.res(chips)!RES_0402-0.0,5%,1/16W,CHIP,G21A!R7E22!//jf4cfls225.pdx.intel.com/apd_proj/ppg_lib/epg_masterlib/logical/mstr_discrete/res/chips/chips.prt!RES!RES_0402-0.0,5%,1/16W,CHIP,G21497-005!RES!!!F1689!!IO_SLOT!!
S!@baseboard_fab2_lib.baseboard_fab2(sch_1):page93_i111@mstr_discrete.res(chips)!RES_0402-0.0,5%,1/16W,CHIP,G21A!R2T65!//jf4cfls225.pdx.intel.com/apd_proj/ppg_lib/epg_masterlib/logical/mstr_discrete/res/chips/chips.prt!RES!RES_0402-0.0,5%,1/16W,CHIP,G21497-005!RES!!!F1706!!!!
S!@baseboard_fab2_lib.baseboard_fab2(sch_1):page93_i112@mstr_discrete.res(chips)!RES_0402-0.0,5%,1/16W,CHIP,G21A!R2T66!//jf4cfls225.pdx.intel.com/apd_proj/ppg_lib/epg_masterlib/logical/mstr_discrete/res/chips/chips.prt!RES!RES_0402-0.0,5%,1/16W,CHIP,G21497-005!RES!!!F1705!!!!
S!@baseboard_fab2_lib.baseboard_fab2(sch_1):page93_i113@mstr_discrete.res(chips)!RES_0402-0.0,5%,1/16W,CHIP,G21A!R2T67!//jf4cfls225.pdx.intel.com/apd_proj/ppg_lib/epg_masterlib/logical/mstr_discrete/res/chips/chips.prt!RES!RES_0402-0.0,5%,1/16W,CHIP,G21497-005!RES!!!F1704!!!!
S!@baseboard_fab2_lib.baseboard_fab2(sch_1):page93_i114@mstr_discrete.res(chips)!RES_0402-0.0,5%,1/16W,CHIP,G21A!R7D41!//jf4cfls225.pdx.intel.com/apd_proj/ppg_lib/epg_masterlib/logical/mstr_discrete/res/chips/chips.prt!RES!RES_0402-0.0,5%,1/16W,CHIP,G21497-005!RES!!!F1703!!!!
S!@baseboard_fab2_lib.baseboard_fab2(sch_1):page93_i119@mstr_discrete.res(chips)!RES_0402-0.0,5%,1/16W,CHIP,G21A!R8F38!//jf4cfls225.pdx.intel.com/apd_proj/ppg_lib/epg_masterlib/logical/mstr_discrete/res/chips/chips.prt!RES!RES_0402-0.0,5%,1/16W,CHIP,G21497-005!RES!!!F1702!!!!
S!@baseboard_fab2_lib.baseboard_fab2(sch_1):page93_i121@mstr_discrete.res(chips)!RES_0402-0.0,5%,1/16W,CHIP,G21A!R2T64!//jf4cfls225.pdx.intel.com/apd_proj/ppg_lib/epg_masterlib/logical/mstr_discrete/res/chips/chips.prt!RES!RES_0402-0.0,5%,1/16W,CHIP,G21497-005!RES!!!F1701!!!!
S!@baseboard_fab2_lib.baseboard_fab2(sch_1):page93_i122@mstr_discrete.res(chips)!RES_0402-0.0,5%,1/16W,CHIP,G21A!R1T36!//jf4cfls225.pdx.intel.com/apd_proj/ppg_lib/epg_masterlib/logical/mstr_discrete/res/chips/chips.prt!RES!RES_0402-0.0,5%,1/16W,CHIP,G21497-005!RES!!!F1700!!!!
S!@baseboard_fab2_lib.baseboard_fab2(sch_1):page93_i123@mstr_discrete.res(chips)!RES_0402-0.0,5%,1/16W,CHIP,G21A!R1T37!//jf4cfls225.pdx.intel.com/apd_proj/ppg_lib/epg_masterlib/logical/mstr_discrete/res/chips/chips.prt!RES!RES_0402-0.0,5%,1/16W,CHIP,G21497-005!RES!!!F1699!!!!
S!@baseboard_fab2_lib.baseboard_fab2(sch_1):page152_i74@mstr_discrete.res(chips)!RES_0402-0.0,5%,1/16W,CHIP,G21A!R1U59!//jf4cfls225.pdx.intel.com/apd_proj/ppg_lib/epg_masterlib/logical/mstr_discrete/res/chips/chips.prt!RES!RES_0402-0.0,5%,1/16W,CHIP,G21497-005!RES!!!F1698!!!!
S!@baseboard_fab2_lib.baseboard_fab2(sch_1):page152_i73@mstr_discrete.res(chips)!RES_0402-0.0,5%,1/16W,CHIP,G21A!R9G33!//jf4cfls225.pdx.intel.com/apd_proj/ppg_lib/epg_masterlib/logical/mstr_discrete/res/chips/chips.prt!RES!RES_0402-0.0,5%,1/16W,CHIP,G21497-005!RES!!!F1697!!!!
S!@baseboard_fab2_lib.baseboard_fab2(sch_1):page152_i72@mstr_discrete.res(chips)!RES_0402-0.0,5%,1/16W,CHIP,G21A!R9G32!//jf4cfls225.pdx.intel.com/apd_proj/ppg_lib/epg_masterlib/logical/mstr_discrete/res/chips/chips.prt!RES!RES_0402-0.0,5%,1/16W,CHIP,G21497-005!RES!!!F1696!!!!
S!@baseboard_fab2_lib.baseboard_fab2(sch_1):page152_i71@mstr_discrete.res(chips)!RES_0402-0.0,5%,1/16W,CHIP,G21A!R9G28!//jf4cfls225.pdx.intel.com/apd_proj/ppg_lib/epg_masterlib/logical/mstr_discrete/res/chips/chips.prt!RES!RES_0402-0.0,5%,1/16W,CHIP,G21497-005!RES!!!F1695!!!!
S!@baseboard_fab2_lib.baseboard_fab2(sch_1):page152_i79@mstr_discrete.res(chips)!RES_0402-0.0,5%,1/16W,CHIP,G21A!R2U47!//jf4cfls225.pdx.intel.com/apd_proj/ppg_lib/epg_masterlib/logical/mstr_discrete/res/chips/chips.prt!RES!RES_0402-0.0,5%,1/16W,CHIP,G21497-005!RES!!!F1694!!!!
S!@baseboard_fab2_lib.baseboard_fab2(sch_1):page152_i92@mstr_discrete.res(chips)!RES_0402-0.0,5%,1/16W,CHIP,G21A!R9G29!//jf4cfls225.pdx.intel.com/apd_proj/ppg_lib/epg_masterlib/logical/mstr_discrete/res/chips/chips.prt!RES!RES_0402-0.0,5%,1/16W,CHIP,G21497-005!RES!!!F1693!!!!
S!@baseboard_fab2_lib.baseboard_fab2(sch_1):page152_i93@mstr_discrete.res(chips)!RES_0402-0.0,5%,1/16W,CHIP,G21A!R1U54!//jf4cfls225.pdx.intel.com/apd_proj/ppg_lib/epg_masterlib/logical/mstr_discrete/res/chips/chips.prt!RES!RES_0402-0.0,5%,1/16W,CHIP,G21497-005!RES!!!F1692!!!!
S!@baseboard_fab2_lib.baseboard_fab2(sch_1):page152_i94@mstr_discrete.res(chips)!RES_0402-0.0,5%,1/16W,CHIP,G21A!R2U46!//jf4cfls225.pdx.intel.com/apd_proj/ppg_lib/epg_masterlib/logical/mstr_discrete/res/chips/chips.prt!RES!RES_0402-0.0,5%,1/16W,CHIP,G21497-005!RES!!!F1691!!!!
S!@baseboard_fab2_lib.baseboard_fab2(sch_1):page93_i103@mstr_discrete.res(chips)!RES_0402-0.0,5%,1/16W,CHIP,G21A!R2T60!//jf4cfls225.pdx.intel.com/apd_proj/ppg_lib/epg_masterlib/logical/mstr_discrete/res/chips/chips.prt!RES!RES_0402-0.0,5%,1/16W,CHIP,G21497-005!RES!!!F1712!!!!
S!@baseboard_fab2_lib.baseboard_fab2(sch_1):page93_i102@mstr_discrete.res(chips)!RES_0402-0.0,5%,1/16W,CHIP,G21A!R2T68!//jf4cfls225.pdx.intel.com/apd_proj/ppg_lib/epg_masterlib/logical/mstr_discrete/res/chips/chips.prt!RES!RES_0402-0.0,5%,1/16W,CHIP,G21497-005!RES!!!F1711!!!!
S!@baseboard_fab2_lib.baseboard_fab2(sch_1):page152_i45@mstr_discrete.res(chips)!RES_0402-0.0,5%,1/16W,CHIP,G21A!R9G34!//jf4cfls225.pdx.intel.com/apd_proj/ppg_lib/epg_masterlib/logical/mstr_discrete/res/chips/chips.prt!RES!RES_0402-0.0,5%,1/16W,CHIP,G21497-005!RES!!!F1710!!!!
S!@baseboard_fab2_lib.baseboard_fab2(sch_1):page152_i49@mstr_discrete.res(chips)!RES_0402-0.0,5%,1/16W,CHIP,G21A!R1U58!//jf4cfls225.pdx.intel.com/apd_proj/ppg_lib/epg_masterlib/logical/mstr_discrete/res/chips/chips.prt!RES!RES_0402-0.0,5%,1/16W,CHIP,G21497-005!RES!!!F1709!!!!
S!@baseboard_fab2_lib.baseboard_fab2(sch_1):page152_i64@mstr_discrete.res(chips)!RES_0402-0.0,5%,1/16W,CHIP,G21A!R1U53!//jf4cfls225.pdx.intel.com/apd_proj/ppg_lib/epg_masterlib/logical/mstr_discrete/res/chips/chips.prt!RES!RES_0402-0.0,5%,1/16W,CHIP,G21497-005!RES!!!F1708!!!!
S!@baseboard_fab2_lib.baseboard_fab2(sch_1):page152_i65@mstr_discrete.res(chips)!RES_0402-0.0,5%,1/16W,CHIP,G21A!R1U60!//jf4cfls225.pdx.intel.com/apd_proj/ppg_lib/epg_masterlib/logical/mstr_discrete/res/chips/chips.prt!RES!RES_0402-0.0,5%,1/16W,CHIP,G21497-005!RES!!!F1707!!!!
S!@baseboard_fab2_lib.baseboard_fab2(sch_1):page104_i69@mstr_discrete.res(chips)!RES_0402-0.0,5%,1/16W,CHIP,G21A!R3F2!//jf4cfls225.pdx.intel.com/apd_proj/ppg_lib/epg_masterlib/logical/mstr_discrete/res/chips/chips.prt!RES!RES_0402-0.0,5%,1/16W,CHIP,G21497-005!RES!!!F1896!!CLOCK_CPU1_OSC!!
S!@baseboard_fab2_lib.baseboard_fab2(sch_1):page104_i70@mstr_discrete.res(chips)!RES_0402-0.0,5%,1/16W,CHIP,G21A!R3F4!//jf4cfls225.pdx.intel.com/apd_proj/ppg_lib/epg_masterlib/logical/mstr_discrete/res/chips/chips.prt!RES!RES_0402-0.0,5%,1/16W,CHIP,G21497-005!RES!!!F1895!!CLOCK_CPU1_OSC!!
S!@baseboard_fab2_lib.baseboard_fab2(sch_1):page104_i67@mstr_discrete.res(chips)!RES_0402-0.0,5%,1/16W,CHIP,G21A!R6F7!//jf4cfls225.pdx.intel.com/apd_proj/ppg_lib/epg_masterlib/logical/mstr_discrete/res/chips/chips.prt!RES!RES_0402-0.0,5%,1/16W,CHIP,G21497-005!RES!!!F1841!!CLOCK_CPU0_OSC!!
S!@baseboard_fab2_lib.baseboard_fab2(sch_1):page104_i68@mstr_discrete.res(chips)!RES_0402-0.0,5%,1/16W,CHIP,G21A!R6F9!//jf4cfls225.pdx.intel.com/apd_proj/ppg_lib/epg_masterlib/logical/mstr_discrete/res/chips/chips.prt!RES!RES_0402-0.0,5%,1/16W,CHIP,G21497-005!RES!!!F1840!!CLOCK_CPU0_OSC!!
S!@baseboard_fab2_lib.baseboard_fab2(sch_1):page104_i93@mstr_discrete.res(chips)!RES_0402-0.0,5%,1/16W,CHIP,G21A!R8D43!//jf4cfls225.pdx.intel.com/apd_proj/ppg_lib/epg_masterlib/logical/mstr_discrete/res/chips/chips.prt!RES!RES_0402-0.0,5%,1/16W,CHIP,G21497-005!RES!!!F1714!!CLOCK_CPU1_OSC!!
S!@baseboard_fab2_lib.baseboard_fab2(sch_1):page104_i96@mstr_discrete.res(chips)!RES_0402-0.0,5%,1/16W,CHIP,G21A!R7D36!//jf4cfls225.pdx.intel.com/apd_proj/ppg_lib/epg_masterlib/logical/mstr_discrete/res/chips/chips.prt!RES!RES_0402-0.0,5%,1/16W,CHIP,G21497-005!RES!!!F1713!!CLOCK_CPU1_OSC!!
S!@baseboard_fab2_lib.baseboard_fab2(sch_1):page230_i34@mstr_discrete.res(chips)!RES_0402-0.0,5%,1/16W,CHIP,G21A!R6L6!//jf4cfls225.pdx.intel.com/apd_proj/ppg_lib/epg_masterlib/logical/mstr_discrete/res/chips/chips.prt!RES!RES_0402-0.0,5%,1/16W,CHIP,G21497-005!RES!!!F1839!!VTT_KLM_PWR_VR!!
S!@baseboard_fab2_lib.baseboard_fab2(sch_1):page181_i268@mstr_discrete.res(chips)!RES_0402-0.0,5%,1/16W,CHIP,G21A!R1F8!//jf4cfls225.pdx.intel.com/apd_proj/ppg_lib/epg_masterlib/logical/mstr_discrete/res/chips/chips.prt!RES!RES_0402-0.0,5%,1/16W,CHIP,G21497-005!RES!!!F1945!!!!
S!@baseboard_fab2_lib.baseboard_fab2(sch_1):page159_i223@mstr_discrete.res(chips)!RES_0402-0.0,5%,1/16W,CHIP,G21A!R1U8!//jf4cfls225.pdx.intel.com/apd_proj/ppg_lib/epg_masterlib/logical/mstr_discrete/res/chips/chips.prt!RES!RES_0402-0.0,5%,1/16W,CHIP,G21497-005!RES!!!F1923!!SMBUS!!
S!@baseboard_fab2_lib.baseboard_fab2(sch_1):page159_i222@mstr_discrete.res(chips)!RES_0402-0.0,5%,1/16W,CHIP,G21A!R1U11!//jf4cfls225.pdx.intel.com/apd_proj/ppg_lib/epg_masterlib/logical/mstr_discrete/res/chips/chips.prt!RES!RES_0402-0.0,5%,1/16W,CHIP,G21497-005!RES!!!F1922!!SMBUS!!
S!@baseboard_fab2_lib.baseboard_fab2(sch_1):page223_i22@mstr_discrete.res(chips)!RES_0402-0.0,5%,1/16W,CHIP,G21A!R1G21!//jf4cfls225.pdx.intel.com/apd_proj/ppg_lib/epg_masterlib/logical/mstr_discrete/res/chips/chips.prt!RES!RES_0402-0.0,5%,1/16W,CHIP,G21497-005!RES!!!F1941!!VDDQ_GHJ_PWR_VR!!
S!@baseboard_fab2_lib.baseboard_fab2(sch_1):page223_i21@mstr_discrete.res(chips)!RES_0402-0.0,5%,1/16W,CHIP,G21A!R1G19!//jf4cfls225.pdx.intel.com/apd_proj/ppg_lib/epg_masterlib/logical/mstr_discrete/res/chips/chips.prt!RES!RES_0402-0.0,5%,1/16W,CHIP,G21497-005!RES!!!F1942!!VDDQ_GHJ_PWR_VR!!
S!@baseboard_fab2_lib.baseboard_fab2(sch_1):page141_i112@mstr_discrete.res(chips)!RES_0402-0.0,5%,1/16W,CHIP,G21A!R1U51!//jf4cfls225.pdx.intel.com/apd_proj/ppg_lib/epg_masterlib/logical/mstr_discrete/res/chips/chips.prt!RES!RES_0402-0.0,5%,1/16W,CHIP,G21497-005!RES!!!F1921!!NIC_SPRV!!
S!@baseboard_fab2_lib.baseboard_fab2(sch_1):page141_i114@mstr_discrete.res(chips)!RES_0402-0.0,5%,1/16W,CHIP,G21A!R1U3!//jf4cfls225.pdx.intel.com/apd_proj/ppg_lib/epg_masterlib/logical/mstr_discrete/res/chips/chips.prt!RES!RES_0402-0.0,5%,1/16W,CHIP,G21497-005!RES!!!F1924!!NIC_SPRV!!
S!@baseboard_fab2_lib.baseboard_fab2(sch_1):page154_i92@mstr_discrete.res(chips)!RES_0402-0.0,5%,1/16W,CHIP,G21A!R2T2!//jf4cfls225.pdx.intel.com/apd_proj/ppg_lib/epg_masterlib/logical/mstr_discrete/res/chips/chips.prt!RES!RES_0402-0.0,5%,1/16W,CHIP,G21497-005!RES!!!F1911!!SB_BMC_SPI_MUX!!
S!@baseboard_fab2_lib.baseboard_fab2(sch_1):page189_i17@mstr_discrete.res(chips)!RES_0402-0.0,5%,1/16W,CHIP,G21A!R8G8!//jf4cfls225.pdx.intel.com/apd_proj/ppg_lib/epg_masterlib/logical/mstr_discrete/res/chips/chips.prt!RES!RES_0402-0.0,5%,1/16W,CHIP,G21497-005!RES!!!F1770!!BMC_DEBUG_HEADER!!
S!@baseboard_fab2_lib.baseboard_fab2(sch_1):page189_i20@mstr_discrete.res(chips)!RES_0402-0.0,5%,1/16W,CHIP,G21A!R8G14!//jf4cfls225.pdx.intel.com/apd_proj/ppg_lib/epg_masterlib/logical/mstr_discrete/res/chips/chips.prt!RES!RES_0402-0.0,5%,1/16W,CHIP,G21497-005!RES!!!F1767!!BMC_DEBUG_HEADER!!
S!@baseboard_fab2_lib.baseboard_fab2(sch_1):page189_i25@mstr_discrete.res(chips)!RES_0402-0.0,5%,1/16W,CHIP,G21A!R8G17!//jf4cfls225.pdx.intel.com/apd_proj/ppg_lib/epg_masterlib/logical/mstr_discrete/res/chips/chips.prt!RES!RES_0402-0.0,5%,1/16W,CHIP,G21497-005!RES!!!F1766!!BMC_DEBUG_HEADER!!
S!@baseboard_fab2_lib.baseboard_fab2(sch_1):page189_i37@mstr_discrete.res(chips)!RES_0402-0.0,5%,1/16W,CHIP,G21A!R7G17!//jf4cfls225.pdx.intel.com/apd_proj/ppg_lib/epg_masterlib/logical/mstr_discrete/res/chips/chips.prt!RES!RES_0402-0.0,5%,1/16W,CHIP,G21497-005!RES!!!F1797!!BMC_DEBUG_HEADER!!
S!@baseboard_fab2_lib.baseboard_fab2(sch_1):page189_i7@mstr_discrete.res(chips)!RES_0402-0.0,5%,1/16W,CHIP,G21A!R8G10!//jf4cfls225.pdx.intel.com/apd_proj/ppg_lib/epg_masterlib/logical/mstr_discrete/res/chips/chips.prt!RES!RES_0402-0.0,5%,1/16W,CHIP,G21497-005!RES!!!F1769!!BMC_DEBUG_HEADER!!
S!@baseboard_fab2_lib.baseboard_fab2(sch_1):page118_i131@mstr_discrete.res(chips)!RES_0402-0.0,5%,1/16W,CHIP,G21A!R7D23!//jf4cfls225.pdx.intel.com/apd_proj/ppg_lib/epg_masterlib/logical/mstr_discrete/res/chips/chips.prt!RES!RES_0402-0.0,5%,1/16W,CHIP,G21497-005!RES!!!F1810!!SB!!
S!@baseboard_fab2_lib.baseboard_fab2(sch_1):page121_i31@mstr_discrete.res(chips)!RES_0402-0.0,5%,1/16W,CHIP,G21A!R7C15!//jf4cfls225.pdx.intel.com/apd_proj/ppg_lib/epg_masterlib/logical/mstr_discrete/res/chips/chips.prt!RES!RES_0402-0.0,5%,1/16W,CHIP,G21497-005!RES!!!F1812!!SB!!
S!@baseboard_fab2_lib.baseboard_fab2(sch_1):page154_i119@mstr_discrete.res(chips)!RES_0402-0.0,5%,1/16W,CHIP,G21A!R8F6!//jf4cfls225.pdx.intel.com/apd_proj/ppg_lib/epg_masterlib/logical/mstr_discrete/res/chips/chips.prt!RES!RES_0402-0.0,5%,1/16W,CHIP,G21497-005!RES!!!F1775!!MIO_BIOS_MEM!!
S!@baseboard_fab2_lib.baseboard_fab2(sch_1):page154_i93@mstr_discrete.res(chips)!RES_0402-0.0,5%,1/16W,CHIP,G21A!R2R12!//jf4cfls225.pdx.intel.com/apd_proj/ppg_lib/epg_masterlib/logical/mstr_discrete/res/chips/chips.prt!RES!RES_0402-0.0,5%,1/16W,CHIP,G21497-005!RES!!!F1912!!SB_BMC_SPI_MUX!!
S!@baseboard_fab2_lib.baseboard_fab2(sch_1):page186_i339@mstr_discrete.res(chips)!RES_0402-0.0,5%,1/16W,CHIP,G21A!R1M15!//jf4cfls225.pdx.intel.com/apd_proj/ppg_lib/epg_masterlib/logical/mstr_discrete/res/chips/chips.prt!RES!RES_0402-0.0,5%,1/16W,CHIP,G21497-005!RES!!!F1930!!IO_SLOT!!
S!@baseboard_fab2_lib.baseboard_fab2(sch_1):page186_i338@mstr_discrete.res(chips)!RES_0402-0.0,5%,1/16W,CHIP,G21A!R1M17!//jf4cfls225.pdx.intel.com/apd_proj/ppg_lib/epg_masterlib/logical/mstr_discrete/res/chips/chips.prt!RES!RES_0402-0.0,5%,1/16W,CHIP,G21497-005!RES!!!F1928!!IO_SLOT!!
S!@baseboard_fab2_lib.baseboard_fab2(sch_1):page186_i337@mstr_discrete.res(chips)!RES_0402-0.0,5%,1/16W,CHIP,G21A!R1M16!//jf4cfls225.pdx.intel.com/apd_proj/ppg_lib/epg_masterlib/logical/mstr_discrete/res/chips/chips.prt!RES!RES_0402-0.0,5%,1/16W,CHIP,G21497-005!RES!!!F1929!!IO_SLOT!!
S!@baseboard_fab2_lib.baseboard_fab2(sch_1):page186_i340@mstr_discrete.res(chips)!RES_0402-0.0,5%,1/16W,CHIP,G21A!R1M18!//jf4cfls225.pdx.intel.com/apd_proj/ppg_lib/epg_masterlib/logical/mstr_discrete/res/chips/chips.prt!RES!RES_0402-0.0,5%,1/16W,CHIP,G21497-005!RES!!!F1927!!IO_SLOT!!
S!@baseboard_fab2_lib.baseboard_fab2(sch_1):page206_i122@mstr_discrete.res(chips)!RES_0402-0.0,5%,1/16W,CHIP,G21A!R9N15!//jf4cfls225.pdx.intel.com/apd_proj/ppg_lib/epg_masterlib/logical/mstr_discrete/res/chips/chips.prt!RES!RES_0402-0.0,5%,1/16W,CHIP,G21497-005!RES!!!F1728!!PVCCIN_CPU0_VR!!
S!@baseboard_fab2_lib.baseboard_fab2(sch_1):page206_i128@mstr_discrete.res(chips)!RES_0402-0.0,5%,1/16W,CHIP,G21A!R9N5!//jf4cfls225.pdx.intel.com/apd_proj/ppg_lib/epg_masterlib/logical/mstr_discrete/res/chips/chips.prt!RES!RES_0402-0.0,5%,1/16W,CHIP,G21497-005!RES!!!F1732!!PVCCIN_CPU0_VR!!
S!@baseboard_fab2_lib.baseboard_fab2(sch_1):page206_i123@mstr_discrete.res(chips)!RES_0402-0.0,5%,1/16W,CHIP,G21A!R9N17!//jf4cfls225.pdx.intel.com/apd_proj/ppg_lib/epg_masterlib/logical/mstr_discrete/res/chips/chips.prt!RES!RES_0402-0.0,5%,1/16W,CHIP,G21497-005!RES!!!F1726!!PVCCIN_CPU0_VR!!
S!@baseboard_fab2_lib.baseboard_fab2(sch_1):page206_i124@mstr_discrete.res(chips)!RES_0402-0.0,5%,1/16W,CHIP,G21A!R9N12!//jf4cfls225.pdx.intel.com/apd_proj/ppg_lib/epg_masterlib/logical/mstr_discrete/res/chips/chips.prt!RES!RES_0402-0.0,5%,1/16W,CHIP,G21497-005!RES!!!F1729!!PVCCIN_CPU0_VR!!
S!@baseboard_fab2_lib.baseboard_fab2(sch_1):page206_i125@mstr_discrete.res(chips)!RES_0402-0.0,5%,1/16W,CHIP,G21A!R9N10!//jf4cfls225.pdx.intel.com/apd_proj/ppg_lib/epg_masterlib/logical/mstr_discrete/res/chips/chips.prt!RES!RES_0402-0.0,5%,1/16W,CHIP,G21497-005!RES!!!F1730!!PVCCIN_CPU0_VR!!
S!@baseboard_fab2_lib.baseboard_fab2(sch_1):page206_i126@mstr_discrete.res(chips)!RES_0402-0.0,5%,1/16W,CHIP,G21A!R9N9!//jf4cfls225.pdx.intel.com/apd_proj/ppg_lib/epg_masterlib/logical/mstr_discrete/res/chips/chips.prt!RES!RES_0402-0.0,5%,1/16W,CHIP,G21497-005!RES!!!F1731!!PVCCIN_CPU0_VR!!
S!@baseboard_fab2_lib.baseboard_fab2(sch_1):page211_i91@mstr_discrete.res(chips)!RES_0402-0.0,5%,1/16W,CHIP,G21A!R3P57!//jf4cfls225.pdx.intel.com/apd_proj/ppg_lib/epg_masterlib/logical/mstr_discrete/res/chips/chips.prt!RES!RES_0402-0.0,5%,1/16W,CHIP,G21497-005!RES!!!F1888!!PVCCIN_CPU0_VR!!
S!@baseboard_fab2_lib.baseboard_fab2(sch_1):page213_i94@mstr_discrete.res(chips)!RES_0402-0.0,5%,1/16W,CHIP,G21A!R4D45!//jf4cfls225.pdx.intel.com/apd_proj/ppg_lib/epg_masterlib/logical/mstr_discrete/res/chips/chips.prt!RES!RES_0402-0.0,5%,1/16W,CHIP,G21497-005!RES!!!F1865!!PVCCIN_CPU0_VR!!
S!@baseboard_fab2_lib.baseboard_fab2(sch_1):page215_i341@mstr_discrete.res(chips)!RES_0402-0.0,5%,1/16W,CHIP,G21A!R3U10!//jf4cfls225.pdx.intel.com/apd_proj/ppg_lib/epg_masterlib/logical/mstr_discrete/res/chips/chips.prt!RES!RES_0402-0.0,5%,1/16W,CHIP,G21497-005!RES!!!F1876!!PVCCIN_CPU0_VR!!
S!@baseboard_fab2_lib.baseboard_fab2(sch_1):page215_i332@mstr_discrete.res(chips)!RES_0402-0.0,5%,1/16W,CHIP,G21A!R3U3!//jf4cfls225.pdx.intel.com/apd_proj/ppg_lib/epg_masterlib/logical/mstr_discrete/res/chips/chips.prt!RES!RES_0402-0.0,5%,1/16W,CHIP,G21497-005!RES!!!F1874!!PVCCIN_CPU0_VR!!
S!@baseboard_fab2_lib.baseboard_fab2(sch_1):page218_i57@mstr_discrete.res(chips)!RES_0402-0.0,5%,1/16W,CHIP,G21A!R3L9!//jf4cfls225.pdx.intel.com/apd_proj/ppg_lib/epg_masterlib/logical/mstr_discrete/res/chips/chips.prt!RES!RES_0402-0.0,5%,1/16W,CHIP,G21497-005!RES!!!F1894!!VDDQ_DEF_PWR_VR!!
S!@baseboard_fab2_lib.baseboard_fab2(sch_1):page218_i50@mstr_discrete.res(chips)!RES_0402-0.0,5%,1/16W,CHIP,G21A!R3L10!//jf4cfls225.pdx.intel.com/apd_proj/ppg_lib/epg_masterlib/logical/mstr_discrete/res/chips/chips.prt!RES!RES_0402-0.0,5%,1/16W,CHIP,G21497-005!RES!!!F1893!!VDDQ_DEF_PWR_VR!!
S!@baseboard_fab2_lib.baseboard_fab2(sch_1):page223_i87@mstr_discrete.res(chips)!RES_0402-0.0,5%,1/16W,CHIP,G21A!R1G28!//jf4cfls225.pdx.intel.com/apd_proj/ppg_lib/epg_masterlib/logical/mstr_discrete/res/chips/chips.prt!RES!RES_0402-0.0,5%,1/16W,CHIP,G21497-005!RES!!!F1718!!PVCCIN_CPU0_VR!!
S!@baseboard_fab2_lib.baseboard_fab2(sch_1):page223_i88@mstr_discrete.res(chips)!RES_0402-0.0,5%,1/16W,CHIP,G21A!R1G27!//jf4cfls225.pdx.intel.com/apd_proj/ppg_lib/epg_masterlib/logical/mstr_discrete/res/chips/chips.prt!RES!RES_0402-0.0,5%,1/16W,CHIP,G21497-005!RES!!!F1717!!PVCCIN_CPU0_VR!!
S!@baseboard_fab2_lib.baseboard_fab2(sch_1):page226_i87@mstr_discrete.res(chips)!RES_0402-0.0,5%,1/16W,CHIP,G21A!R9M11!//jf4cfls225.pdx.intel.com/apd_proj/ppg_lib/epg_masterlib/logical/mstr_discrete/res/chips/chips.prt!RES!RES_0402-0.0,5%,1/16W,CHIP,G21497-005!RES!!!F1733!!PVCCIN_CPU0_VR!!
S!@baseboard_fab2_lib.baseboard_fab2(sch_1):page226_i88@mstr_discrete.res(chips)!RES_0402-0.0,5%,1/16W,CHIP,G21A!R9M10!//jf4cfls225.pdx.intel.com/apd_proj/ppg_lib/epg_masterlib/logical/mstr_discrete/res/chips/chips.prt!RES!RES_0402-0.0,5%,1/16W,CHIP,G21497-005!RES!!!F1734!!PVCCIN_CPU0_VR!!
S!@baseboard_fab2_lib.baseboard_fab2(sch_1):page235_i224@mstr_discrete.res(chips)!RES_0402-0.0,5%,1/16W,CHIP,G21A!R2L1!//jf4cfls225.pdx.intel.com/apd_proj/ppg_lib/epg_masterlib/logical/mstr_discrete/res/chips/chips.prt!RES!RES_0402-0.0,5%,1/16W,CHIP,G21497-005!RES!!!F1920!!PVCCIN_CPU0_VR!!
S!@baseboard_fab2_lib.baseboard_fab2(sch_1):page235_i225@mstr_discrete.res(chips)!RES_0402-0.0,5%,1/16W,CHIP,G21A!R2L7!//jf4cfls225.pdx.intel.com/apd_proj/ppg_lib/epg_masterlib/logical/mstr_discrete/res/chips/chips.prt!RES!RES_0402-0.0,5%,1/16W,CHIP,G21497-005!RES!!!F1919!!PVCCIN_CPU0_VR!!
S!@baseboard_fab2_lib.baseboard_fab2(sch_1):page201_i154@mstr_discrete.res(chips)!RES_0402-0.0,5%,1/16W,CHIP,G21A!R6P29!//jf4cfls225.pdx.intel.com/apd_proj/ppg_lib/epg_masterlib/logical/mstr_discrete/res/chips/chips.prt!RES!RES_0402-0.0,5%,1/16W,CHIP,G21497-005!RES!!!F1830!!PVCCIN_CPU0_VR!!
S!@baseboard_fab2_lib.baseboard_fab2(sch_1):page201_i150@mstr_discrete.res(chips)!RES_0402-0.0,5%,1/16W,CHIP,G21A!R6P43!//jf4cfls225.pdx.intel.com/apd_proj/ppg_lib/epg_masterlib/logical/mstr_discrete/res/chips/chips.prt!RES!RES_0402-0.0,5%,1/16W,CHIP,G21497-005!RES!!!F1824!!PVCCIN_CPU0_VR!!
S!@baseboard_fab2_lib.baseboard_fab2(sch_1):page201_i139@mstr_discrete.res(chips)!RES_0402-0.0,5%,1/16W,CHIP,G21A!R6P42!//jf4cfls225.pdx.intel.com/apd_proj/ppg_lib/epg_masterlib/logical/mstr_discrete/res/chips/chips.prt!RES!RES_0402-0.0,5%,1/16W,CHIP,G21497-005!RES!!!F1825!!PVCCIN_CPU0_VR!!
S!@baseboard_fab2_lib.baseboard_fab2(sch_1):page201_i147@mstr_discrete.res(chips)!RES_0402-0.0,5%,1/16W,CHIP,G21A!R6P38!//jf4cfls225.pdx.intel.com/apd_proj/ppg_lib/epg_masterlib/logical/mstr_discrete/res/chips/chips.prt!RES!RES_0402-0.0,5%,1/16W,CHIP,G21497-005!RES!!!F1827!!PVCCIN_CPU0_VR!!
S!@baseboard_fab2_lib.baseboard_fab2(sch_1):page201_i148@mstr_discrete.res(chips)!RES_0402-0.0,5%,1/16W,CHIP,G21A!R6P34!//jf4cfls225.pdx.intel.com/apd_proj/ppg_lib/epg_masterlib/logical/mstr_discrete/res/chips/chips.prt!RES!RES_0402-0.0,5%,1/16W,CHIP,G21497-005!RES!!!F1828!!PVCCIN_CPU0_VR!!
S!@baseboard_fab2_lib.baseboard_fab2(sch_1):page201_i149@mstr_discrete.res(chips)!RES_0402-0.0,5%,1/16W,CHIP,G21A!R6P30!//jf4cfls225.pdx.intel.com/apd_proj/ppg_lib/epg_masterlib/logical/mstr_discrete/res/chips/chips.prt!RES!RES_0402-0.0,5%,1/16W,CHIP,G21497-005!RES!!!F1829!!PVCCIN_CPU0_VR!!
S!@baseboard_fab2_lib.baseboard_fab2(sch_1):page121_i67@mstr_discrete.res(chips)!RES_0402-0.0,5%,1/16W,CHIP,G21A!R3P2!//jf4cfls225.pdx.intel.com/apd_proj/ppg_lib/epg_masterlib/logical/mstr_discrete/res/chips/chips.prt!RES!RES_0402-0.0,5%,1/16W,CHIP,G21497-005!RES!!!F1886!!!!
S!@baseboard_fab2_lib.baseboard_fab2(sch_1):page121_i66@mstr_discrete.res(chips)!RES_0402-0.0,5%,1/16W,CHIP,G21A!R2P1!//jf4cfls225.pdx.intel.com/apd_proj/ppg_lib/epg_masterlib/logical/mstr_discrete/res/chips/chips.prt!RES!RES_0402-0.0,5%,1/16W,CHIP,G21497-005!RES!!!F1914!!!!
S!@baseboard_fab2_lib.baseboard_fab2(sch_1):page121_i65@mstr_discrete.res(chips)!RES_0402-0.0,5%,1/16W,CHIP,G21A!R3P3!//jf4cfls225.pdx.intel.com/apd_proj/ppg_lib/epg_masterlib/logical/mstr_discrete/res/chips/chips.prt!RES!RES_0402-0.0,5%,1/16W,CHIP,G21497-005!RES!!!F1885!!!!
S!@baseboard_fab2_lib.baseboard_fab2(sch_1):page183_i52@mstr_discrete.res(chips)!RES_0402-0.0,5%,1/16W,CHIP,G21A!R9F54!//jf4cfls225.pdx.intel.com/apd_proj/ppg_lib/epg_masterlib/logical/mstr_discrete/res/chips/chips.prt!RES!RES_0402-0.0,5%,1/16W,CHIP,G21497-005!RES!!!F1750!!LBG!!
S!@baseboard_fab2_lib.baseboard_fab2(sch_1):page183_i53@mstr_discrete.res(chips)!RES_0402-0.0,5%,1/16W,CHIP,G21A!R9F53!//jf4cfls225.pdx.intel.com/apd_proj/ppg_lib/epg_masterlib/logical/mstr_discrete/res/chips/chips.prt!RES!RES_0402-0.0,5%,1/16W,CHIP,G21497-005!RES!!!F1751!!LBG!!
S!@baseboard_fab2_lib.baseboard_fab2(sch_1):page183_i49@mstr_discrete.res(chips)!RES_0402-0.0,5%,1/16W,CHIP,G21A!R9F56!//jf4cfls225.pdx.intel.com/apd_proj/ppg_lib/epg_masterlib/logical/mstr_discrete/res/chips/chips.prt!RES!RES_0402-0.0,5%,1/16W,CHIP,G21497-005!RES!!!F1749!!LBG!!
S!@baseboard_fab2_lib.baseboard_fab2(sch_1):page183_i48@mstr_discrete.res(chips)!RES_0402-0.0,5%,1/16W,CHIP,G21A!R9F57!//jf4cfls225.pdx.intel.com/apd_proj/ppg_lib/epg_masterlib/logical/mstr_discrete/res/chips/chips.prt!RES!RES_0402-0.0,5%,1/16W,CHIP,G21497-005!RES!!!F1748!!LBG!!
S!@baseboard_fab2_lib.baseboard_fab2(sch_1):page177_i6@mstr_discrete.res(chips)!RES_0402-0.0,5%,1/16W,CHIP,G21A!R1M10!//jf4cfls225.pdx.intel.com/apd_proj/ppg_lib/epg_masterlib/logical/mstr_discrete/res/chips/chips.prt!RES!RES_0402-0.0,5%,1/16W,CHIP,G21497-005!RES!!!F1932!!MIO_CHASSIS!!
S!@baseboard_fab2_lib.baseboard_fab2(sch_1):page177_i3@mstr_discrete.res(chips)!RES_0402-0.0,5%,1/16W,CHIP,G21A!R1M13!//jf4cfls225.pdx.intel.com/apd_proj/ppg_lib/epg_masterlib/logical/mstr_discrete/res/chips/chips.prt!RES!RES_0402-0.0,5%,1/16W,CHIP,G21497-005!RES!!!F1931!!MIO_CHASSIS!!
S!@baseboard_fab2_lib.baseboard_fab2(sch_1):page181_i255@mstr_discrete.res(chips)!RES_0402-0.0,5%,1/16W,CHIP,G21A!R9T2!//jf4cfls225.pdx.intel.com/apd_proj/ppg_lib/epg_masterlib/logical/mstr_discrete/res/chips/chips.prt!RES!RES_0402-0.0,5%,1/16W,CHIP,G21497-005!RES!!!F1720!!!!
S!@baseboard_fab2_lib.baseboard_fab2(sch_1):page181_i254@mstr_discrete.res(chips)!RES_0402-0.0,5%,1/16W,CHIP,G21A!R9R9!//jf4cfls225.pdx.intel.com/apd_proj/ppg_lib/epg_masterlib/logical/mstr_discrete/res/chips/chips.prt!RES!RES_0402-0.0,5%,1/16W,CHIP,G21497-005!RES!!!F1723!!!!
S!@baseboard_fab2_lib.baseboard_fab2(sch_1):page181_i256@mstr_discrete.res(chips)!RES_0402-0.0,5%,1/16W,CHIP,G21A!R9R10!//jf4cfls225.pdx.intel.com/apd_proj/ppg_lib/epg_masterlib/logical/mstr_discrete/res/chips/chips.prt!RES!RES_0402-0.0,5%,1/16W,CHIP,G21497-005!RES!!!F1722!!!!
S!@baseboard_fab2_lib.baseboard_fab2(sch_1):page181_i261@mstr_discrete.res(chips)!RES_0402-0.0,5%,1/16W,CHIP,G21A!R9T1!//jf4cfls225.pdx.intel.com/apd_proj/ppg_lib/epg_masterlib/logical/mstr_discrete/res/chips/chips.prt!RES!RES_0402-0.0,5%,1/16W,CHIP,G21497-005!RES!!!F1721!!!!
S!@baseboard_fab2_lib.baseboard_fab2(sch_1):page191_i184@mstr_discrete.res(chips)!RES_0402-0.0,5%,1/16W,CHIP,G21A!R2R4!//jf4cfls225.pdx.intel.com/apd_proj/ppg_lib/epg_masterlib/logical/mstr_discrete/res/chips/chips.prt!RES!RES_0402-0.0,5%,1/16W,CHIP,G21497-005!RES!!!F1913!!CPLD!!
S!@baseboard_fab2_lib.baseboard_fab2(sch_1):page189_i63@mstr_discrete.res(chips)!RES_0402-0.0,5%,1/16W,CHIP,G21A!R7G21!//jf4cfls225.pdx.intel.com/apd_proj/ppg_lib/epg_masterlib/logical/mstr_discrete/res/chips/chips.prt!RES!RES_0402-0.0,5%,1/16W,CHIP,G21497-005!RES!!!F1796!!BMC_DEBUG_HEADER!!
S!@baseboard_fab2_lib.baseboard_fab2(sch_1):page189_i65@mstr_discrete.res(chips)!RES_0402-0.0,5%,1/16W,CHIP,G21A!R8G21!//jf4cfls225.pdx.intel.com/apd_proj/ppg_lib/epg_masterlib/logical/mstr_discrete/res/chips/chips.prt!RES!RES_0402-0.0,5%,1/16W,CHIP,G21497-005!RES!!!F1763!!BMC_DEBUG_HEADER!!
S!@baseboard_fab2_lib.baseboard_fab2(sch_1):page189_i64@mstr_discrete.res(chips)!RES_0402-0.0,5%,1/16W,CHIP,G21A!R8G19!//jf4cfls225.pdx.intel.com/apd_proj/ppg_lib/epg_masterlib/logical/mstr_discrete/res/chips/chips.prt!RES!RES_0402-0.0,5%,1/16W,CHIP,G21497-005!RES!!!F1764!!BMC_DEBUG_HEADER!!
S!@baseboard_fab2_lib.baseboard_fab2(sch_1):page189_i66@mstr_discrete.res(chips)!RES_0402-0.0,5%,1/16W,CHIP,G21A!R8G22!//jf4cfls225.pdx.intel.com/apd_proj/ppg_lib/epg_masterlib/logical/mstr_discrete/res/chips/chips.prt!RES!RES_0402-0.0,5%,1/16W,CHIP,G21497-005!RES!!!F1762!!BMC_DEBUG_HEADER!!
S!@baseboard_fab2_lib.baseboard_fab2(sch_1):page157_i379@mstr_discrete.res(chips)!RES_0402-0.0,5%,1/16W,CHIP,G21A!R9E14!//jf4cfls225.pdx.intel.com/apd_proj/ppg_lib/epg_masterlib/logical/mstr_discrete/res/chips/chips.prt!RES!RES_0402-0.0,5%,1/16W,CHIP,G21497-005!RES!!!F1757!!!!
S!@baseboard_fab2_lib.baseboard_fab2(sch_1):page201_i131@mstr_discrete.res(chips)!RES_0402-0.0,5%,1/16W,CHIP,G21A!R6P18!//jf4cfls225.pdx.intel.com/apd_proj/ppg_lib/epg_masterlib/logical/mstr_discrete/res/chips/chips.prt!RES!RES_0402-0.0,5%,1/16W,CHIP,G21497-005!RES!!!F1831!!PVCCIN_CPU0_VR!!
S!@baseboard_fab2_lib.baseboard_fab2(sch_1):page206_i119@mstr_discrete.res(chips)!RES_0402-0.0,5%,1/16W,CHIP,G21A!R9N16!//jf4cfls225.pdx.intel.com/apd_proj/ppg_lib/epg_masterlib/logical/mstr_discrete/res/chips/chips.prt!RES!RES_0402-0.0,5%,1/16W,CHIP,G21497-005!RES!!!F1727!!PVCCIN_CPU0_VR!!
S!@baseboard_fab2_lib.baseboard_fab2(sch_1):page211_i87@mstr_discrete.res(chips)!RES_0402-0.0,5%,1/16W,CHIP,G21A!R3P26!//jf4cfls225.pdx.intel.com/apd_proj/ppg_lib/epg_masterlib/logical/mstr_discrete/res/chips/chips.prt!RES!RES_0402-0.0,5%,1/16W,CHIP,G21497-005!RES!!!F1880!!PVCCIN_CPU0_VR!!
S!@baseboard_fab2_lib.baseboard_fab2(sch_1):page213_i90@mstr_discrete.res(chips)!RES_0402-0.0,5%,1/16W,CHIP,G21A!R6P41!//jf4cfls225.pdx.intel.com/apd_proj/ppg_lib/epg_masterlib/logical/mstr_discrete/res/chips/chips.prt!RES!RES_0402-0.0,5%,1/16W,CHIP,G21497-005!RES!!!F1826!!PVCCIN_CPU0_VR!!
S!@baseboard_fab2_lib.baseboard_fab2(sch_1):page215_i343@mstr_discrete.res(chips)!RES_0402-0.0,5%,1/16W,CHIP,G21A!R7F21!//jf4cfls225.pdx.intel.com/apd_proj/ppg_lib/epg_masterlib/logical/mstr_discrete/res/chips/chips.prt!RES!RES_0402-0.0,5%,1/16W,CHIP,G21497-005!RES!!!F1801!!PVCCIN_CPU0_VR!!
S!@baseboard_fab2_lib.baseboard_fab2(sch_1):page218_i59@mstr_discrete.res(chips)!RES_0402-0.0,5%,1/16W,CHIP,G21A!R3M6!//jf4cfls225.pdx.intel.com/apd_proj/ppg_lib/epg_masterlib/logical/mstr_discrete/res/chips/chips.prt!RES!RES_0402-0.0,5%,1/16W,CHIP,G21497-005!RES!!!F1890!!VDDQ_DEF_PWR_VR!!
S!@baseboard_fab2_lib.baseboard_fab2(sch_1):page223_i84@mstr_discrete.res(chips)!RES_0402-0.0,5%,1/16W,CHIP,G21A!R9U7!//jf4cfls225.pdx.intel.com/apd_proj/ppg_lib/epg_masterlib/logical/mstr_discrete/res/chips/chips.prt!RES!RES_0402-0.0,5%,1/16W,CHIP,G21497-005!RES!!!F1716!!PVCCIN_CPU0_VR!!
S!@baseboard_fab2_lib.baseboard_fab2(sch_1):page226_i84@mstr_discrete.res(chips)!RES_0402-0.0,5%,1/16W,CHIP,G21A!R9M9!//jf4cfls225.pdx.intel.com/apd_proj/ppg_lib/epg_masterlib/logical/mstr_discrete/res/chips/chips.prt!RES!RES_0402-0.0,5%,1/16W,CHIP,G21497-005!RES!!!F1735!!PVCCIN_CPU0_VR!!
S!@baseboard_fab2_lib.baseboard_fab2(sch_1):page231_i220@mstr_discrete.res(chips)!RES_0402-0.0,5%,1/16W,CHIP,G21A!R7F9!//jf4cfls225.pdx.intel.com/apd_proj/ppg_lib/epg_masterlib/logical/mstr_discrete/res/chips/chips.prt!RES!RES_0402-0.0,5%,1/16W,CHIP,G21497-005!RES!!!F1803!!PVCCIN_CPU0_VR!!
S!@baseboard_fab2_lib.baseboard_fab2(sch_1):page232_i307@mstr_discrete.res(chips)!RES_0402-0.0,5%,1/16W,CHIP,G21A!R7B9!//jf4cfls225.pdx.intel.com/apd_proj/ppg_lib/epg_masterlib/logical/mstr_discrete/res/chips/chips.prt!RES!RES_0402-0.0,5%,1/16W,CHIP,G21497-005!RES!!!F1814!!PVCCIN_CPU0_VR!!
S!@baseboard_fab2_lib.baseboard_fab2(sch_1):page233_i275@mstr_discrete.res(chips)!RES_0402-0.0,5%,1/16W,CHIP,G21A!R4G4!//jf4cfls225.pdx.intel.com/apd_proj/ppg_lib/epg_masterlib/logical/mstr_discrete/res/chips/chips.prt!RES!RES_0402-0.0,5%,1/16W,CHIP,G21497-005!RES!!!F1854!!PVCCIN_CPU0_VR!!
S!@baseboard_fab2_lib.baseboard_fab2(sch_1):page234_i220@mstr_discrete.res(chips)!RES_0402-0.0,5%,1/16W,CHIP,G21A!R4B1!//jf4cfls225.pdx.intel.com/apd_proj/ppg_lib/epg_masterlib/logical/mstr_discrete/res/chips/chips.prt!RES!RES_0402-0.0,5%,1/16W,CHIP,G21497-005!RES!!!F1871!!PVCCIN_CPU0_VR!!
S!@baseboard_fab2_lib.baseboard_fab2(sch_1):page235_i221@mstr_discrete.res(chips)!RES_0402-0.0,5%,1/16W,CHIP,G21A!R2L17!//jf4cfls225.pdx.intel.com/apd_proj/ppg_lib/epg_masterlib/logical/mstr_discrete/res/chips/chips.prt!RES!RES_0402-0.0,5%,1/16W,CHIP,G21497-005!RES!!!F1917!!PVCCIN_CPU0_VR!!
S!@baseboard_fab2_lib.baseboard_fab2(sch_1):page240_i176@mstr_discrete.res(chips)!RES_0402-0.0,5%,1/16W,CHIP,G21A!R8F2!//jf4cfls225.pdx.intel.com/apd_proj/ppg_lib/epg_masterlib/logical/mstr_discrete/res/chips/chips.prt!RES!RES_0402-0.0,5%,1/16W,CHIP,G21497-005!RES!!!F1776!!PVCCIN_CPU0_VR!!
S!@baseboard_fab2_lib.baseboard_fab2(sch_1):page241_i91@mstr_discrete.res(chips)!RES_0402-0.0,5%,1/16W,CHIP,G21A!R8E33!//jf4cfls225.pdx.intel.com/apd_proj/ppg_lib/epg_masterlib/logical/mstr_discrete/res/chips/chips.prt!RES!RES_0402-0.0,5%,1/16W,CHIP,G21497-005!RES!!!F1780!!PVCCIN_CPU0_VR!!
S!@baseboard_fab2_lib.baseboard_fab2(sch_1):page118_i120@mstr_discrete.res(chips)!RES_0402-0.0,5%,1/16W,CHIP,G21A!R8C24!//jf4cfls225.pdx.intel.com/apd_proj/ppg_lib/epg_masterlib/logical/mstr_discrete/res/chips/chips.prt!RES!RES_0402-0.0,5%,1/16W,CHIP,G21497-005!RES!!!F1789!!SB!!
S!@baseboard_fab2_lib.baseboard_fab2(sch_1):page221_i32@mstr_discrete.res(chips)!RES_0402-0.0,5%,1/16W,CHIP,G21A!R6U5!//jf4cfls225.pdx.intel.com/apd_proj/ppg_lib/epg_masterlib/logical/mstr_discrete/res/chips/chips.prt!RES!RES_0402-0.0,5%,1/16W,CHIP,G21497-005!RES!!!F1820!!VTT_ABC_PWR_VR!!
S!@baseboard_fab2_lib.baseboard_fab2(sch_1):page222_i34@mstr_discrete.res(chips)!RES_0402-0.0,5%,1/16W,CHIP,G21A!R6L10!//jf4cfls225.pdx.intel.com/apd_proj/ppg_lib/epg_masterlib/logical/mstr_discrete/res/chips/chips.prt!RES!RES_0402-0.0,5%,1/16W,CHIP,G21497-005!RES!!!F1837!!VTT_DEF_PWR_VR!!
S!@baseboard_fab2_lib.baseboard_fab2(sch_1):page229_i39@mstr_discrete.res(chips)!RES_0402-0.0,5%,1/16W,CHIP,G21A!R6U6!//jf4cfls225.pdx.intel.com/apd_proj/ppg_lib/epg_masterlib/logical/mstr_discrete/res/chips/chips.prt!RES!RES_0402-0.0,5%,1/16W,CHIP,G21497-005!RES!!!F1819!!VTT_GHJ_PWR_VR!!
S!@baseboard_fab2_lib.baseboard_fab2(sch_1):page189_i18@mstr_discrete.res(chips)!RES_0402-0.0,5%,1/16W,CHIP,G21A!R8G7!//jf4cfls225.pdx.intel.com/apd_proj/ppg_lib/epg_masterlib/logical/mstr_discrete/res/chips/chips.prt!RES!RES_0402-0.0,5%,1/16W,CHIP,G21497-005!RES!!!F1771!!BMC_DEBUG_HEADER!!
S!@baseboard_fab2_lib.baseboard_fab2(sch_1):page189_i23@mstr_discrete.res(chips)!RES_0402-0.0,5%,1/16W,CHIP,G21A!R8G13!//jf4cfls225.pdx.intel.com/apd_proj/ppg_lib/epg_masterlib/logical/mstr_discrete/res/chips/chips.prt!RES!RES_0402-0.0,5%,1/16W,CHIP,G21497-005!RES!!!F1768!!BMC_DEBUG_HEADER!!
S!@baseboard_fab2_lib.baseboard_fab2(sch_1):page189_i26@mstr_discrete.res(chips)!RES_0402-0.0,5%,1/16W,CHIP,G21A!R8G18!//jf4cfls225.pdx.intel.com/apd_proj/ppg_lib/epg_masterlib/logical/mstr_discrete/res/chips/chips.prt!RES!RES_0402-0.0,5%,1/16W,CHIP,G21497-005!RES!!!F1765!!BMC_DEBUG_HEADER!!
S!@baseboard_fab2_lib.baseboard_fab2(sch_1):page189_i38@mstr_discrete.res(chips)!RES_0402-0.0,5%,1/16W,CHIP,G21A!R7G14!//jf4cfls225.pdx.intel.com/apd_proj/ppg_lib/epg_masterlib/logical/mstr_discrete/res/chips/chips.prt!RES!RES_0402-0.0,5%,1/16W,CHIP,G21497-005!RES!!!F1798!!BMC_DEBUG_HEADER!!
S!@baseboard_fab2_lib.baseboard_fab2(sch_1):page236_i92@mstr_discrete.res(chips)!RES_0402-0.0,5%,1/16W,CHIP,G21A!R7A18!//jf4cfls225.pdx.intel.com/apd_proj/ppg_lib/epg_masterlib/logical/mstr_discrete/res/chips/chips.prt!RES!RES_0402-0.0,5%,1/16W,CHIP,G21497-005!RES!!!F1815!!P1V05_PCH_STBY!!
S!@baseboard_fab2_lib.baseboard_fab2(sch_1):page95_i108@mstr_discrete.res(chips)!RES_0402-0.0,5%,1/16W,CHIP,G21A!R7E9!//jf4cfls225.pdx.intel.com/apd_proj/ppg_lib/epg_masterlib/logical/mstr_discrete/res/chips/chips.prt!RES!RES_0402-0.0,5%,1/16W,CHIP,G21497-005!RES!!!F1807!!PROC_SIDEBAND!!
S!@baseboard_fab2_lib.baseboard_fab2(sch_1):page170_i51@mstr_discrete.res(chips)!RES_0402-0.0,5%,1/16W,CHIP,G21A!R1R8!//jf4cfls225.pdx.intel.com/apd_proj/ppg_lib/epg_masterlib/logical/mstr_discrete/res/chips/chips.prt!RES!RES_0402-0.0,5%,1/16W,CHIP,G21497-005!RES!!!F1925!!PROC_SIDEBAND!!
S!@baseboard_fab2_lib.baseboard_fab2(sch_1):page232_i299@mstr_discrete.res(chips)!RES_0402-0.0,5%,1/16W,CHIP,G21A!R7B11!//jf4cfls225.pdx.intel.com/apd_proj/ppg_lib/epg_masterlib/logical/mstr_discrete/res/chips/chips.prt!RES!RES_0402-0.0,5%,1/16W,CHIP,G21497-005!RES!!!F1813!!PVPP_KLM_VR!!
S!@baseboard_fab2_lib.baseboard_fab2(sch_1):page233_i271@mstr_discrete.res(chips)!RES_0402-0.0,5%,1/16W,CHIP,G21A!R4G8!//jf4cfls225.pdx.intel.com/apd_proj/ppg_lib/epg_masterlib/logical/mstr_discrete/res/chips/chips.prt!RES!RES_0402-0.0,5%,1/16W,CHIP,G21497-005!RES!!!F1853!!PVPP_KLM_VR!!
S!@baseboard_fab2_lib.baseboard_fab2(sch_1):page234_i214@mstr_discrete.res(chips)!RES_0402-0.0,5%,1/16W,CHIP,G21A!R4B3!//jf4cfls225.pdx.intel.com/apd_proj/ppg_lib/epg_masterlib/logical/mstr_discrete/res/chips/chips.prt!RES!RES_0402-0.0,5%,1/16W,CHIP,G21497-005!RES!!!F1870!!PVPP_KLM_VR!!
S!@baseboard_fab2_lib.baseboard_fab2(sch_1):page232_i240@mstr_discrete.res(chips)!RES_0402-0.0,5%,1/16W,CHIP,G21A!R7B19!//jf4cfls225.pdx.intel.com/apd_proj/ppg_lib/epg_masterlib/logical/mstr_discrete/res/chips/chips.prt!RES!RES_0402-0.0,5%,1/16W,CHIP,G21497-005!RES!!!F1891!!PVPP_KLM_VR!!
S!@baseboard_fab2_lib.baseboard_fab2(sch_1):page233_i199@mstr_discrete.res(chips)!RES_0402-0.0,5%,1/16W,CHIP,G21A!R4G24!//jf4cfls225.pdx.intel.com/apd_proj/ppg_lib/epg_masterlib/logical/mstr_discrete/res/chips/chips.prt!RES!RES_0402-0.0,5%,1/16W,CHIP,G21497-005!RES!!!F1823!!PVPP_KLM_VR!!
S!@baseboard_fab2_lib.baseboard_fab2(sch_1):page234_i155@mstr_discrete.res(chips)!RES_0402-0.0,5%,1/16W,CHIP,G21A!R4B13!//jf4cfls225.pdx.intel.com/apd_proj/ppg_lib/epg_masterlib/logical/mstr_discrete/res/chips/chips.prt!RES!RES_0402-0.0,5%,1/16W,CHIP,G21497-005!RES!!!F1835!!PVPP_KLM_VR!!
S!@baseboard_fab2_lib.baseboard_fab2(sch_1):page158_i91@mstr_discrete.res(chips)!RES_0402-0.0,5%,1/16W,CHIP,G21A!R9F27!//jf4cfls225.pdx.intel.com/apd_proj/ppg_lib/epg_masterlib/logical/mstr_discrete/res/chips/chips.prt!RES!RES_0402-0.0,5%,1/16W,CHIP,G21497-005!RES!!!F1753!!UART_MUX!!
S!@baseboard_fab2_lib.baseboard_fab2(sch_1):page183_i24@mstr_discrete.res(chips)!RES_0402-0.0,5%,1/16W,CHIP,G21A!R9F58!//jf4cfls225.pdx.intel.com/apd_proj/ppg_lib/epg_masterlib/logical/mstr_discrete/res/chips/chips.prt!RES!RES_0402-0.0,5%,1/16W,CHIP,G21497-005!RES!!!F1747!!LBG!!
S!@baseboard_fab2_lib.baseboard_fab2(sch_1):page183_i25@mstr_discrete.res(chips)!RES_0402-0.0,5%,1/16W,CHIP,G21A!R9F59!//jf4cfls225.pdx.intel.com/apd_proj/ppg_lib/epg_masterlib/logical/mstr_discrete/res/chips/chips.prt!RES!RES_0402-0.0,5%,1/16W,CHIP,G21497-005!RES!!!F1746!!LBG!!
S!@baseboard_fab2_lib.baseboard_fab2(sch_1):page231_i168@mstr_discrete.res(chips)!RES_0402-0.0,5%,1/16W,CHIP,G21A!R7F12!//jf4cfls225.pdx.intel.com/apd_proj/ppg_lib/epg_masterlib/logical/mstr_discrete/res/chips/chips.prt!RES!RES_0402-0.0,5%,1/16W,CHIP,G21497-005!RES!!!F1802!!PVPP_KLM_VR!!
S!@baseboard_fab2_lib.baseboard_fab2(sch_1):page240_i144@mstr_discrete.res(chips)!RES_0402-0.0,5%,1/16W,CHIP,G21A!R8E25!//jf4cfls225.pdx.intel.com/apd_proj/ppg_lib/epg_masterlib/logical/mstr_discrete/res/chips/chips.prt!RES!RES_0402-0.0,5%,1/16W,CHIP,G21497-005!RES!!!F1784!!PVPP_KLM_VR!!
S!@baseboard_fab2_lib.baseboard_fab2(sch_1):page138_i171@mstr_discrete.res(chips)!RES_0402-0.0,5%,1/16W,CHIP,G21A!R2N20!//jf4cfls225.pdx.intel.com/apd_proj/ppg_lib/epg_masterlib/logical/mstr_discrete/res/chips/chips.prt!RES!RES_0402-0.0,5%,1/16W,CHIP,G21497-005!RES!!!F1916!!SMBUS!!
S!@baseboard_fab2_lib.baseboard_fab2(sch_1):page138_i175@mstr_discrete.res(chips)!RES_0402-0.0,5%,1/16W,CHIP,G21A!R2N21!//jf4cfls225.pdx.intel.com/apd_proj/ppg_lib/epg_masterlib/logical/mstr_discrete/res/chips/chips.prt!RES!RES_0402-0.0,5%,1/16W,CHIP,G21497-005!RES!!!F1915!!SMBUS!!
S!@baseboard_fab2_lib.baseboard_fab2(sch_1):page231_i154@mstr_discrete.res(chips)!RES_0402-0.0,5%,1/16W,CHIP,G21A!R7F8!//jf4cfls225.pdx.intel.com/apd_proj/ppg_lib/epg_masterlib/logical/mstr_discrete/res/chips/chips.prt!RES!RES_0402-0.0,5%,1/16W,CHIP,G21497-005!RES!!!F1804!!PVPP_ABC_VR!!
S!@baseboard_fab2_lib.baseboard_fab2(sch_1):page231_i170@mstr_discrete.res(chips)!RES_0402-0.0,5%,1/16W,CHIP,G21A!R7F35!//jf4cfls225.pdx.intel.com/apd_proj/ppg_lib/epg_masterlib/logical/mstr_discrete/res/chips/chips.prt!RES!RES_0402-0.0,5%,1/16W,CHIP,G21497-005!RES!!!F1877!!PVPP_KLM_VR!!
S!@baseboard_fab2_lib.baseboard_fab2(sch_1):page232_i150@mstr_discrete.res(chips)!RES_0402-0.0,5%,1/16W,CHIP,G21A!R7B20!//jf4cfls225.pdx.intel.com/apd_proj/ppg_lib/epg_masterlib/logical/mstr_discrete/res/chips/chips.prt!RES!RES_0402-0.0,5%,1/16W,CHIP,G21497-005!RES!!!F1889!!PVPP_KLM_VR!!
S!@baseboard_fab2_lib.baseboard_fab2(sch_1):page233_i157@mstr_discrete.res(chips)!RES_0402-0.0,5%,1/16W,CHIP,G21A!R4G25!//jf4cfls225.pdx.intel.com/apd_proj/ppg_lib/epg_masterlib/logical/mstr_discrete/res/chips/chips.prt!RES!RES_0402-0.0,5%,1/16W,CHIP,G21497-005!RES!!!F1822!!PVPP_KLM_VR!!
S!@baseboard_fab2_lib.baseboard_fab2(sch_1):page240_i127@mstr_discrete.res(chips)!RES_0402-0.0,5%,1/16W,CHIP,G21A!R8E35!//jf4cfls225.pdx.intel.com/apd_proj/ppg_lib/epg_masterlib/logical/mstr_discrete/res/chips/chips.prt!RES!RES_0402-0.0,5%,1/16W,CHIP,G21497-005!RES!!!F1779!!P3V3_STBY_VR!!
S!@baseboard_fab2_lib.baseboard_fab2(sch_1):page240_i140@mstr_discrete.res(chips)!RES_0402-0.0,5%,1/16W,CHIP,G21A!R8E38!//jf4cfls225.pdx.intel.com/apd_proj/ppg_lib/epg_masterlib/logical/mstr_discrete/res/chips/chips.prt!RES!RES_0402-0.0,5%,1/16W,CHIP,G21497-005!RES!!!F1777!!P3V3_STBY_VR!!
S!@baseboard_fab2_lib.baseboard_fab2(sch_1):page240_i146@mstr_discrete.res(chips)!RES_0402-0.0,5%,1/16W,CHIP,G21A!R8F11!//jf4cfls225.pdx.intel.com/apd_proj/ppg_lib/epg_masterlib/logical/mstr_discrete/res/chips/chips.prt!RES!RES_0402-0.0,5%,1/16W,CHIP,G21497-005!RES!!!F1774!!P3V3_STBY_VR!!
S!@baseboard_fab2_lib.baseboard_fab2(sch_1):page184_i92@mstr_discrete.res(chips)!RES_0402-0.0,5%,1/16W,CHIP,G21A!R8D35!//jf4cfls225.pdx.intel.com/apd_proj/ppg_lib/epg_masterlib/logical/mstr_discrete/res/chips/chips.prt!RES!RES_0402-0.0,5%,1/16W,CHIP,G21497-005!RES!!!F1787!!TPM!!
S!@baseboard_fab2_lib.baseboard_fab2(sch_1):page184_i99@mstr_discrete.res(chips)!RES_0402-0.0,5%,1/16W,CHIP,G21A!R8E1!//jf4cfls225.pdx.intel.com/apd_proj/ppg_lib/epg_masterlib/logical/mstr_discrete/res/chips/chips.prt!RES!RES_0402-0.0,5%,1/16W,CHIP,G21497-005!RES!!!F1786!!TPM!!
S!@baseboard_fab2_lib.baseboard_fab2(sch_1):page141_i75@mstr_discrete.res(chips)!RES_0402-0.0,5%,1/16W,CHIP,G21A!R9G9!//jf4cfls225.pdx.intel.com/apd_proj/ppg_lib/epg_masterlib/logical/mstr_discrete/res/chips/chips.prt!RES!RES_0402-0.0,5%,1/16W,CHIP,G21497-005!RES!!!F1744!!NIC_SPRV!!
S!@baseboard_fab2_lib.baseboard_fab2(sch_1):page141_i76@mstr_discrete.res(chips)!RES_0402-0.0,5%,1/16W,CHIP,G21A!R9G11!//jf4cfls225.pdx.intel.com/apd_proj/ppg_lib/epg_masterlib/logical/mstr_discrete/res/chips/chips.prt!RES!RES_0402-0.0,5%,1/16W,CHIP,G21497-005!RES!!!F1743!!NIC_SPRV!!
S!@baseboard_fab2_lib.baseboard_fab2(sch_1):page141_i77@mstr_discrete.res(chips)!RES_0402-0.0,5%,1/16W,CHIP,G21A!R9G18!//jf4cfls225.pdx.intel.com/apd_proj/ppg_lib/epg_masterlib/logical/mstr_discrete/res/chips/chips.prt!RES!RES_0402-0.0,5%,1/16W,CHIP,G21497-005!RES!!!F1741!!NIC_SPRV!!
S!@baseboard_fab2_lib.baseboard_fab2(sch_1):page141_i78@mstr_discrete.res(chips)!RES_0402-0.0,5%,1/16W,CHIP,G21A!R9G17!//jf4cfls225.pdx.intel.com/apd_proj/ppg_lib/epg_masterlib/logical/mstr_discrete/res/chips/chips.prt!RES!RES_0402-0.0,5%,1/16W,CHIP,G21497-005!RES!!!F1742!!NIC_SPRV!!
S!@baseboard_fab2_lib.baseboard_fab2(sch_1):page141_i79@mstr_discrete.res(chips)!RES_0402-0.0,5%,1/16W,CHIP,G21A!R9G19!//jf4cfls225.pdx.intel.com/apd_proj/ppg_lib/epg_masterlib/logical/mstr_discrete/res/chips/chips.prt!RES!RES_0402-0.0,5%,1/16W,CHIP,G21497-005!RES!!!F1740!!NIC_SPRV!!
S!@baseboard_fab2_lib.baseboard_fab2(sch_1):page141_i80@mstr_discrete.res(chips)!RES_0402-0.0,5%,1/16W,CHIP,G21A!R9G20!//jf4cfls225.pdx.intel.com/apd_proj/ppg_lib/epg_masterlib/logical/mstr_discrete/res/chips/chips.prt!RES!RES_0402-0.0,5%,1/16W,CHIP,G21497-005!RES!!!F1739!!NIC_SPRV!!
S!@baseboard_fab2_lib.baseboard_fab2(sch_1):page141_i81@mstr_discrete.res(chips)!RES_0402-0.0,5%,1/16W,CHIP,G21A!R9G24!//jf4cfls225.pdx.intel.com/apd_proj/ppg_lib/epg_masterlib/logical/mstr_discrete/res/chips/chips.prt!RES!RES_0402-0.0,5%,1/16W,CHIP,G21497-005!RES!!!F1737!!NIC_SPRV!!
S!@baseboard_fab2_lib.baseboard_fab2(sch_1):page141_i82@mstr_discrete.res(chips)!RES_0402-0.0,5%,1/16W,CHIP,G21A!R9G22!//jf4cfls225.pdx.intel.com/apd_proj/ppg_lib/epg_masterlib/logical/mstr_discrete/res/chips/chips.prt!RES!RES_0402-0.0,5%,1/16W,CHIP,G21497-005!RES!!!F1738!!NIC_SPRV!!
S!@baseboard_fab2_lib.baseboard_fab2(sch_1):page111_i74@mstr_discrete.res(chips)!RES_0402-0.0,5%,1/16W,CHIP,G21A!R9A3!//jf4cfls225.pdx.intel.com/apd_proj/ppg_lib/epg_masterlib/logical/mstr_discrete/res/chips/chips.prt!RES!RES_0402-0.0,5%,1/16W,CHIP,G21497-005!RES!!!F1759!!DEBUG!!
S!@baseboard_fab2_lib.baseboard_fab2(sch_1):page108_i173@mstr_discrete.res(chips)!RES_0402-0.0,5%,1/16W,CHIP,G21A!R2U37!//jf4cfls225.pdx.intel.com/apd_proj/ppg_lib/epg_masterlib/logical/mstr_discrete/res/chips/chips.prt!RES!RES_0402-0.0,5%,1/16W,CHIP,G21497-005!RES!!!F1902!!IO_SLOT!!
S!@baseboard_fab2_lib.baseboard_fab2(sch_1):page142_i32@mstr_discrete.res(chips)!RES_0402-0.0,5%,1/16W,CHIP,G21A!R8E27!//jf4cfls225.pdx.intel.com/apd_proj/ppg_lib/epg_masterlib/logical/mstr_discrete/res/chips/chips.prt!RES!RES_0402-0.0,5%,1/16W,CHIP,G21497-005!RES!!!F1782!!PCIE_WAKE_BUFFER!!
S!@baseboard_fab2_lib.baseboard_fab2(sch_1):page142_i30@mstr_discrete.res(chips)!RES_0402-0.0,5%,1/16W,CHIP,G21A!R8E26!//jf4cfls225.pdx.intel.com/apd_proj/ppg_lib/epg_masterlib/logical/mstr_discrete/res/chips/chips.prt!RES!RES_0402-0.0,5%,1/16W,CHIP,G21497-005!RES!!!F1783!!PCIE_WAKE_BUFFER!!
S!@baseboard_fab2_lib.baseboard_fab2(sch_1):page142_i33@mstr_discrete.res(chips)!RES_0402-0.0,5%,1/16W,CHIP,G21A!R8E21!//jf4cfls225.pdx.intel.com/apd_proj/ppg_lib/epg_masterlib/logical/mstr_discrete/res/chips/chips.prt!RES!RES_0402-0.0,5%,1/16W,CHIP,G21497-005!RES!!!F1785!!PCIE_WAKE_BUFFER!!
S!@baseboard_fab2_lib.baseboard_fab2(sch_1):page142_i31@mstr_discrete.res(chips)!RES_0402-0.0,5%,1/16W,CHIP,G21A!R8E28!//jf4cfls225.pdx.intel.com/apd_proj/ppg_lib/epg_masterlib/logical/mstr_discrete/res/chips/chips.prt!RES!RES_0402-0.0,5%,1/16W,CHIP,G21497-005!RES!!!F1781!!PCIE_WAKE_BUFFER!!
S!@baseboard_fab2_lib.baseboard_fab2(sch_1):page176_i31@mstr_discrete.res(chips)!RES_0402-0.0,5%,1/16W,CHIP,G21A!R1M6!//jf4cfls225.pdx.intel.com/apd_proj/ppg_lib/epg_masterlib/logical/mstr_discrete/res/chips/chips.prt!RES!RES_0402-0.0,5%,1/16W,CHIP,G21497-005!RES!!!F1933!!USB!!
S!@baseboard_fab2_lib.baseboard_fab2(sch_1):page176_i16@mstr_discrete.res(chips)!RES_0402-0.0,5%,1/16W,CHIP,G21A!R1M5!//jf4cfls225.pdx.intel.com/apd_proj/ppg_lib/epg_masterlib/logical/mstr_discrete/res/chips/chips.prt!RES!RES_0402-0.0,5%,1/16W,CHIP,G21497-005!RES!!!F1934!!USB_REAR!!
S!@baseboard_fab2_lib.baseboard_fab2(sch_1):page176_i58@mstr_discrete.res(chips)!RES_0402-0.0,5%,1/16W,CHIP,G21A!R1L42!//jf4cfls225.pdx.intel.com/apd_proj/ppg_lib/epg_masterlib/logical/mstr_discrete/res/chips/chips.prt!RES!RES_0402-0.0,5%,1/16W,CHIP,G21497-005!RES!!!F1937!!USB_REAR!!
S!@baseboard_fab2_lib.baseboard_fab2(sch_1):page176_i59@mstr_discrete.res(chips)!RES_0402-0.0,5%,1/16W,CHIP,G21A!R1L40!//jf4cfls225.pdx.intel.com/apd_proj/ppg_lib/epg_masterlib/logical/mstr_discrete/res/chips/chips.prt!RES!RES_0402-0.0,5%,1/16W,CHIP,G21497-005!RES!!!F1938!!USB_REAR!!
S!@baseboard_fab2_lib.baseboard_fab2(sch_1):page176_i60@mstr_discrete.res(chips)!RES_0402-0.0,5%,1/16W,CHIP,G21A!R1M2!//jf4cfls225.pdx.intel.com/apd_proj/ppg_lib/epg_masterlib/logical/mstr_discrete/res/chips/chips.prt!RES!RES_0402-0.0,5%,1/16W,CHIP,G21497-005!RES!!!F1935!!USB_REAR!!
S!@baseboard_fab2_lib.baseboard_fab2(sch_1):page176_i61@mstr_discrete.res(chips)!RES_0402-0.0,5%,1/16W,CHIP,G21A!R1M1!//jf4cfls225.pdx.intel.com/apd_proj/ppg_lib/epg_masterlib/logical/mstr_discrete/res/chips/chips.prt!RES!RES_0402-0.0,5%,1/16W,CHIP,G21497-005!RES!!!F1936!!USB_REAR!!
S!@baseboard_fab2_lib.baseboard_fab2(sch_1):page222_i38@mstr_discrete.res(chips)!RES_0402-0.0,5%,1/16W,CHIP,G21A!R4A2!//jf4cfls225.pdx.intel.com/apd_proj/ppg_lib/epg_masterlib/logical/mstr_discrete/res/chips/chips.prt!RES!RES_0402-0.0,5%,1/16W,CHIP,G21497-005!RES!!!F1873!!VTT_DEF_PWR_VR!!
S!@baseboard_fab2_lib.baseboard_fab2(sch_1):page221_i38@mstr_discrete.res(chips)!RES_0402-0.0,5%,1/16W,CHIP,G21A!R4G23!//jf4cfls225.pdx.intel.com/apd_proj/ppg_lib/epg_masterlib/logical/mstr_discrete/res/chips/chips.prt!RES!RES_0402-0.0,5%,1/16W,CHIP,G21497-005!RES!!!F1851!!VTT_ABC_PWR_VR!!
S!@baseboard_fab2_lib.baseboard_fab2(sch_1):page229_i35@mstr_discrete.res(chips)!RES_0402-0.0,5%,1/16W,CHIP,G21A!R4G16!//jf4cfls225.pdx.intel.com/apd_proj/ppg_lib/epg_masterlib/logical/mstr_discrete/res/chips/chips.prt!RES!RES_0402-0.0,5%,1/16W,CHIP,G21497-005!RES!!!F1852!!VTT_GHJ_PWR_VR!!
S!@baseboard_fab2_lib.baseboard_fab2(sch_1):page230_i38@mstr_discrete.res(chips)!RES_0402-0.0,5%,1/16W,CHIP,G21A!R4A3!//jf4cfls225.pdx.intel.com/apd_proj/ppg_lib/epg_masterlib/logical/mstr_discrete/res/chips/chips.prt!RES!RES_0402-0.0,5%,1/16W,CHIP,G21497-005!RES!!!F1872!!VTT_KLM_PWR_VR!!
S!@baseboard_fab2_lib.baseboard_fab2(sch_1):page139_i201@mstr_discrete.res(chips)!RES_0402-0.0,5%,1/16W,CHIP,G21A!R9E18!//jf4cfls225.pdx.intel.com/apd_proj/ppg_lib/epg_masterlib/logical/mstr_discrete/res/chips/chips.prt!RES!RES_0402-0.0,5%,1/16W,CHIP,G21497-005!RES!!!F1756!!NIC_SPRV!!
S!@baseboard_fab2_lib.baseboard_fab2(sch_1):page190_i116@mstr_discrete.res(chips)!RES_0402-0.0,5%,1/16W,CHIP,G21A!R3P34!//jf4cfls225.pdx.intel.com/apd_proj/ppg_lib/epg_masterlib/logical/mstr_discrete/res/chips/chips.prt!RES!RES_0402-0.0,5%,1/16W,CHIP,G21497-005!RES!!!F1879!!CPLD!!
S!@baseboard_fab2_lib.baseboard_fab2(sch_1):page190_i117@mstr_discrete.res(chips)!RES_0402-0.0,5%,1/16W,CHIP,G21A!R3P35!//jf4cfls225.pdx.intel.com/apd_proj/ppg_lib/epg_masterlib/logical/mstr_discrete/res/chips/chips.prt!RES!RES_0402-0.0,5%,1/16W,CHIP,G21497-005!RES!!!F1878!!CPLD!!
S!@baseboard_fab2_lib.baseboard_fab2(sch_1):page200_i71@mstr_discrete.res(chips)!RES_0402-0.0,5%,1/16W,CHIP,G21A!R9P21!//jf4cfls225.pdx.intel.com/apd_proj/ppg_lib/epg_masterlib/logical/mstr_discrete/res/chips/chips.prt!RES!RES_0402-0.0,5%,1/16W,CHIP,G21497-005!RES!!!F1724!!HOT_SWAP!!
S!@baseboard_fab2_lib.baseboard_fab2(sch_1):page235_i159@mstr_discrete.res(chips)!RES_0402-0.0,5%,1/16W,CHIP,G21A!R2L14!//jf4cfls225.pdx.intel.com/apd_proj/ppg_lib/epg_masterlib/logical/mstr_discrete/res/chips/chips.prt!RES!RES_0402-0.0,5%,1/16W,CHIP,G21497-005!RES!!!F1918!!PVNN_PCH_STBY!!
S!@baseboard_fab2_lib.baseboard_fab2(sch_1):page175_i63@mstr_discrete.res(chips)!RES_0402-0.0,5%,1/16W,CHIP,G21A!R1L12!//jf4cfls225.pdx.intel.com/apd_proj/ppg_lib/epg_masterlib/logical/mstr_discrete/res/chips/chips.prt!RES!RES_0402-0.0,5%,1/16W,CHIP,G21497-005!RES!!!F1939!!MIO_CHASSIS!!
S!@baseboard_fab2_lib.baseboard_fab2(sch_1):page185_i115@mstr_discrete.res(chips)!RES_0402-0.0,5%,1/16W,CHIP,G21A!R2P14!//jf4cfls225.pdx.intel.com/apd_proj/ppg_lib/epg_masterlib/logical/mstr_discrete/res/chips/chips.prt!RES!RES_0402-0.0,5%,1/16W,CHIP,G21497-005!RES!!!F1788!!M_2!!
S!@baseboard_fab2_lib.baseboard_fab2(sch_1):page211_i24@mstr_discrete.res(chips)!RES_0402-0.0,5%,1/16W,CHIP,G21A!R3P22!//jf4cfls225.pdx.intel.com/apd_proj/ppg_lib/epg_masterlib/logical/mstr_discrete/res/chips/chips.prt!RES!RES_0402-0.0,5%,1/16W,CHIP,G21497-005!RES!!!F1881!!PVCCIO_CPU0!!
S!@baseboard_fab2_lib.baseboard_fab2(sch_1):page211_i61@mstr_discrete.res(chips)!RES_0402-0.0,5%,1/16W,CHIP,G21A!R3P1!//jf4cfls225.pdx.intel.com/apd_proj/ppg_lib/epg_masterlib/logical/mstr_discrete/res/chips/chips.prt!RES!RES_0402-0.0,5%,1/16W,CHIP,G21497-005!RES!!!F1887!!PVCCIO_CPU0!!
S!@baseboard_fab2_lib.baseboard_fab2(sch_1):page213_i16@mstr_discrete.res(chips)!RES_0402-0.0,5%,1/16W,CHIP,G21A!R4D56!//jf4cfls225.pdx.intel.com/apd_proj/ppg_lib/epg_masterlib/logical/mstr_discrete/res/chips/chips.prt!RES!RES_0402-0.0,5%,1/16W,CHIP,G21497-005!RES!!!F1860!!PVCCIO_CPU1!!
S!@baseboard_fab2_lib.baseboard_fab2(sch_1):page211_i16@mstr_discrete.res(chips)!RES_0402-0.0,5%,1/16W,CHIP,G21A!R3P11!//jf4cfls225.pdx.intel.com/apd_proj/ppg_lib/epg_masterlib/logical/mstr_discrete/res/chips/chips.prt!RES!RES_0402-0.0,5%,1/16W,CHIP,G21497-005!RES!!!F1882!!PVCCIO_CPU0!!
S!@baseboard_fab2_lib.baseboard_fab2(sch_1):page213_i37@mstr_discrete.res(chips)!RES_0402-0.0,5%,1/16W,CHIP,G21A!R4D54!//jf4cfls225.pdx.intel.com/apd_proj/ppg_lib/epg_masterlib/logical/mstr_discrete/res/chips/chips.prt!RES!RES_0402-0.0,5%,1/16W,CHIP,G21497-005!RES!!!F1861!!PVCCIO_CPU1!!
S!@baseboard_fab2_lib.baseboard_fab2(sch_1):page213_i25@mstr_discrete.res(chips)!RES_0402-0.0,5%,1/16W,CHIP,G21A!R4D47!//jf4cfls225.pdx.intel.com/apd_proj/ppg_lib/epg_masterlib/logical/mstr_discrete/res/chips/chips.prt!RES!RES_0402-0.0,5%,1/16W,CHIP,G21497-005!RES!!!F1864!!PVCCIO_CPU1!!
S!@baseboard_fab2_lib.baseboard_fab2(sch_1):page185_i105@mstr_discrete.res(chips)!RES_0402-0.0,5%,1/16W,CHIP,G21A!R8F18!//jf4cfls225.pdx.intel.com/apd_proj/ppg_lib/epg_masterlib/logical/mstr_discrete/res/chips/chips.prt!RES!RES_0402-0.0,5%,1/16W,CHIP,G21497-005!RES!!!F1773!!M_2!!
S!@baseboard_fab2_lib.baseboard_fab2(sch_1):page185_i106@mstr_discrete.res(chips)!RES_0402-0.0,5%,1/16W,CHIP,G21A!R8F21!//jf4cfls225.pdx.intel.com/apd_proj/ppg_lib/epg_masterlib/logical/mstr_discrete/res/chips/chips.prt!RES!RES_0402-0.0,5%,1/16W,CHIP,G21497-005!RES!!!F1772!!M_2!!
S!@baseboard_fab2_lib.baseboard_fab2(sch_1):page168_i6@mstr_discrete.res(chips)!RES_0402-0.0,5%,1/16W,CHIP,G21A!R1L6!//jf4cfls225.pdx.intel.com/apd_proj/ppg_lib/epg_masterlib/logical/mstr_discrete/res/chips/chips.prt!RES!RES_0402-0.0,5%,1/16W,CHIP,G21497-005!RES!!!F1940!!UART_MUX!!
S!@baseboard_fab2_lib.baseboard_fab2(sch_1):page155_i53@mstr_discrete.res(chips)!RES_0402-0.0,5%,1/16W,CHIP,G21A!R9A8!//jf4cfls225.pdx.intel.com/apd_proj/ppg_lib/epg_masterlib/logical/mstr_discrete/res/chips/chips.prt!RES!RES_0402-0.0,5%,1/16W,CHIP,G21497-005!RES!!!F1758!!BMC_DEBUG_HEADER!!
S!@baseboard_fab2_lib.baseboard_fab2(sch_1):page89_i2@mstr_discrete.res(chips)!RES_0402-0.0,5%,1/16W,CHIP,G21A!R4T1!//jf4cfls225.pdx.intel.com/apd_proj/ppg_lib/epg_masterlib/logical/mstr_discrete/res/chips/chips.prt!RES!RES_0402-0.0,5%,1/16W,CHIP,G21497-005!RES!!!F1848!!NV_DIMM!!
S!@baseboard_fab2_lib.baseboard_fab2(sch_1):page236_i59@mstr_discrete.res(chips)!RES_0402-0.0,5%,1/16W,CHIP,G21A!R8B12!//jf4cfls225.pdx.intel.com/apd_proj/ppg_lib/epg_masterlib/logical/mstr_discrete/res/chips/chips.prt!RES!RES_0402-0.0,5%,1/16W,CHIP,G21497-005!RES!!!F1791!!P1V05_PCH_STBY!!
S!@baseboard_fab2_lib.baseboard_fab2(sch_1):page236_i56@mstr_discrete.res(chips)!RES_0402-0.0,5%,1/16W,CHIP,G21A!R8B14!//jf4cfls225.pdx.intel.com/apd_proj/ppg_lib/epg_masterlib/logical/mstr_discrete/res/chips/chips.prt!RES!RES_0402-0.0,5%,1/16W,CHIP,G21497-005!RES!!!F1790!!P1V05_PCH_STBY!!
S!@baseboard_fab2_lib.baseboard_fab2(sch_1):page241_i78@mstr_discrete.res(chips)!RES_0402-0.0,5%,1/16W,CHIP,G21A!R8E37!//jf4cfls225.pdx.intel.com/apd_proj/ppg_lib/epg_masterlib/logical/mstr_discrete/res/chips/chips.prt!RES!RES_0402-0.0,5%,1/16W,CHIP,G21497-005!RES!!!F1778!!P5V_STBY_VR!!
S!@baseboard_fab2_lib.baseboard_fab2(sch_1):page223_i30@mstr_discrete.res(chips)!RES_0402-0.0,5%,1/16W,CHIP,G21A!R9U10!//jf4cfls225.pdx.intel.com/apd_proj/ppg_lib/epg_masterlib/logical/mstr_discrete/res/chips/chips.prt!RES!RES_0402-0.0,5%,1/16W,CHIP,G21497-005!RES!!!F1715!!VDDQ_GHJ_PWR_VR!!
S!@baseboard_fab2_lib.baseboard_fab2(sch_1):page197_i110@mstr_discrete.res(chips)!RES_0402-0.0,5%,1/16W,CHIP,G21A!R4F1!//jf4cfls225.pdx.intel.com/apd_proj/ppg_lib/epg_masterlib/logical/mstr_discrete/res/chips/chips.prt!RES!RES_0402-0.0,5%,1/16W,CHIP,G21497-005!RES!!!F1855!!PVDDQ_ABC_PWR_VR!!
S!@baseboard_fab2_lib.baseboard_fab2(sch_1):page197_i113@mstr_discrete.res(chips)!RES_0402-0.0,5%,1/16W,CHIP,G21A!R4B11!//jf4cfls225.pdx.intel.com/apd_proj/ppg_lib/epg_masterlib/logical/mstr_discrete/res/chips/chips.prt!RES!RES_0402-0.0,5%,1/16W,CHIP,G21497-005!RES!!!F1869!!PVDDQ_DEF_PWR_VR!!
S!@baseboard_fab2_lib.baseboard_fab2(sch_1):page197_i126@mstr_discrete.res(chips)!RES_0402-0.0,5%,1/16W,CHIP,G21A!R9T4!//jf4cfls225.pdx.intel.com/apd_proj/ppg_lib/epg_masterlib/logical/mstr_discrete/res/chips/chips.prt!RES!RES_0402-0.0,5%,1/16W,CHIP,G21497-005!RES!!!F1719!!PVDDQ_GHJ_PWR_VR!!
S!@baseboard_fab2_lib.baseboard_fab2(sch_1):page197_i137@mstr_discrete.res(chips)!RES_0402-0.0,5%,1/16W,CHIP,G21A!R1B14!//jf4cfls225.pdx.intel.com/apd_proj/ppg_lib/epg_masterlib/logical/mstr_discrete/res/chips/chips.prt!RES!RES_0402-0.0,5%,1/16W,CHIP,G21497-005!RES!!!F1961!!PVDDQ_KLM_PWR_VR!!
S!@baseboard_fab2_lib.baseboard_fab2(sch_1):page221_i28@mstr_discrete.res(chips)!RES_0402-0.0,5%,1/16W,CHIP,G21A!R6U4!//jf4cfls225.pdx.intel.com/apd_proj/ppg_lib/epg_masterlib/logical/mstr_discrete/res/chips/chips.prt!RES!RES_0402-0.0,5%,1/16W,CHIP,G21497-005!RES!!!F1821!!VTT_ABC_PWR_VR!!
S!@baseboard_fab2_lib.baseboard_fab2(sch_1):page221_i18@mstr_discrete.res(chips)!RES_0402-0.0,5%,1/16W,CHIP,G21A!R5U1!//jf4cfls225.pdx.intel.com/apd_proj/ppg_lib/epg_masterlib/logical/mstr_discrete/res/chips/chips.prt!RES!RES_0402-0.0,5%,1/16W,CHIP,G21497-005!RES!!!F1844!!VTT_ABC_PWR_VR!!
S!@baseboard_fab2_lib.baseboard_fab2(sch_1):page141_i56@mstr_discrete.res(chips)!RES_0402-0.0,5%,1/16W,CHIP,G21A!R9G4!//jf4cfls225.pdx.intel.com/apd_proj/ppg_lib/epg_masterlib/logical/mstr_discrete/res/chips/chips.prt!RES!RES_0402-0.0,5%,1/16W,CHIP,G21497-005!RES!!!F1745!!NIC_SPRV!!
S!@baseboard_fab2_lib.baseboard_fab2(sch_1):page222_i30@mstr_discrete.res(chips)!RES_0402-0.0,5%,1/16W,CHIP,G21A!R6L11!//jf4cfls225.pdx.intel.com/apd_proj/ppg_lib/epg_masterlib/logical/mstr_discrete/res/chips/chips.prt!RES!RES_0402-0.0,5%,1/16W,CHIP,G21497-005!RES!!!F1836!!VTT_DEF_PWR_VR!!
S!@baseboard_fab2_lib.baseboard_fab2(sch_1):page222_i15@mstr_discrete.res(chips)!RES_0402-0.0,5%,1/16W,CHIP,G21A!R5L1!//jf4cfls225.pdx.intel.com/apd_proj/ppg_lib/epg_masterlib/logical/mstr_discrete/res/chips/chips.prt!RES!RES_0402-0.0,5%,1/16W,CHIP,G21497-005!RES!!!F1845!!VTT_DEF_PWR_VR!!
S!@baseboard_fab2_lib.baseboard_fab2(sch_1):page229_i18@mstr_discrete.res(chips)!RES_0402-0.0,5%,1/16W,CHIP,G21A!R8U1!//jf4cfls225.pdx.intel.com/apd_proj/ppg_lib/epg_masterlib/logical/mstr_discrete/res/chips/chips.prt!RES!RES_0402-0.0,5%,1/16W,CHIP,G21497-005!RES!!!F1760!!VTT_GHJ_PWR_VR!!
S!@baseboard_fab2_lib.baseboard_fab2(sch_1):page230_i13@mstr_discrete.res(chips)!RES_0402-0.0,5%,1/16W,CHIP,G21A!R8L1!//jf4cfls225.pdx.intel.com/apd_proj/ppg_lib/epg_masterlib/logical/mstr_discrete/res/chips/chips.prt!RES!RES_0402-0.0,5%,1/16W,CHIP,G21497-005!RES!!!F1761!!VTT_KLM_PWR_VR!!
S!@baseboard_fab2_lib.baseboard_fab2(sch_1):page229_i32@mstr_discrete.res(chips)!RES_0402-0.0,5%,1/16W,CHIP,G21A!R6U7!//jf4cfls225.pdx.intel.com/apd_proj/ppg_lib/epg_masterlib/logical/mstr_discrete/res/chips/chips.prt!RES!RES_0402-0.0,5%,1/16W,CHIP,G21497-005!RES!!!F1818!!VTT_GHJ_PWR_VR!!
S!@baseboard_fab2_lib.baseboard_fab2(sch_1):page230_i30@mstr_discrete.res(chips)!RES_0402-0.0,5%,1/16W,CHIP,G21A!R6L8!//jf4cfls225.pdx.intel.com/apd_proj/ppg_lib/epg_masterlib/logical/mstr_discrete/res/chips/chips.prt!RES!RES_0402-0.0,5%,1/16W,CHIP,G21497-005!RES!!!F1838!!VTT_KLM_PWR_VR!!
S!@baseboard_fab2_lib.baseboard_fab2(sch_1):page218_i34@mstr_discrete.res(chips)!RES_0402-0.0,5%,1/16W,CHIP,G21A!R3M1!//jf4cfls225.pdx.intel.com/apd_proj/ppg_lib/epg_masterlib/logical/mstr_discrete/res/chips/chips.prt!RES!RES_0402-0.0,5%,1/16W,CHIP,G21497-005!RES!!!F1892!!VDDQ_DEF_PWR_VR!!
S!@baseboard_fab2_lib.baseboard_fab2(sch_1):page218_i15@mstr_discrete.res(chips)!RES_0402-0.0,5%,1/16W,CHIP,G21A!R7A11!//jf4cfls225.pdx.intel.com/apd_proj/ppg_lib/epg_masterlib/logical/mstr_discrete/res/chips/chips.prt!RES!RES_0402-0.0,5%,1/16W,CHIP,G21497-005!RES!!!F1817!!VDDQ_DEF_PWR_VR!!
S!@baseboard_fab2_lib.baseboard_fab2(sch_1):page218_i25@mstr_discrete.res(chips)!RES_0402-0.0,5%,1/16W,CHIP,G21A!R7A12!//jf4cfls225.pdx.intel.com/apd_proj/ppg_lib/epg_masterlib/logical/mstr_discrete/res/chips/chips.prt!RES!RES_0402-0.0,5%,1/16W,CHIP,G21497-005!RES!!!F1816!!VDDQ_DEF_PWR_VR!!
S!@baseboard_fab2_lib.baseboard_fab2(sch_1):page223_i16@mstr_discrete.res(chips)!RES_0402-0.0,5%,1/16W,CHIP,G21A!R1G9!//jf4cfls225.pdx.intel.com/apd_proj/ppg_lib/epg_masterlib/logical/mstr_discrete/res/chips/chips.prt!RES!RES_0402-0.0,5%,1/16W,CHIP,G21497-005!RES!!!F1944!!VDDQ_GHJ_PWR_VR!!
S!@baseboard_fab2_lib.baseboard_fab2(sch_1):page223_i23@mstr_discrete.res(chips)!RES_0402-0.0,5%,1/16W,CHIP,G21A!R1G10!//jf4cfls225.pdx.intel.com/apd_proj/ppg_lib/epg_masterlib/logical/mstr_discrete/res/chips/chips.prt!RES!RES_0402-0.0,5%,1/16W,CHIP,G21497-005!RES!!!F1943!!VDDQ_GHJ_PWR_VR!!
S!@baseboard_fab2_lib.baseboard_fab2(sch_1):page226_i30@mstr_discrete.res(chips)!RES_0402-0.0,5%,1/16W,CHIP,G21A!R9M3!//jf4cfls225.pdx.intel.com/apd_proj/ppg_lib/epg_masterlib/logical/mstr_discrete/res/chips/chips.prt!RES!RES_0402-0.0,5%,1/16W,CHIP,G21497-005!RES!!!F1736!!VDDQ_KLM_PWR_VR!!
S!@baseboard_fab2_lib.baseboard_fab2(sch_1):page226_i16@mstr_discrete.res(chips)!RES_0402-0.0,5%,1/16W,CHIP,G21A!R1B11!//jf4cfls225.pdx.intel.com/apd_proj/ppg_lib/epg_masterlib/logical/mstr_discrete/res/chips/chips.prt!RES!RES_0402-0.0,5%,1/16W,CHIP,G21497-005!RES!!!F1962!!VDDQ_KLM_PWR_VR!!
S!@baseboard_fab2_lib.baseboard_fab2(sch_1):page226_i23@mstr_discrete.res(chips)!RES_0402-0.0,5%,1/16W,CHIP,G21A!R1B10!//jf4cfls225.pdx.intel.com/apd_proj/ppg_lib/epg_masterlib/logical/mstr_discrete/res/chips/chips.prt!RES!RES_0402-0.0,5%,1/16W,CHIP,G21497-005!RES!!!F1963!!VDDQ_KLM_PWR_VR!!
S!@baseboard_fab2_lib.baseboard_fab2(sch_1):page234_i29@mstr_discrete.res(chips)!RES_0402-0.0,5%,1/16W,CHIP,G21A!R4B14!//jf4cfls225.pdx.intel.com/apd_proj/ppg_lib/epg_masterlib/logical/mstr_discrete/res/chips/chips.prt!RES!RES_0402-0.0,5%,1/16W,CHIP,G21497-005!RES!!!F1834!!PVPP_KLM_VR!!
S!@baseboard_fab2_lib.baseboard_fab2(sch_1):page209_i11@mstr_discrete.res(chips)!RES_0402-0.0,5%,1/16W,CHIP,G21A!R1E6!//jf4cfls225.pdx.intel.com/apd_proj/ppg_lib/epg_masterlib/logical/mstr_discrete/res/chips/chips.prt!RES!RES_0402-0.0,5%,1/16W,CHIP,G21497-005!RES!!!F1947!!PVCCIN_CPU1_VSENSE_VR!!
S!@baseboard_fab2_lib.baseboard_fab2(sch_1):page209_i10@mstr_discrete.res(chips)!RES_0402-0.0,5%,1/16W,CHIP,G21A!R1E7!//jf4cfls225.pdx.intel.com/apd_proj/ppg_lib/epg_masterlib/logical/mstr_discrete/res/chips/chips.prt!RES!RES_0402-0.0,5%,1/16W,CHIP,G21497-005!RES!!!F1946!!PVCCIN_CPU1_VSENSE_VR!!
S!@baseboard_fab2_lib.baseboard_fab2(sch_1):page214_i99@mstr_discrete.res(chips)!RES_0402-0.0,5%,1/16W,CHIP,G21A!R3D29!//jf4cfls225.pdx.intel.com/apd_proj/ppg_lib/epg_masterlib/logical/mstr_discrete/res/chips/chips.prt!RES!RES_0402-0.0,5%,1/16W,CHIP,G21497-005!RES!!!F1898!!PVCCIO_CPU1!!
S!@baseboard_fab2_lib.baseboard_fab2(sch_1):page214_i104@mstr_discrete.res(chips)!RES_0402-0.0,5%,1/16W,CHIP,G21A!R3D30!//jf4cfls225.pdx.intel.com/apd_proj/ppg_lib/epg_masterlib/logical/mstr_discrete/res/chips/chips.prt!RES!RES_0402-0.0,5%,1/16W,CHIP,G21497-005!RES!!!F1897!!PVCCIO_CPU1!!
S!@baseboard_fab2_lib.baseboard_fab2(sch_1):page241_i37@mstr_discrete.res(chips)!RES_0402-0.0,5%,1/16W,CHIP,G21A!R7E17!//jf4cfls225.pdx.intel.com/apd_proj/ppg_lib/epg_masterlib/logical/mstr_discrete/res/chips/chips.prt!RES!RES_0402-0.0,5%,1/16W,CHIP,G21497-005!RES!!!F1805!!P5V_STBY_VR!!
S!@baseboard_fab2_lib.baseboard_fab2(sch_1):page241_i58@mstr_discrete.res(chips)!RES_0402-0.0,5%,1/16W,CHIP,G21A!R7E13!//jf4cfls225.pdx.intel.com/apd_proj/ppg_lib/epg_masterlib/logical/mstr_discrete/res/chips/chips.prt!RES!RES_0402-0.0,5%,1/16W,CHIP,G21497-005!RES!!!F1806!!P5V_STBY_VR!!
S!@baseboard_fab2_lib.baseboard_fab2(sch_1):page93_i15@mstr_discrete.res(chips)!RES_0402-0.0,5%,1/16W,CHIP,G21A!R2T32!//jf4cfls225.pdx.intel.com/apd_proj/ppg_lib/epg_masterlib/logical/mstr_discrete/res/chips/chips.prt!RES!RES_0402-0.0,5%,1/16W,CHIP,G21497-005!RES!!!F1907!!PROC_SIDEBAND!!
S!@baseboard_fab2_lib.baseboard_fab2(sch_1):page93_i23@mstr_discrete.res(chips)!RES_0402-0.0,5%,1/16W,CHIP,G21A!R2T17!//jf4cfls225.pdx.intel.com/apd_proj/ppg_lib/epg_masterlib/logical/mstr_discrete/res/chips/chips.prt!RES!RES_0402-0.0,5%,1/16W,CHIP,G21497-005!RES!!!F1910!!PROC_SIDEBAND!!
S!@baseboard_fab2_lib.baseboard_fab2(sch_1):page93_i16@mstr_discrete.res(chips)!RES_0402-0.0,5%,1/16W,CHIP,G21A!R2T20!//jf4cfls225.pdx.intel.com/apd_proj/ppg_lib/epg_masterlib/logical/mstr_discrete/res/chips/chips.prt!RES!RES_0402-0.0,5%,1/16W,CHIP,G21497-005!RES!!!F1909!!PROC_SIDEBAND!!
S!@baseboard_fab2_lib.baseboard_fab2(sch_1):page93_i13@mstr_discrete.res(chips)!RES_0402-0.0,5%,1/16W,CHIP,G21A!R2T27!//jf4cfls225.pdx.intel.com/apd_proj/ppg_lib/epg_masterlib/logical/mstr_discrete/res/chips/chips.prt!RES!RES_0402-0.0,5%,1/16W,CHIP,G21497-005!RES!!!F1908!!PROC_SIDEBAND!!
S!@baseboard_fab2_lib.baseboard_fab2(sch_1):page139_i110@mstr_discrete.res(chips)!RES_0402-0.0,5%,1/16W,CHIP,G21A!R9E20!//jf4cfls225.pdx.intel.com/apd_proj/ppg_lib/epg_masterlib/logical/mstr_discrete/res/chips/chips.prt!RES!RES_0402-0.0,5%,1/16W,CHIP,G21497-005!RES!!!F1755!!NIC_SPRV!!
S!@baseboard_fab2_lib.baseboard_fab2(sch_1):page139_i195@mstr_discrete.res(chips)!RES_0402-0.0,5%,1/16W,CHIP,G21A!R1R1!//jf4cfls225.pdx.intel.com/apd_proj/ppg_lib/epg_masterlib/logical/mstr_discrete/res/chips/chips.prt!RES!RES_0402-0.0,5%,1/16W,CHIP,G21497-005!RES!!!F1926!!NIC_SPRV!!
S!@baseboard_fab2_lib.baseboard_fab2(sch_1):page92_i97@mstr_discrete.res(chips)!RES_0402-0.0,5%,1/16W,CHIP,G21A!R3P59!//jf4cfls225.pdx.intel.com/apd_proj/ppg_lib/epg_masterlib/logical/mstr_discrete/res/chips/chips.prt!RES!RES_0402-0.0,5%,1/16W,CHIP,G21497-005!RES!!!F1903!!PROC_SIDEBAND!!
S!@baseboard_fab2_lib.baseboard_fab2(sch_1):page92_i98@mstr_discrete.res(chips)!RES_0402-0.0,5%,1/16W,CHIP,G21A!R3P58!//jf4cfls225.pdx.intel.com/apd_proj/ppg_lib/epg_masterlib/logical/mstr_discrete/res/chips/chips.prt!RES!RES_0402-0.0,5%,1/16W,CHIP,G21497-005!RES!!!F1904!!PROC_SIDEBAND!!
S!@baseboard_fab2_lib.baseboard_fab2(sch_1):page212_i71@mstr_discrete.res(chips)!RES_0402-0.0,5%,1/16W,CHIP,G21A!R3P9!//jf4cfls225.pdx.intel.com/apd_proj/ppg_lib/epg_masterlib/logical/mstr_discrete/res/chips/chips.prt!RES!RES_0402-0.0,5%,1/16W,CHIP,G21497-005!RES!!!F1884!!PVCCIO_CPU0!!
S!@baseboard_fab2_lib.baseboard_fab2(sch_1):page212_i66@mstr_discrete.res(chips)!RES_0402-0.0,5%,1/16W,CHIP,G21A!R3P10!//jf4cfls225.pdx.intel.com/apd_proj/ppg_lib/epg_masterlib/logical/mstr_discrete/res/chips/chips.prt!RES!RES_0402-0.0,5%,1/16W,CHIP,G21497-005!RES!!!F1883!!PVCCIO_CPU0!!
S!@baseboard_fab2_lib.baseboard_fab2(sch_1):page215_i313@mstr_discrete.res(chips)!RES_0402-0.0,5%,1/16W,CHIP,G21A!R3T13!//jf4cfls225.pdx.intel.com/apd_proj/ppg_lib/epg_masterlib/logical/mstr_discrete/res/chips/chips.prt!RES!RES_0402-0.0,5%,1/16W,CHIP,G21497-005!RES!!!F1875!!VDDQ_ABC_PWR_VR!!
S!@baseboard_fab2_lib.baseboard_fab2(sch_1):page215_i302@mstr_discrete.res(chips)!RES_0402-0.0,5%,1/16W,CHIP,G21A!R7G4!//jf4cfls225.pdx.intel.com/apd_proj/ppg_lib/epg_masterlib/logical/mstr_discrete/res/chips/chips.prt!RES!RES_0402-0.0,5%,1/16W,CHIP,G21497-005!RES!!!F1799!!VDDQ_ABC_PWR_VR!!
S!@baseboard_fab2_lib.baseboard_fab2(sch_1):page204_i61@mstr_discrete.res(chips)!RES_0402-0.0,5%,1/16W,CHIP,G21A!R4E16!//jf4cfls225.pdx.intel.com/apd_proj/ppg_lib/epg_masterlib/logical/mstr_discrete/res/chips/chips.prt!RES!RES_0402-0.0,5%,1/16W,CHIP,G21497-005!RES!!!F1857!!PVCCIN_CPU0_VSENSE_VR!!
S!@baseboard_fab2_lib.baseboard_fab2(sch_1):page204_i62@mstr_discrete.res(chips)!RES_0402-0.0,5%,1/16W,CHIP,G21A!R4E17!//jf4cfls225.pdx.intel.com/apd_proj/ppg_lib/epg_masterlib/logical/mstr_discrete/res/chips/chips.prt!RES!RES_0402-0.0,5%,1/16W,CHIP,G21497-005!RES!!!F1856!!PVCCIN_CPU0_VSENSE_VR!!
S!@baseboard_fab2_lib.baseboard_fab2(sch_1):page217_i67@mstr_discrete.res(chips)!RES_0402-0.0,5%,1/16W,CHIP,G21A!R4U5!//jf4cfls225.pdx.intel.com/apd_proj/ppg_lib/epg_masterlib/logical/mstr_discrete/res/chips/chips.prt!RES!RES_0402-0.0,5%,1/16W,CHIP,G21497-005!RES!!!F1847!!VDDQ_ABC_PWR_VR!!
S!@baseboard_fab2_lib.baseboard_fab2(sch_1):page217_i71@mstr_discrete.res(chips)!RES_0402-0.0,5%,1/16W,CHIP,G21A!R4U7!//jf4cfls225.pdx.intel.com/apd_proj/ppg_lib/epg_masterlib/logical/mstr_discrete/res/chips/chips.prt!RES!RES_0402-0.0,5%,1/16W,CHIP,G21497-005!RES!!!F1846!!VDDQ_ABC_PWR_VR!!
S!@baseboard_fab2_lib.baseboard_fab2(sch_1):page225_i67@mstr_discrete.res(chips)!RES_0402-0.0,5%,1/16W,CHIP,G21A!R7U3!//jf4cfls225.pdx.intel.com/apd_proj/ppg_lib/epg_masterlib/logical/mstr_discrete/res/chips/chips.prt!RES!RES_0402-0.0,5%,1/16W,CHIP,G21497-005!RES!!!F1792!!VDDQ_GHJ_PWR_VR!!
S!@baseboard_fab2_lib.baseboard_fab2(sch_1):page225_i71@mstr_discrete.res(chips)!RES_0402-0.0,5%,1/16W,CHIP,G21A!R7U1!//jf4cfls225.pdx.intel.com/apd_proj/ppg_lib/epg_masterlib/logical/mstr_discrete/res/chips/chips.prt!RES!RES_0402-0.0,5%,1/16W,CHIP,G21497-005!RES!!!F1793!!VDDQ_GHJ_PWR_VR!!
S!@baseboard_fab2_lib.baseboard_fab2(sch_1):page228_i67@mstr_discrete.res(chips)!RES_0402-0.0,5%,1/16W,CHIP,G21A!R7L1!//jf4cfls225.pdx.intel.com/apd_proj/ppg_lib/epg_masterlib/logical/mstr_discrete/res/chips/chips.prt!RES!RES_0402-0.0,5%,1/16W,CHIP,G21497-005!RES!!!F1795!!VDDQ_KLM_PWR_VR!!
S!@baseboard_fab2_lib.baseboard_fab2(sch_1):page228_i71@mstr_discrete.res(chips)!RES_0402-0.0,5%,1/16W,CHIP,G21A!R7L3!//jf4cfls225.pdx.intel.com/apd_proj/ppg_lib/epg_masterlib/logical/mstr_discrete/res/chips/chips.prt!RES!RES_0402-0.0,5%,1/16W,CHIP,G21497-005!RES!!!F1794!!VDDQ_KLM_PWR_VR!!
S!@baseboard_fab2_lib.baseboard_fab2(sch_1):page220_i67@mstr_discrete.res(chips)!RES_0402-0.0,5%,1/16W,CHIP,G21A!R4L1!//jf4cfls225.pdx.intel.com/apd_proj/ppg_lib/epg_masterlib/logical/mstr_discrete/res/chips/chips.prt!RES!RES_0402-0.0,5%,1/16W,CHIP,G21497-005!RES!!!F1850!!VDDQ_DEF_PWR_VR!!
S!@baseboard_fab2_lib.baseboard_fab2(sch_1):page220_i71@mstr_discrete.res(chips)!RES_0402-0.0,5%,1/16W,CHIP,G21A!R4L3!//jf4cfls225.pdx.intel.com/apd_proj/ppg_lib/epg_masterlib/logical/mstr_discrete/res/chips/chips.prt!RES!RES_0402-0.0,5%,1/16W,CHIP,G21497-005!RES!!!F1849!!VDDQ_DEF_PWR_VR!!
S!@baseboard_fab2_lib.baseboard_fab2(sch_1):page21_i154@mstr_discrete.res(chips)!RES_0402-0.0,5%,1/16W,CHIP,G21A!R6B4!//jf4cfls225.pdx.intel.com/apd_proj/ppg_lib/epg_masterlib/logical/mstr_discrete/res/chips/chips.prt!RES!RES_0402-0.0,5%,1/16W,CHIP,G21497-005!RES!!!F1843!!CPU0!!
S!@baseboard_fab2_lib.baseboard_fab2(sch_1):page21_i153@mstr_discrete.res(chips)!RES_0402-0.0,5%,1/16W,CHIP,G21A!R6B5!//jf4cfls225.pdx.intel.com/apd_proj/ppg_lib/epg_masterlib/logical/mstr_discrete/res/chips/chips.prt!RES!RES_0402-0.0,5%,1/16W,CHIP,G21497-005!RES!!!F1842!!CPU0!!
S!@baseboard_fab2_lib.baseboard_fab2(sch_1):page21_i151@mstr_discrete.res(chips)!RES_0402-0.0,5%,1/16W,CHIP,G21A!R6N11!//jf4cfls225.pdx.intel.com/apd_proj/ppg_lib/epg_masterlib/logical/mstr_discrete/res/chips/chips.prt!RES!RES_0402-0.0,5%,1/16W,CHIP,G21497-005!RES!!!F1833!!CPU0!!
S!@baseboard_fab2_lib.baseboard_fab2(sch_1):page21_i150@mstr_discrete.res(chips)!RES_0402-0.0,5%,1/16W,CHIP,G21A!R6N12!//jf4cfls225.pdx.intel.com/apd_proj/ppg_lib/epg_masterlib/logical/mstr_discrete/res/chips/chips.prt!RES!RES_0402-0.0,5%,1/16W,CHIP,G21497-005!RES!!!F1832!!CPU0!!
S!@baseboard_fab2_lib.baseboard_fab2(sch_1):page55_i25@mstr_discrete.res(chips)!RES_0402-0.0,5%,1/16W,CHIP,G21A!R1C3!//jf4cfls225.pdx.intel.com/apd_proj/ppg_lib/epg_masterlib/logical/mstr_discrete/res/chips/chips.prt!RES!RES_0402-0.0,5%,1/16W,CHIP,G21497-005!RES!!!F1959!!CPU1!!
S!@baseboard_fab2_lib.baseboard_fab2(sch_1):page199_i27@mstr_discrete.res(chips)!RES_0402-0.0,5%,1/16W,CHIP,G21A!R1D24!//jf4cfls225.pdx.intel.com/apd_proj/ppg_lib/epg_masterlib/logical/mstr_discrete/res/chips/chips.prt!RES!RES_0402-0.0,5%,1/16W,CHIP,G21497-005!RES!!!F1951!!HOT_SWAP!!
S!@baseboard_fab2_lib.baseboard_fab2(sch_1):page199_i28@mstr_discrete.res(chips)!RES_0402-0.0,5%,1/16W,CHIP,G21A!R1D25!//jf4cfls225.pdx.intel.com/apd_proj/ppg_lib/epg_masterlib/logical/mstr_discrete/res/chips/chips.prt!RES!RES_0402-0.0,5%,1/16W,CHIP,G21497-005!RES!!!F1950!!HOT_SWAP!!
S!@baseboard_fab2_lib.baseboard_fab2(sch_1):page199_i36@mstr_discrete.res(chips)!RES_0402-0.0,5%,1/16W,CHIP,G21A!R9P16!//jf4cfls225.pdx.intel.com/apd_proj/ppg_lib/epg_masterlib/logical/mstr_discrete/res/chips/chips.prt!RES!RES_0402-0.0,5%,1/16W,CHIP,G21497-005!RES!!!F1725!!HOT_SWAP!!
S!@baseboard_fab2_lib.baseboard_fab2(sch_1):page201_i40@mstr_discrete.res(chips)!RES_0402-0.0,5%,1/16W,CHIP,G21A!R4D26!//jf4cfls225.pdx.intel.com/apd_proj/ppg_lib/epg_masterlib/logical/mstr_discrete/res/chips/chips.prt!RES!RES_0402-0.0,5%,1/16W,CHIP,G21497-005!RES!!!F1866!!PVCCIN_CPU0_VR!!
S!@baseboard_fab2_lib.baseboard_fab2(sch_1):page201_i98@mstr_discrete.res(chips)!RES_0402-0.0,5%,1/16W,CHIP,G21A!R4D66!//jf4cfls225.pdx.intel.com/apd_proj/ppg_lib/epg_masterlib/logical/mstr_discrete/res/chips/chips.prt!RES!RES_0402-0.0,5%,1/16W,CHIP,G21497-005!RES!!!F1859!!PVCCIN_CPU0_VR!!
S!@baseboard_fab2_lib.baseboard_fab2(sch_1):page201_i26@mstr_discrete.res(chips)!RES_0402-0.0,5%,1/16W,CHIP,G21A!R4D67!//jf4cfls225.pdx.intel.com/apd_proj/ppg_lib/epg_masterlib/logical/mstr_discrete/res/chips/chips.prt!RES!RES_0402-0.0,5%,1/16W,CHIP,G21497-005!RES!!!F1858!!PVCCIN_CPU0_VR!!
S!@baseboard_fab2_lib.baseboard_fab2(sch_1):page201_i28@mstr_discrete.res(chips)!RES_0402-0.0,5%,1/16W,CHIP,G21A!R4D50!//jf4cfls225.pdx.intel.com/apd_proj/ppg_lib/epg_masterlib/logical/mstr_discrete/res/chips/chips.prt!RES!RES_0402-0.0,5%,1/16W,CHIP,G21497-005!RES!!!F1863!!PVCCIN_CPU0_VR!!
S!@baseboard_fab2_lib.baseboard_fab2(sch_1):page201_i31@mstr_discrete.res(chips)!RES_0402-0.0,5%,1/16W,CHIP,G21A!R4D53!//jf4cfls225.pdx.intel.com/apd_proj/ppg_lib/epg_masterlib/logical/mstr_discrete/res/chips/chips.prt!RES!RES_0402-0.0,5%,1/16W,CHIP,G21497-005!RES!!!F1862!!PVCCIN_CPU0_VR!!
S!@baseboard_fab2_lib.baseboard_fab2(sch_1):page206_i46@mstr_discrete.res(chips)!RES_0402-0.0,5%,1/16W,CHIP,G21A!R1C14!//jf4cfls225.pdx.intel.com/apd_proj/ppg_lib/epg_masterlib/logical/mstr_discrete/res/chips/chips.prt!RES!RES_0402-0.0,5%,1/16W,CHIP,G21497-005!RES!!!F1956!!PVCCIN_CPU1_VR!!
S!@baseboard_fab2_lib.baseboard_fab2(sch_1):page206_i38@mstr_discrete.res(chips)!RES_0402-0.0,5%,1/16W,CHIP,G21A!R1D2!//jf4cfls225.pdx.intel.com/apd_proj/ppg_lib/epg_masterlib/logical/mstr_discrete/res/chips/chips.prt!RES!RES_0402-0.0,5%,1/16W,CHIP,G21497-005!RES!!!F1953!!PVCCIN_CPU1_VR!!
S!@baseboard_fab2_lib.baseboard_fab2(sch_1):page206_i27@mstr_discrete.res(chips)!RES_0402-0.0,5%,1/16W,CHIP,G21A!R1C23!//jf4cfls225.pdx.intel.com/apd_proj/ppg_lib/epg_masterlib/logical/mstr_discrete/res/chips/chips.prt!RES!RES_0402-0.0,5%,1/16W,CHIP,G21497-005!RES!!!F1955!!PVCCIN_CPU1_VR!!
S!@baseboard_fab2_lib.baseboard_fab2(sch_1):page206_i37@mstr_discrete.res(chips)!RES_0402-0.0,5%,1/16W,CHIP,G21A!R1D3!//jf4cfls225.pdx.intel.com/apd_proj/ppg_lib/epg_masterlib/logical/mstr_discrete/res/chips/chips.prt!RES!RES_0402-0.0,5%,1/16W,CHIP,G21497-005!RES!!!F1952!!PVCCIN_CPU1_VR!!
S!@baseboard_fab2_lib.baseboard_fab2(sch_1):page206_i28@mstr_discrete.res(chips)!RES_0402-0.0,5%,1/16W,CHIP,G21A!R1C25!//jf4cfls225.pdx.intel.com/apd_proj/ppg_lib/epg_masterlib/logical/mstr_discrete/res/chips/chips.prt!RES!RES_0402-0.0,5%,1/16W,CHIP,G21497-005!RES!!!F1954!!PVCCIN_CPU1_VR!!
S!@baseboard_fab2_lib.baseboard_fab2(sch_1):page210_i31@mstr_discrete.res(chips)!RES_0402-0.0,5%,1/16W,CHIP,G21A!R1C7!//jf4cfls225.pdx.intel.com/apd_proj/ppg_lib/epg_masterlib/logical/mstr_discrete/res/chips/chips.prt!RES!RES_0402-0.0,5%,1/16W,CHIP,G21497-005!RES!!!F1957!!PVSA_CPU1_VSENSE_VR!!
S!@baseboard_fab2_lib.baseboard_fab2(sch_1):page210_i32@mstr_discrete.res(chips)!RES_0402-0.0,5%,1/16W,CHIP,G21A!R1C5!//jf4cfls225.pdx.intel.com/apd_proj/ppg_lib/epg_masterlib/logical/mstr_discrete/res/chips/chips.prt!RES!RES_0402-0.0,5%,1/16W,CHIP,G21497-005!RES!!!F1958!!PVSA_CPU1_VSENSE_VR!!
S!@baseboard_fab2_lib.baseboard_fab2(sch_1):page205_i26@mstr_discrete.res(chips)!RES_0402-0.0,5%,1/16W,CHIP,G21A!R4C4!//jf4cfls225.pdx.intel.com/apd_proj/ppg_lib/epg_masterlib/logical/mstr_discrete/res/chips/chips.prt!RES!RES_0402-0.0,5%,1/16W,CHIP,G21497-005!RES!!!F1867!!PVSA_CPU0_VSENSE_VR!!
S!@baseboard_fab2_lib.baseboard_fab2(sch_1):page205_i30@mstr_discrete.res(chips)!RES_0402-0.0,5%,1/16W,CHIP,G21A!R4C2!//jf4cfls225.pdx.intel.com/apd_proj/ppg_lib/epg_masterlib/logical/mstr_discrete/res/chips/chips.prt!RES!RES_0402-0.0,5%,1/16W,CHIP,G21497-005!RES!!!F1868!!PVSA_CPU0_VSENSE_VR!!
S!@baseboard_fab2_lib.baseboard_fab2(sch_1):page55_i24@mstr_discrete.res(chips)!RES_0402-0.0,5%,1/16W,CHIP,G21A!R1C2!//jf4cfls225.pdx.intel.com/apd_proj/ppg_lib/epg_masterlib/logical/mstr_discrete/res/chips/chips.prt!RES!RES_0402-0.0,5%,1/16W,CHIP,G21497-005!RES!!!F1960!!CPU1!!
S!@baseboard_fab2_lib.baseboard_fab2(sch_1):page55_i29@mstr_discrete.res(chips)!RES_0402-0.0,5%,1/16W,CHIP,G21A!R3B3!//jf4cfls225.pdx.intel.com/apd_proj/ppg_lib/epg_masterlib/logical/mstr_discrete/res/chips/chips.prt!RES!RES_0402-0.0,5%,1/16W,CHIP,G21497-005!RES!!!F1901!!CPU1!!
S!@baseboard_fab2_lib.baseboard_fab2(sch_1):page55_i28@mstr_discrete.res(chips)!RES_0402-0.0,5%,1/16W,CHIP,G21A!R3B5!//jf4cfls225.pdx.intel.com/apd_proj/ppg_lib/epg_masterlib/logical/mstr_discrete/res/chips/chips.prt!RES!RES_0402-0.0,5%,1/16W,CHIP,G21497-005!RES!!!F1900!!CPU1!!
S!@baseboard_fab2_lib.baseboard_fab2(sch_1):page97_i33@mstr_discrete.res(chips)!RES_0402-0.0,5%,1/16W,CHIP,G21A!R3D18!//jf4cfls225.pdx.intel.com/apd_proj/ppg_lib/epg_masterlib/logical/mstr_discrete/res/chips/chips.prt!RES!RES_0402-0.0,5%,1/16W,CHIP,G21497-005!RES!!!F1899!!PROC_SIDEBAND!!
S!@baseboard_fab2_lib.baseboard_fab2(sch_1):page200_i44@mstr_discrete.res(chips)!RES_0402-0.0,5%,1/16W,CHIP,G21A!R1D44!//jf4cfls225.pdx.intel.com/apd_proj/ppg_lib/epg_masterlib/logical/mstr_discrete/res/chips/chips.prt!RES!RES_0402-0.0,5%,1/16W,CHIP,G21497-005!RES!!!F1949!!HOT_SWAP!!
S!@baseboard_fab2_lib.baseboard_fab2(sch_1):page200_i43@mstr_discrete.res(chips)!RES_0402-0.0,5%,1/16W,CHIP,G21A!R1D45!//jf4cfls225.pdx.intel.com/apd_proj/ppg_lib/epg_masterlib/logical/mstr_discrete/res/chips/chips.prt!RES!RES_0402-0.0,5%,1/16W,CHIP,G21497-005!RES!!!F1948!!HOT_SWAP!!
S!@baseboard_fab2_lib.baseboard_fab2(sch_1):page92_i68@mstr_discrete.res(chips)!RES_0402-0.0,5%,1/16W,CHIP,G21A!R7D27!//jf4cfls225.pdx.intel.com/apd_proj/ppg_lib/epg_masterlib/logical/mstr_discrete/res/chips/chips.prt!RES!RES_0402-0.0,5%,1/16W,CHIP,G21497-005!RES!!!F1809!!PROC_SIDEBAND!!
S!@baseboard_fab2_lib.baseboard_fab2(sch_1):page92_i67@mstr_discrete.res(chips)!RES_0402-0.0,5%,1/16W,CHIP,G21A!R7D28!//jf4cfls225.pdx.intel.com/apd_proj/ppg_lib/epg_masterlib/logical/mstr_discrete/res/chips/chips.prt!RES!RES_0402-0.0,5%,1/16W,CHIP,G21497-005!RES!!!F1808!!PROC_SIDEBAND!!
S!@baseboard_fab2_lib.baseboard_fab2(sch_1):page92_i93@mstr_discrete.res(chips)!RES_0402-0.0,5%,1/16W,CHIP,G21A!R2T40!//jf4cfls225.pdx.intel.com/apd_proj/ppg_lib/epg_masterlib/logical/mstr_discrete/res/chips/chips.prt!RES!RES_0402-0.0,5%,1/16W,CHIP,G21497-005!RES!!!F1906!!PROC_SIDEBAND!!
S!@baseboard_fab2_lib.baseboard_fab2(sch_1):page92_i92@mstr_discrete.res(chips)!RES_0402-0.0,5%,1/16W,CHIP,G21A!R2T44!//jf4cfls225.pdx.intel.com/apd_proj/ppg_lib/epg_masterlib/logical/mstr_discrete/res/chips/chips.prt!RES!RES_0402-0.0,5%,1/16W,CHIP,G21497-005!RES!!!F1905!!PROC_SIDEBAND!!
S!@baseboard_fab2_lib.baseboard_fab2(sch_1):page215_i307@mstr_discrete.res(chips)!RES_0402-0.0,5%,1/16W,CHIP,G21A!R7G2!//jf4cfls225.pdx.intel.com/apd_proj/ppg_lib/epg_masterlib/logical/mstr_discrete/res/chips/chips.prt!RES!RES_0402-0.0,5%,1/16W,CHIP,G21497-005!RES!!!F1800!!VDDQ_ABC_PWR_VR!!
S!@baseboard_fab2_lib.baseboard_fab2(sch_1):page144_i405@mstr_discrete.res(chips)!RES_0402-0.0,5%,1/16W,CHIP,G21A!R9F7!//jf4cfls225.pdx.intel.com/apd_proj/ppg_lib/epg_masterlib/logical/mstr_discrete/res/chips/chips.prt!RES!RES_0402-0.0,5%,1/16W,CHIP,G21497-005!RES!!!F1754!!BMC!!
S!@baseboard_fab2_lib.baseboard_fab2(sch_1):page119_i215@mstr_discrete.res(chips)!RES_0402-0.0,5%,1/16W,EMPTY,G2A!R2U50!//jf4cfls225.pdx.intel.com/apd_proj/ppg_lib/epg_masterlib/logical/mstr_discrete/res/chips/chips.prt!RES!RES_0402-0.0,5%,1/16W,EMPTY,G21497-005!RES!!!F1595!!!!
S!@baseboard_fab2_lib.baseboard_fab2(sch_1):page166_i11@mstr_discrete.res(chips)!RES_0402-0.0,5%,1/16W,EMPTY,G2A!R7C18!//jf4cfls225.pdx.intel.com/apd_proj/ppg_lib/epg_masterlib/logical/mstr_discrete/res/chips/chips.prt!RES!RES_0402-0.0,5%,1/16W,EMPTY,G21497-005!RES!!!F1648!!PECI!!
S!@baseboard_fab2_lib.baseboard_fab2(sch_1):page93_i131@mstr_discrete.res(chips)!RES_0402-0.0,5%,1/16W,EMPTY,G2A!R8F37!//jf4cfls225.pdx.intel.com/apd_proj/ppg_lib/epg_masterlib/logical/mstr_discrete/res/chips/chips.prt!RES!RES_0402-0.0,5%,1/16W,EMPTY,G21497-005!RES!!!F1603!!!!
S!@baseboard_fab2_lib.baseboard_fab2(sch_1):page93_i133@mstr_discrete.res(chips)!RES_0402-0.0,5%,1/16W,EMPTY,G2A!R2T63!//jf4cfls225.pdx.intel.com/apd_proj/ppg_lib/epg_masterlib/logical/mstr_discrete/res/chips/chips.prt!RES!RES_0402-0.0,5%,1/16W,EMPTY,G21497-005!RES!!!F1602!!!!
S!@baseboard_fab2_lib.baseboard_fab2(sch_1):page93_i135@mstr_discrete.res(chips)!RES_0402-0.0,5%,1/16W,EMPTY,G2A!R1T35!//jf4cfls225.pdx.intel.com/apd_proj/ppg_lib/epg_masterlib/logical/mstr_discrete/res/chips/chips.prt!RES!RES_0402-0.0,5%,1/16W,EMPTY,G21497-005!RES!!!F1601!!!!
S!@baseboard_fab2_lib.baseboard_fab2(sch_1):page93_i137@mstr_discrete.res(chips)!RES_0402-0.0,5%,1/16W,EMPTY,G2A!R1T38!//jf4cfls225.pdx.intel.com/apd_proj/ppg_lib/epg_masterlib/logical/mstr_discrete/res/chips/chips.prt!RES!RES_0402-0.0,5%,1/16W,EMPTY,G21497-005!RES!!!F1600!!!!
S!@baseboard_fab2_lib.baseboard_fab2(sch_1):page152_i95@mstr_discrete.res(chips)!RES_0402-0.0,5%,1/16W,EMPTY,G2A!R3N30!//jf4cfls225.pdx.intel.com/apd_proj/ppg_lib/epg_masterlib/logical/mstr_discrete/res/chips/chips.prt!RES!RES_0402-0.0,5%,1/16W,EMPTY,G21497-005!RES!!!F1599!!!!
S!@baseboard_fab2_lib.baseboard_fab2(sch_1):page152_i98@mstr_discrete.res(chips)!RES_0402-0.0,5%,1/16W,EMPTY,G2A!R9G30!//jf4cfls225.pdx.intel.com/apd_proj/ppg_lib/epg_masterlib/logical/mstr_discrete/res/chips/chips.prt!RES!RES_0402-0.0,5%,1/16W,EMPTY,G21497-005!RES!!!F1598!!!!
S!@baseboard_fab2_lib.baseboard_fab2(sch_1):page152_i100@mstr_discrete.res(chips)!RES_0402-0.0,5%,1/16W,EMPTY,G2A!R7D35!//jf4cfls225.pdx.intel.com/apd_proj/ppg_lib/epg_masterlib/logical/mstr_discrete/res/chips/chips.prt!RES!RES_0402-0.0,5%,1/16W,EMPTY,G21497-005!RES!!!F1597!!!!
S!@baseboard_fab2_lib.baseboard_fab2(sch_1):page152_i102@mstr_discrete.res(chips)!RES_0402-0.0,5%,1/16W,EMPTY,G2A!R2U45!//jf4cfls225.pdx.intel.com/apd_proj/ppg_lib/epg_masterlib/logical/mstr_discrete/res/chips/chips.prt!RES!RES_0402-0.0,5%,1/16W,EMPTY,G21497-005!RES!!!F1596!!!!
S!@baseboard_fab2_lib.baseboard_fab2(sch_1):page107_i466@mstr_discrete.res(chips)!RES_0402-0.0,5%,1/16W,EMPTY,G2A!R2U14!//jf4cfls225.pdx.intel.com/apd_proj/ppg_lib/epg_masterlib/logical/mstr_discrete/res/chips/chips.prt!RES!RES_0402-0.0,5%,1/16W,EMPTY,G21497-005!RES!!!F1671!!!!
S!@baseboard_fab2_lib.baseboard_fab2(sch_1):page107_i465@mstr_discrete.res(chips)!RES_0402-0.0,5%,1/16W,EMPTY,G2A!R2U15!//jf4cfls225.pdx.intel.com/apd_proj/ppg_lib/epg_masterlib/logical/mstr_discrete/res/chips/chips.prt!RES!RES_0402-0.0,5%,1/16W,EMPTY,G21497-005!RES!!!F1670!!!!
S!@baseboard_fab2_lib.baseboard_fab2(sch_1):page107_i467@mstr_discrete.res(chips)!RES_0402-0.0,5%,1/16W,EMPTY,G2A!R2U16!//jf4cfls225.pdx.intel.com/apd_proj/ppg_lib/epg_masterlib/logical/mstr_discrete/res/chips/chips.prt!RES!RES_0402-0.0,5%,1/16W,EMPTY,G21497-005!RES!!!F1669!!!!
S!@baseboard_fab2_lib.baseboard_fab2(sch_1):page107_i464@mstr_discrete.res(chips)!RES_0402-0.0,5%,1/16W,EMPTY,G2A!R2U17!//jf4cfls225.pdx.intel.com/apd_proj/ppg_lib/epg_masterlib/logical/mstr_discrete/res/chips/chips.prt!RES!RES_0402-0.0,5%,1/16W,EMPTY,G21497-005!RES!!!F1668!!!!
S!@baseboard_fab2_lib.baseboard_fab2(sch_1):page107_i468@mstr_discrete.res(chips)!RES_0402-0.0,5%,1/16W,EMPTY,G2A!R2U18!//jf4cfls225.pdx.intel.com/apd_proj/ppg_lib/epg_masterlib/logical/mstr_discrete/res/chips/chips.prt!RES!RES_0402-0.0,5%,1/16W,EMPTY,G21497-005!RES!!!F1667!!!!
S!@baseboard_fab2_lib.baseboard_fab2(sch_1):page107_i463@mstr_discrete.res(chips)!RES_0402-0.0,5%,1/16W,EMPTY,G2A!R2U19!//jf4cfls225.pdx.intel.com/apd_proj/ppg_lib/epg_masterlib/logical/mstr_discrete/res/chips/chips.prt!RES!RES_0402-0.0,5%,1/16W,EMPTY,G21497-005!RES!!!F1666!!!!
S!@baseboard_fab2_lib.baseboard_fab2(sch_1):page107_i469@mstr_discrete.res(chips)!RES_0402-0.0,5%,1/16W,EMPTY,G2A!R2U20!//jf4cfls225.pdx.intel.com/apd_proj/ppg_lib/epg_masterlib/logical/mstr_discrete/res/chips/chips.prt!RES!RES_0402-0.0,5%,1/16W,EMPTY,G21497-005!RES!!!F1665!!!!
S!@baseboard_fab2_lib.baseboard_fab2(sch_1):page107_i462@mstr_discrete.res(chips)!RES_0402-0.0,5%,1/16W,EMPTY,G2A!R2U21!//jf4cfls225.pdx.intel.com/apd_proj/ppg_lib/epg_masterlib/logical/mstr_discrete/res/chips/chips.prt!RES!RES_0402-0.0,5%,1/16W,EMPTY,G21497-005!RES!!!F1664!!!!
S!@baseboard_fab2_lib.baseboard_fab2(sch_1):page107_i470@mstr_discrete.res(chips)!RES_0402-0.0,5%,1/16W,EMPTY,G2A!R2U22!//jf4cfls225.pdx.intel.com/apd_proj/ppg_lib/epg_masterlib/logical/mstr_discrete/res/chips/chips.prt!RES!RES_0402-0.0,5%,1/16W,EMPTY,G21497-005!RES!!!F1663!!!!
S!@baseboard_fab2_lib.baseboard_fab2(sch_1):page107_i461@mstr_discrete.res(chips)!RES_0402-0.0,5%,1/16W,EMPTY,G2A!R2U23!//jf4cfls225.pdx.intel.com/apd_proj/ppg_lib/epg_masterlib/logical/mstr_discrete/res/chips/chips.prt!RES!RES_0402-0.0,5%,1/16W,EMPTY,G21497-005!RES!!!F1662!!!!
S!@baseboard_fab2_lib.baseboard_fab2(sch_1):page107_i471@mstr_discrete.res(chips)!RES_0402-0.0,5%,1/16W,EMPTY,G2A!R2U24!//jf4cfls225.pdx.intel.com/apd_proj/ppg_lib/epg_masterlib/logical/mstr_discrete/res/chips/chips.prt!RES!RES_0402-0.0,5%,1/16W,EMPTY,G21497-005!RES!!!F1661!!!!
S!@baseboard_fab2_lib.baseboard_fab2(sch_1):page107_i460@mstr_discrete.res(chips)!RES_0402-0.0,5%,1/16W,EMPTY,G2A!R2U25!//jf4cfls225.pdx.intel.com/apd_proj/ppg_lib/epg_masterlib/logical/mstr_discrete/res/chips/chips.prt!RES!RES_0402-0.0,5%,1/16W,EMPTY,G21497-005!RES!!!F1660!!!!
S!@baseboard_fab2_lib.baseboard_fab2(sch_1):page107_i472@mstr_discrete.res(chips)!RES_0402-0.0,5%,1/16W,EMPTY,G2A!R2U26!//jf4cfls225.pdx.intel.com/apd_proj/ppg_lib/epg_masterlib/logical/mstr_discrete/res/chips/chips.prt!RES!RES_0402-0.0,5%,1/16W,EMPTY,G21497-005!RES!!!F1659!!!!
S!@baseboard_fab2_lib.baseboard_fab2(sch_1):page107_i459@mstr_discrete.res(chips)!RES_0402-0.0,5%,1/16W,EMPTY,G2A!R2U27!//jf4cfls225.pdx.intel.com/apd_proj/ppg_lib/epg_masterlib/logical/mstr_discrete/res/chips/chips.prt!RES!RES_0402-0.0,5%,1/16W,EMPTY,G21497-005!RES!!!F1658!!!!
S!@baseboard_fab2_lib.baseboard_fab2(sch_1):page107_i473@mstr_discrete.res(chips)!RES_0402-0.0,5%,1/16W,EMPTY,G2A!R2U28!//jf4cfls225.pdx.intel.com/apd_proj/ppg_lib/epg_masterlib/logical/mstr_discrete/res/chips/chips.prt!RES!RES_0402-0.0,5%,1/16W,EMPTY,G21497-005!RES!!!F1657!!!!
S!@baseboard_fab2_lib.baseboard_fab2(sch_1):page107_i458@mstr_discrete.res(chips)!RES_0402-0.0,5%,1/16W,EMPTY,G2A!R2U29!//jf4cfls225.pdx.intel.com/apd_proj/ppg_lib/epg_masterlib/logical/mstr_discrete/res/chips/chips.prt!RES!RES_0402-0.0,5%,1/16W,EMPTY,G21497-005!RES!!!F1656!!!!
S!@baseboard_fab2_lib.baseboard_fab2(sch_1):page145_i257@mstr_discrete.res(chips)!RES_0402-0.0,5%,1/16W,EMPTY,G2A!R9F60!//jf4cfls225.pdx.intel.com/apd_proj/ppg_lib/epg_masterlib/logical/mstr_discrete/res/chips/chips.prt!RES!RES_0402-0.0,5%,1/16W,EMPTY,G21497-005!RES!!!F1604!!BMC!!
S!@baseboard_fab2_lib.baseboard_fab2(sch_1):page93_i88@mstr_discrete.res(chips)!RES_0402-0.0,5%,1/16W,EMPTY,G2A!R2T57!//jf4cfls225.pdx.intel.com/apd_proj/ppg_lib/epg_masterlib/logical/mstr_discrete/res/chips/chips.prt!RES!RES_0402-0.0,5%,1/16W,EMPTY,G21497-005!RES!!!F1620!!!!
S!@baseboard_fab2_lib.baseboard_fab2(sch_1):page93_i108@mstr_discrete.res(chips)!RES_0402-0.0,5%,1/16W,EMPTY,G2A!R2T69!//jf4cfls225.pdx.intel.com/apd_proj/ppg_lib/epg_masterlib/logical/mstr_discrete/res/chips/chips.prt!RES!RES_0402-0.0,5%,1/16W,EMPTY,G21497-005!RES!!!F1619!!!!
S!@baseboard_fab2_lib.baseboard_fab2(sch_1):page93_i89@mstr_discrete.res(chips)!RES_0402-0.0,5%,1/16W,EMPTY,G2A!R2T61!//jf4cfls225.pdx.intel.com/apd_proj/ppg_lib/epg_masterlib/logical/mstr_discrete/res/chips/chips.prt!RES!RES_0402-0.0,5%,1/16W,EMPTY,G21497-005!RES!!!F1618!!!!
S!@baseboard_fab2_lib.baseboard_fab2(sch_1):page93_i107@mstr_discrete.res(chips)!RES_0402-0.0,5%,1/16W,EMPTY,G2A!R2T59!//jf4cfls225.pdx.intel.com/apd_proj/ppg_lib/epg_masterlib/logical/mstr_discrete/res/chips/chips.prt!RES!RES_0402-0.0,5%,1/16W,EMPTY,G21497-005!RES!!!F1617!!!!
S!@baseboard_fab2_lib.baseboard_fab2(sch_1):page93_i93@mstr_discrete.res(chips)!RES_0402-0.0,5%,1/16W,EMPTY,G2A!R2T62!//jf4cfls225.pdx.intel.com/apd_proj/ppg_lib/epg_masterlib/logical/mstr_discrete/res/chips/chips.prt!RES!RES_0402-0.0,5%,1/16W,EMPTY,G21497-005!RES!!!F1616!!!!
S!@baseboard_fab2_lib.baseboard_fab2(sch_1):page93_i109@mstr_discrete.res(chips)!RES_0402-0.0,5%,1/16W,EMPTY,G2A!R2T71!//jf4cfls225.pdx.intel.com/apd_proj/ppg_lib/epg_masterlib/logical/mstr_discrete/res/chips/chips.prt!RES!RES_0402-0.0,5%,1/16W,EMPTY,G21497-005!RES!!!F1615!!!!
S!@baseboard_fab2_lib.baseboard_fab2(sch_1):page93_i110@mstr_discrete.res(chips)!RES_0402-0.0,5%,1/16W,EMPTY,G2A!R2T70!//jf4cfls225.pdx.intel.com/apd_proj/ppg_lib/epg_masterlib/logical/mstr_discrete/res/chips/chips.prt!RES!RES_0402-0.0,5%,1/16W,EMPTY,G21497-005!RES!!!F1614!!!!
S!@baseboard_fab2_lib.baseboard_fab2(sch_1):page93_i94@mstr_discrete.res(chips)!RES_0402-0.0,5%,1/16W,EMPTY,G2A!R2T58!//jf4cfls225.pdx.intel.com/apd_proj/ppg_lib/epg_masterlib/logical/mstr_discrete/res/chips/chips.prt!RES!RES_0402-0.0,5%,1/16W,EMPTY,G21497-005!RES!!!F1613!!!!
S!@baseboard_fab2_lib.baseboard_fab2(sch_1):page152_i51@mstr_discrete.res(chips)!RES_0402-0.0,5%,1/16W,EMPTY,G2A!R2U51!//jf4cfls225.pdx.intel.com/apd_proj/ppg_lib/epg_masterlib/logical/mstr_discrete/res/chips/chips.prt!RES!RES_0402-0.0,5%,1/16W,EMPTY,G21497-005!RES!!!F1612!!!!
S!@baseboard_fab2_lib.baseboard_fab2(sch_1):page152_i68@mstr_discrete.res(chips)!RES_0402-0.0,5%,1/16W,EMPTY,G2A!R1U62!//jf4cfls225.pdx.intel.com/apd_proj/ppg_lib/epg_masterlib/logical/mstr_discrete/res/chips/chips.prt!RES!RES_0402-0.0,5%,1/16W,EMPTY,G21497-005!RES!!!F1611!!!!
S!@baseboard_fab2_lib.baseboard_fab2(sch_1):page152_i50@mstr_discrete.res(chips)!RES_0402-0.0,5%,1/16W,EMPTY,G2A!R1U56!//jf4cfls225.pdx.intel.com/apd_proj/ppg_lib/epg_masterlib/logical/mstr_discrete/res/chips/chips.prt!RES!RES_0402-0.0,5%,1/16W,EMPTY,G21497-005!RES!!!F1610!!!!
S!@baseboard_fab2_lib.baseboard_fab2(sch_1):page152_i67@mstr_discrete.res(chips)!RES_0402-0.0,5%,1/16W,EMPTY,G2A!R1U55!//jf4cfls225.pdx.intel.com/apd_proj/ppg_lib/epg_masterlib/logical/mstr_discrete/res/chips/chips.prt!RES!RES_0402-0.0,5%,1/16W,EMPTY,G21497-005!RES!!!F1609!!!!
S!@baseboard_fab2_lib.baseboard_fab2(sch_1):page152_i47@mstr_discrete.res(chips)!RES_0402-0.0,5%,1/16W,EMPTY,G2A!R9G27!//jf4cfls225.pdx.intel.com/apd_proj/ppg_lib/epg_masterlib/logical/mstr_discrete/res/chips/chips.prt!RES!RES_0402-0.0,5%,1/16W,EMPTY,G21497-005!RES!!!F1608!!!!
S!@baseboard_fab2_lib.baseboard_fab2(sch_1):page152_i69@mstr_discrete.res(chips)!RES_0402-0.0,5%,1/16W,EMPTY,G2A!R1U57!//jf4cfls225.pdx.intel.com/apd_proj/ppg_lib/epg_masterlib/logical/mstr_discrete/res/chips/chips.prt!RES!RES_0402-0.0,5%,1/16W,EMPTY,G21497-005!RES!!!F1607!!!!
S!@baseboard_fab2_lib.baseboard_fab2(sch_1):page152_i66@mstr_discrete.res(chips)!RES_0402-0.0,5%,1/16W,EMPTY,G2A!R2U49!//jf4cfls225.pdx.intel.com/apd_proj/ppg_lib/epg_masterlib/logical/mstr_discrete/res/chips/chips.prt!RES!RES_0402-0.0,5%,1/16W,EMPTY,G21497-005!RES!!!F1606!!!!
S!@baseboard_fab2_lib.baseboard_fab2(sch_1):page152_i70@mstr_discrete.res(chips)!RES_0402-0.0,5%,1/16W,EMPTY,G2A!R1U61!//jf4cfls225.pdx.intel.com/apd_proj/ppg_lib/epg_masterlib/logical/mstr_discrete/res/chips/chips.prt!RES!RES_0402-0.0,5%,1/16W,EMPTY,G21497-005!RES!!!F1605!!!!
S!@baseboard_fab2_lib.baseboard_fab2(sch_1):page104_i94@mstr_discrete.res(chips)!RES_0402-0.0,5%,1/16W,EMPTY,G2A!R7D40!//jf4cfls225.pdx.intel.com/apd_proj/ppg_lib/epg_masterlib/logical/mstr_discrete/res/chips/chips.prt!RES!RES_0402-0.0,5%,1/16W,EMPTY,G21497-005!RES!!!F1628!!CLOCK_CPU1_OSC!!
S!@baseboard_fab2_lib.baseboard_fab2(sch_1):page104_i97@mstr_discrete.res(chips)!RES_0402-0.0,5%,1/16W,EMPTY,G2A!R7D38!//jf4cfls225.pdx.intel.com/apd_proj/ppg_lib/epg_masterlib/logical/mstr_discrete/res/chips/chips.prt!RES!RES_0402-0.0,5%,1/16W,EMPTY,G21497-005!RES!!!F1627!!CLOCK_CPU1_OSC!!
S!@baseboard_fab2_lib.baseboard_fab2(sch_1):page104_i78@mstr_discrete.res(chips)!RES_0402-0.0,5%,1/16W,EMPTY,G2A!R6F10!//jf4cfls225.pdx.intel.com/apd_proj/ppg_lib/epg_masterlib/logical/mstr_discrete/res/chips/chips.prt!RES!RES_0402-0.0,5%,1/16W,EMPTY,G21497-005!RES!!!F1626!!!!
S!@baseboard_fab2_lib.baseboard_fab2(sch_1):page104_i79@mstr_discrete.res(chips)!RES_0402-0.0,5%,1/16W,EMPTY,G2A!R6F11!//jf4cfls225.pdx.intel.com/apd_proj/ppg_lib/epg_masterlib/logical/mstr_discrete/res/chips/chips.prt!RES!RES_0402-0.0,5%,1/16W,EMPTY,G21497-005!RES!!!F1625!!!!
S!@baseboard_fab2_lib.baseboard_fab2(sch_1):page104_i84@mstr_discrete.res(chips)!RES_0402-0.0,5%,1/16W,EMPTY,G2A!R3F5!//jf4cfls225.pdx.intel.com/apd_proj/ppg_lib/epg_masterlib/logical/mstr_discrete/res/chips/chips.prt!RES!RES_0402-0.0,5%,1/16W,EMPTY,G21497-005!RES!!!F1624!!!!
S!@baseboard_fab2_lib.baseboard_fab2(sch_1):page104_i88@mstr_discrete.res(chips)!RES_0402-0.0,5%,1/16W,EMPTY,G2A!R3F6!//jf4cfls225.pdx.intel.com/apd_proj/ppg_lib/epg_masterlib/logical/mstr_discrete/res/chips/chips.prt!RES!RES_0402-0.0,5%,1/16W,EMPTY,G21497-005!RES!!!F1623!!!!
S!@baseboard_fab2_lib.baseboard_fab2(sch_1):page104_i95@mstr_discrete.res(chips)!RES_0402-0.0,5%,1/16W,EMPTY,G2A!R7D39!//jf4cfls225.pdx.intel.com/apd_proj/ppg_lib/epg_masterlib/logical/mstr_discrete/res/chips/chips.prt!RES!RES_0402-0.0,5%,1/16W,EMPTY,G21497-005!RES!!!F1622!!!!
S!@baseboard_fab2_lib.baseboard_fab2(sch_1):page104_i98@mstr_discrete.res(chips)!RES_0402-0.0,5%,1/16W,EMPTY,G2A!R7D37!//jf4cfls225.pdx.intel.com/apd_proj/ppg_lib/epg_masterlib/logical/mstr_discrete/res/chips/chips.prt!RES!RES_0402-0.0,5%,1/16W,EMPTY,G21497-005!RES!!!F1621!!!!
S!@baseboard_fab2_lib.baseboard_fab2(sch_1):page182_i110@mstr_discrete.res(chips)!RES_0402-0.0,5%,1/16W,EMPTY,G2A!R1C31!//jf4cfls225.pdx.intel.com/apd_proj/ppg_lib/epg_masterlib/logical/mstr_discrete/res/chips/chips.prt!RES!RES_0402-0.0,5%,1/16W,EMPTY,G21497-005!RES!!!F1677!!IO_SLOT!!
S!@baseboard_fab2_lib.baseboard_fab2(sch_1):page182_i97@mstr_discrete.res(chips)!RES_0402-0.0,5%,1/16W,EMPTY,G2A!R1C11!//jf4cfls225.pdx.intel.com/apd_proj/ppg_lib/epg_masterlib/logical/mstr_discrete/res/chips/chips.prt!RES!RES_0402-0.0,5%,1/16W,EMPTY,G21497-005!RES!!!F1678!!IO_SLOT!!
S!@baseboard_fab2_lib.baseboard_fab2(sch_1):page182_i101@mstr_discrete.res(chips)!RES_0402-0.0,5%,1/16W,EMPTY,G2A!R1C10!//jf4cfls225.pdx.intel.com/apd_proj/ppg_lib/epg_masterlib/logical/mstr_discrete/res/chips/chips.prt!RES!RES_0402-0.0,5%,1/16W,EMPTY,G21497-005!RES!!!F1679!!IO_SLOT!!
S!@baseboard_fab2_lib.baseboard_fab2(sch_1):page182_i104@mstr_discrete.res(chips)!RES_0402-0.0,5%,1/16W,EMPTY,G2A!R1C9!//jf4cfls225.pdx.intel.com/apd_proj/ppg_lib/epg_masterlib/logical/mstr_discrete/res/chips/chips.prt!RES!RES_0402-0.0,5%,1/16W,EMPTY,G21497-005!RES!!!F1680!!IO_SLOT!!
S!@baseboard_fab2_lib.baseboard_fab2(sch_1):page182_i107@mstr_discrete.res(chips)!RES_0402-0.0,5%,1/16W,EMPTY,G2A!R1F9!//jf4cfls225.pdx.intel.com/apd_proj/ppg_lib/epg_masterlib/logical/mstr_discrete/res/chips/chips.prt!RES!RES_0402-0.0,5%,1/16W,EMPTY,G21497-005!RES!!!F1676!!IO_SLOT!!
S!@baseboard_fab2_lib.baseboard_fab2(sch_1):page118_i125@mstr_discrete.res(chips)!RES_0402-0.0,5%,1/16W,EMPTY,G2A!R8C23!//jf4cfls225.pdx.intel.com/apd_proj/ppg_lib/epg_masterlib/logical/mstr_discrete/res/chips/chips.prt!RES!RES_0402-0.0,5%,1/16W,EMPTY,G21497-005!RES!!!F1643!!SB!!
S!@baseboard_fab2_lib.baseboard_fab2(sch_1):page150_i114@mstr_discrete.res(chips)!RES_0402-0.0,5%,1/16W,EMPTY,G2A!R9E15!//jf4cfls225.pdx.intel.com/apd_proj/ppg_lib/epg_masterlib/logical/mstr_discrete/res/chips/chips.prt!RES!RES_0402-0.0,5%,1/16W,EMPTY,G21497-005!RES!!!F1635!!BMC!!
S!@baseboard_fab2_lib.baseboard_fab2(sch_1):page146_i127@mstr_discrete.res(chips)!RES_0402-0.0,5%,1/16W,EMPTY,G2A!R1T24!//jf4cfls225.pdx.intel.com/apd_proj/ppg_lib/epg_masterlib/logical/mstr_discrete/res/chips/chips.prt!RES!RES_0402-0.0,5%,1/16W,EMPTY,G21497-005!RES!!!F1673!!!!
S!@baseboard_fab2_lib.baseboard_fab2(sch_1):page114_i142@mstr_discrete.res(chips)!RES_0402-0.0,5%,1/16W,EMPTY,G2A!R7C4!//jf4cfls225.pdx.intel.com/apd_proj/ppg_lib/epg_masterlib/logical/mstr_discrete/res/chips/chips.prt!RES!RES_0402-0.0,5%,1/16W,EMPTY,G21497-005!RES!!!F1649!!SB!!
S!@baseboard_fab2_lib.baseboard_fab2(sch_1):page114_i141@mstr_discrete.res(chips)!RES_0402-0.0,5%,1/16W,EMPTY,G2A!R7C2!//jf4cfls225.pdx.intel.com/apd_proj/ppg_lib/epg_masterlib/logical/mstr_discrete/res/chips/chips.prt!RES!RES_0402-0.0,5%,1/16W,EMPTY,G21497-005!RES!!!F1650!!SB!!
S!@baseboard_fab2_lib.baseboard_fab2(sch_1):page156_i279@mstr_discrete.res(chips)!RES_0402-0.0,5%,1/16W,EMPTY,G2A!R8E11!//jf4cfls225.pdx.intel.com/apd_proj/ppg_lib/epg_masterlib/logical/mstr_discrete/res/chips/chips.prt!RES!RES_0402-0.0,5%,1/16W,EMPTY,G21497-005!RES!!!F1642!!BMC_MISC!!
S!@baseboard_fab2_lib.baseboard_fab2(sch_1):page189_i9@mstr_discrete.res(chips)!RES_0402-0.0,5%,1/16W,EMPTY,G2A!R8G9!//jf4cfls225.pdx.intel.com/apd_proj/ppg_lib/epg_masterlib/logical/mstr_discrete/res/chips/chips.prt!RES!RES_0402-0.0,5%,1/16W,EMPTY,G21497-005!RES!!!F1640!!BMC_DEBUG_HEADER!!
S!@baseboard_fab2_lib.baseboard_fab2(sch_1):page200_i198@mstr_discrete.res(chips)!RES_0402-0.0,5%,1/16W,EMPTY,G2A!R9P15!//jf4cfls225.pdx.intel.com/apd_proj/ppg_lib/epg_masterlib/logical/mstr_discrete/res/chips/chips.prt!RES!RES_0402-0.0,5%,1/16W,EMPTY,G21497-005!RES!!!F1630!!HOT_SWAP!!
S!@baseboard_fab2_lib.baseboard_fab2(sch_1):page104_i41@mstr_discrete.res(chips)!RES_0402-0.0,5%,1/16W,EMPTY,G2A!R6F6!//jf4cfls225.pdx.intel.com/apd_proj/ppg_lib/epg_masterlib/logical/mstr_discrete/res/chips/chips.prt!RES!RES_0402-0.0,5%,1/16W,EMPTY,G21497-005!RES!!!F1652!!CLOCK_CPU0_OSC!!
S!@baseboard_fab2_lib.baseboard_fab2(sch_1):page104_i51@mstr_discrete.res(chips)!RES_0402-0.0,5%,1/16W,EMPTY,G2A!R3F1!//jf4cfls225.pdx.intel.com/apd_proj/ppg_lib/epg_masterlib/logical/mstr_discrete/res/chips/chips.prt!RES!RES_0402-0.0,5%,1/16W,EMPTY,G21497-005!RES!!!F1655!!CLOCK_CPU1_OSC!!
S!@baseboard_fab2_lib.baseboard_fab2(sch_1):page104_i37@mstr_discrete.res(chips)!RES_0402-0.0,5%,1/16W,EMPTY,G2A!R6F8!//jf4cfls225.pdx.intel.com/apd_proj/ppg_lib/epg_masterlib/logical/mstr_discrete/res/chips/chips.prt!RES!RES_0402-0.0,5%,1/16W,EMPTY,G21497-005!RES!!!F1651!!CLOCK_CPU0_OSC!!
S!@baseboard_fab2_lib.baseboard_fab2(sch_1):page104_i53@mstr_discrete.res(chips)!RES_0402-0.0,5%,1/16W,EMPTY,G2A!R3F3!//jf4cfls225.pdx.intel.com/apd_proj/ppg_lib/epg_masterlib/logical/mstr_discrete/res/chips/chips.prt!RES!RES_0402-0.0,5%,1/16W,EMPTY,G21497-005!RES!!!F1654!!CLOCK_CPU1_OSC!!
S!@baseboard_fab2_lib.baseboard_fab2(sch_1):page181_i249@mstr_discrete.res(chips)!RES_0402-0.0,5%,1/16W,EMPTY,G2A!R9T8!//jf4cfls225.pdx.intel.com/apd_proj/ppg_lib/epg_masterlib/logical/mstr_discrete/res/chips/chips.prt!RES!RES_0402-0.0,5%,1/16W,EMPTY,G21497-005!RES!!!F1629!!!!
S!@baseboard_fab2_lib.baseboard_fab2(sch_1):page189_i13@mstr_discrete.res(chips)!RES_0402-0.0,5%,1/16W,EMPTY,G2A!R7G18!//jf4cfls225.pdx.intel.com/apd_proj/ppg_lib/epg_masterlib/logical/mstr_discrete/res/chips/chips.prt!RES!RES_0402-0.0,5%,1/16W,EMPTY,G21497-005!RES!!!F1645!!BMC_DEBUG_HEADER!!
S!@baseboard_fab2_lib.baseboard_fab2(sch_1):page189_i19@mstr_discrete.res(chips)!RES_0402-0.0,5%,1/16W,EMPTY,G2A!R8G11!//jf4cfls225.pdx.intel.com/apd_proj/ppg_lib/epg_masterlib/logical/mstr_discrete/res/chips/chips.prt!RES!RES_0402-0.0,5%,1/16W,EMPTY,G21497-005!RES!!!F1639!!BMC_DEBUG_HEADER!!
S!@baseboard_fab2_lib.baseboard_fab2(sch_1):page189_i22@mstr_discrete.res(chips)!RES_0402-0.0,5%,1/16W,EMPTY,G2A!R8G16!//jf4cfls225.pdx.intel.com/apd_proj/ppg_lib/epg_masterlib/logical/mstr_discrete/res/chips/chips.prt!RES!RES_0402-0.0,5%,1/16W,EMPTY,G21497-005!RES!!!F1636!!BMC_DEBUG_HEADER!!
S!@baseboard_fab2_lib.baseboard_fab2(sch_1):page189_i36@mstr_discrete.res(chips)!RES_0402-0.0,5%,1/16W,EMPTY,G2A!R7G15!//jf4cfls225.pdx.intel.com/apd_proj/ppg_lib/epg_masterlib/logical/mstr_discrete/res/chips/chips.prt!RES!RES_0402-0.0,5%,1/16W,EMPTY,G21497-005!RES!!!F1647!!BMC_DEBUG_HEADER!!
S!@baseboard_fab2_lib.baseboard_fab2(sch_1):page89_i23@mstr_discrete.res(chips)!RES_0402-0.0,5%,1/16W,EMPTY,G2A!R2P12!//jf4cfls225.pdx.intel.com/apd_proj/ppg_lib/epg_masterlib/logical/mstr_discrete/res/chips/chips.prt!RES!RES_0402-0.0,5%,1/16W,EMPTY,G21497-005!RES!!!F1672!!NV_DIMM!!
S!@baseboard_fab2_lib.baseboard_fab2(sch_1):page189_i8@mstr_discrete.res(chips)!RES_0402-0.0,5%,1/16W,EMPTY,G2A!R7G19!//jf4cfls225.pdx.intel.com/apd_proj/ppg_lib/epg_masterlib/logical/mstr_discrete/res/chips/chips.prt!RES!RES_0402-0.0,5%,1/16W,EMPTY,G21497-005!RES!!!F1644!!BMC_DEBUG_HEADER!!
S!@baseboard_fab2_lib.baseboard_fab2(sch_1):page189_i21@mstr_discrete.res(chips)!RES_0402-0.0,5%,1/16W,EMPTY,G2A!R8G12!//jf4cfls225.pdx.intel.com/apd_proj/ppg_lib/epg_masterlib/logical/mstr_discrete/res/chips/chips.prt!RES!RES_0402-0.0,5%,1/16W,EMPTY,G21497-005!RES!!!F1638!!BMC_DEBUG_HEADER!!
S!@baseboard_fab2_lib.baseboard_fab2(sch_1):page189_i24@mstr_discrete.res(chips)!RES_0402-0.0,5%,1/16W,EMPTY,G2A!R8G15!//jf4cfls225.pdx.intel.com/apd_proj/ppg_lib/epg_masterlib/logical/mstr_discrete/res/chips/chips.prt!RES!RES_0402-0.0,5%,1/16W,EMPTY,G21497-005!RES!!!F1637!!BMC_DEBUG_HEADER!!
S!@baseboard_fab2_lib.baseboard_fab2(sch_1):page189_i27@mstr_discrete.res(chips)!RES_0402-0.0,5%,1/16W,EMPTY,G2A!R7G16!//jf4cfls225.pdx.intel.com/apd_proj/ppg_lib/epg_masterlib/logical/mstr_discrete/res/chips/chips.prt!RES!RES_0402-0.0,5%,1/16W,EMPTY,G21497-005!RES!!!F1646!!BMC_DEBUG_HEADER!!
S!@baseboard_fab2_lib.baseboard_fab2(sch_1):page142_i18@mstr_discrete.res(chips)!RES_0402-0.0,5%,1/16W,EMPTY,G2A!R8E29!//jf4cfls225.pdx.intel.com/apd_proj/ppg_lib/epg_masterlib/logical/mstr_discrete/res/chips/chips.prt!RES!RES_0402-0.0,5%,1/16W,EMPTY,G21497-005!RES!!!F1641!!PCIE_WAKE_BUFFER!!
S!@baseboard_fab2_lib.baseboard_fab2(sch_1):page144_i516@mstr_discrete.res(chips)!RES_0402-0.0,5%,1/16W,EMPTY,G2A!R9G5!//jf4cfls225.pdx.intel.com/apd_proj/ppg_lib/epg_masterlib/logical/mstr_discrete/res/chips/chips.prt!RES!RES_0402-0.0,5%,1/16W,EMPTY,G21497-005!RES!!!F1632!!BMC!!
S!@baseboard_fab2_lib.baseboard_fab2(sch_1):page144_i517@mstr_discrete.res(chips)!RES_0402-0.0,5%,1/16W,EMPTY,G2A!R9G6!//jf4cfls225.pdx.intel.com/apd_proj/ppg_lib/epg_masterlib/logical/mstr_discrete/res/chips/chips.prt!RES!RES_0402-0.0,5%,1/16W,EMPTY,G21497-005!RES!!!F1631!!BMC!!
S!@baseboard_fab2_lib.baseboard_fab2(sch_1):page145_i183@mstr_discrete.res(chips)!RES_0402-0.0,5%,1/16W,EMPTY,G2A!R1T15!//jf4cfls225.pdx.intel.com/apd_proj/ppg_lib/epg_masterlib/logical/mstr_discrete/res/chips/chips.prt!RES!RES_0402-0.0,5%,1/16W,EMPTY,G21497-005!RES!!!F1675!!BMC!!
S!@baseboard_fab2_lib.baseboard_fab2(sch_1):page145_i184@mstr_discrete.res(chips)!RES_0402-0.0,5%,1/16W,EMPTY,G2A!R1T23!//jf4cfls225.pdx.intel.com/apd_proj/ppg_lib/epg_masterlib/logical/mstr_discrete/res/chips/chips.prt!RES!RES_0402-0.0,5%,1/16W,EMPTY,G21497-005!RES!!!F1674!!BMC!!
S!@baseboard_fab2_lib.baseboard_fab2(sch_1):page158_i100@mstr_discrete.res(chips)!RES_0402-0.0,5%,1/16W,EMPTY,G2A!R9F24!//jf4cfls225.pdx.intel.com/apd_proj/ppg_lib/epg_masterlib/logical/mstr_discrete/res/chips/chips.prt!RES!RES_0402-0.0,5%,1/16W,EMPTY,G21497-005!RES!!!F1634!!UART_MUX!!
S!@baseboard_fab2_lib.baseboard_fab2(sch_1):page158_i99@mstr_discrete.res(chips)!RES_0402-0.0,5%,1/16W,EMPTY,G2A!R9F26!//jf4cfls225.pdx.intel.com/apd_proj/ppg_lib/epg_masterlib/logical/mstr_discrete/res/chips/chips.prt!RES!RES_0402-0.0,5%,1/16W,EMPTY,G21497-005!RES!!!F1633!!UART_MUX!!
S!@baseboard_fab2_lib.baseboard_fab2(sch_1):page89_i1@mstr_discrete.res(chips)!RES_0402-0.0,5%,1/16W,EMPTY,G2A!R4T2!//jf4cfls225.pdx.intel.com/apd_proj/ppg_lib/epg_masterlib/logical/mstr_discrete/res/chips/chips.prt!RES!RES_0402-0.0,5%,1/16W,EMPTY,G21497-005!RES!!!F1653!!NV_DIMM!!
S!@baseboard_fab2_lib.baseboard_fab2(sch_1):page236_i41@mstr_discrete.res(chips)!RES_0402-1.0,1%,1/16W,CHIP,G21A!R3L4!//jf4cfls225.pdx.intel.com/apd_proj/ppg_lib/epg_masterlib/logical/mstr_discrete/res/chips/chips.prt!RES!RES_0402-1.0,1%,1/16W,CHIP,G21796-090!RES!!!F1593!!P1V05_PCH_STBY_VR!!
S!@baseboard_fab2_lib.baseboard_fab2(sch_1):page236_i14@mstr_discrete.res(chips)!RES_0402-1.0,1%,1/16W,CHIP,G21A!R3L1!//jf4cfls225.pdx.intel.com/apd_proj/ppg_lib/epg_masterlib/logical/mstr_discrete/res/chips/chips.prt!RES!RES_0402-1.0,1%,1/16W,CHIP,G21796-090!RES!!!F1594!!PVNN_PCH_STBY!!
S!@baseboard_fab2_lib.baseboard_fab2(sch_1):page212_i32@mstr_discrete.res(chips)!RES_0402-1.0,1%,1/16W,CHIP,G21A!R3N7!//jf4cfls225.pdx.intel.com/apd_proj/ppg_lib/epg_masterlib/logical/mstr_discrete/res/chips/chips.prt!RES!RES_0402-1.0,1%,1/16W,CHIP,G21796-090!RES!!!F1590!!PVCCIO_CPU0!!
S!@baseboard_fab2_lib.baseboard_fab2(sch_1):page214_i71@mstr_discrete.res(chips)!RES_0402-1.0,1%,1/16W,CHIP,G21A!R6R5!//jf4cfls225.pdx.intel.com/apd_proj/ppg_lib/epg_masterlib/logical/mstr_discrete/res/chips/chips.prt!RES!RES_0402-1.0,1%,1/16W,CHIP,G21796-090!RES!!!F1581!!PVCCIO_CPU1!!
S!@baseboard_fab2_lib.baseboard_fab2(sch_1):page203_i38@mstr_discrete.res(chips)!RES_0402-1.0,1%,1/16W,CHIP,G21A!R6P19!//jf4cfls225.pdx.intel.com/apd_proj/ppg_lib/epg_masterlib/logical/mstr_discrete/res/chips/chips.prt!RES!RES_0402-1.0,1%,1/16W,CHIP,G21796-090!RES!!!F1584!!PVCCIN_CPU0_PWR_VR!!
S!@baseboard_fab2_lib.baseboard_fab2(sch_1):page203_i50@mstr_discrete.res(chips)!RES_0402-1.0,1%,1/16W,CHIP,G21A!R6P10!//jf4cfls225.pdx.intel.com/apd_proj/ppg_lib/epg_masterlib/logical/mstr_discrete/res/chips/chips.prt!RES!RES_0402-1.0,1%,1/16W,CHIP,G21796-090!RES!!!F1585!!PVCCIN_CPU0_PWR_VR!!
S!@baseboard_fab2_lib.baseboard_fab2(sch_1):page209_i24@mstr_discrete.res(chips)!RES_0402-1.0,1%,1/16W,CHIP,G21A!R9P32!//jf4cfls225.pdx.intel.com/apd_proj/ppg_lib/epg_masterlib/logical/mstr_discrete/res/chips/chips.prt!RES!RES_0402-1.0,1%,1/16W,CHIP,G21796-090!RES!!!F1577!!PVCCIN_CPU1_PWR_VR!!
S!@baseboard_fab2_lib.baseboard_fab2(sch_1):page202_i39@mstr_discrete.res(chips)!RES_0402-1.0,1%,1/16W,CHIP,G21A!R6R6!//jf4cfls225.pdx.intel.com/apd_proj/ppg_lib/epg_masterlib/logical/mstr_discrete/res/chips/chips.prt!RES!RES_0402-1.0,1%,1/16W,CHIP,G21796-090!RES!!!F1583!!PVCCIN_CPU0_PWR_VR!!
S!@baseboard_fab2_lib.baseboard_fab2(sch_1):page202_i33@mstr_discrete.res(chips)!RES_0402-1.0,1%,1/16W,CHIP,G21A!R6R2!//jf4cfls225.pdx.intel.com/apd_proj/ppg_lib/epg_masterlib/logical/mstr_discrete/res/chips/chips.prt!RES!RES_0402-1.0,1%,1/16W,CHIP,G21796-090!RES!!!F1582!!PVCCIN_CPU0_PWR_VR!!
S!@baseboard_fab2_lib.baseboard_fab2(sch_1):page204_i33@mstr_discrete.res(chips)!RES_0402-1.0,1%,1/16W,CHIP,G21A!R6P47!//jf4cfls225.pdx.intel.com/apd_proj/ppg_lib/epg_masterlib/logical/mstr_discrete/res/chips/chips.prt!RES!RES_0402-1.0,1%,1/16W,CHIP,G21796-090!RES!!!F1586!!PVCCIN_CPU0_PWR_VR!!
S!@baseboard_fab2_lib.baseboard_fab2(sch_1):page216_i52@mstr_discrete.res(chips)!RES_0402-1.0,1%,1/16W,CHIP,G21A!R3U6!//jf4cfls225.pdx.intel.com/apd_proj/ppg_lib/epg_masterlib/logical/mstr_discrete/res/chips/chips.prt!RES!RES_0402-1.0,1%,1/16W,CHIP,G21796-090!RES!!!F1589!!VDDQ_ABC_PWR_VR!!
S!@baseboard_fab2_lib.baseboard_fab2(sch_1):page216_i76@mstr_discrete.res(chips)!RES_0402-1.0,1%,1/16W,CHIP,G21A!R3U9!//jf4cfls225.pdx.intel.com/apd_proj/ppg_lib/epg_masterlib/logical/mstr_discrete/res/chips/chips.prt!RES!RES_0402-1.0,1%,1/16W,CHIP,G21796-090!RES!!!F1588!!VDDQ_ABC_PWR_VR!!
S!@baseboard_fab2_lib.baseboard_fab2(sch_1):page219_i52@mstr_discrete.res(chips)!RES_0402-1.0,1%,1/16W,CHIP,G21A!R3L6!//jf4cfls225.pdx.intel.com/apd_proj/ppg_lib/epg_masterlib/logical/mstr_discrete/res/chips/chips.prt!RES!RES_0402-1.0,1%,1/16W,CHIP,G21796-090!RES!!!F1592!!VDDQ_DEF_PWR_VR!!
S!@baseboard_fab2_lib.baseboard_fab2(sch_1):page219_i76@mstr_discrete.res(chips)!RES_0402-1.0,1%,1/16W,CHIP,G21A!R3L8!//jf4cfls225.pdx.intel.com/apd_proj/ppg_lib/epg_masterlib/logical/mstr_discrete/res/chips/chips.prt!RES!RES_0402-1.0,1%,1/16W,CHIP,G21796-090!RES!!!F1591!!VDDQ_DEF_PWR_VR!!
S!@baseboard_fab2_lib.baseboard_fab2(sch_1):page227_i52@mstr_discrete.res(chips)!RES_0402-1.0,1%,1/16W,CHIP,G21A!R9L9!//jf4cfls225.pdx.intel.com/apd_proj/ppg_lib/epg_masterlib/logical/mstr_discrete/res/chips/chips.prt!RES!RES_0402-1.0,1%,1/16W,CHIP,G21796-090!RES!!!F1579!!VDDQ_KLM_PWR_VR!!
S!@baseboard_fab2_lib.baseboard_fab2(sch_1):page227_i76@mstr_discrete.res(chips)!RES_0402-1.0,1%,1/16W,CHIP,G21A!R9L4!//jf4cfls225.pdx.intel.com/apd_proj/ppg_lib/epg_masterlib/logical/mstr_discrete/res/chips/chips.prt!RES!RES_0402-1.0,1%,1/16W,CHIP,G21796-090!RES!!!F1580!!VDDQ_KLM_PWR_VR!!
S!@baseboard_fab2_lib.baseboard_fab2(sch_1):page205_i19@mstr_discrete.res(chips)!RES_0402-1.0,1%,1/16W,CHIP,G21A!R6N3!//jf4cfls225.pdx.intel.com/apd_proj/ppg_lib/epg_masterlib/logical/mstr_discrete/res/chips/chips.prt!RES!RES_0402-1.0,1%,1/16W,CHIP,G21796-090!RES!!!F1587!!PVSA_CPU0_PWR_VR!!
S!@baseboard_fab2_lib.baseboard_fab2(sch_1):page224_i52@mstr_discrete.res(chips)!RES_0402-1.0,1%,1/16W,CHIP,G21A!R9U1!//jf4cfls225.pdx.intel.com/apd_proj/ppg_lib/epg_masterlib/logical/mstr_discrete/res/chips/chips.prt!RES!RES_0402-1.0,1%,1/16W,CHIP,G21796-090!RES!!!F1571!!VDDQ_GHJ_PWR_VR!!
S!@baseboard_fab2_lib.baseboard_fab2(sch_1):page224_i76@mstr_discrete.res(chips)!RES_0402-1.0,1%,1/16W,CHIP,G21A!R9U12!//jf4cfls225.pdx.intel.com/apd_proj/ppg_lib/epg_masterlib/logical/mstr_discrete/res/chips/chips.prt!RES!RES_0402-1.0,1%,1/16W,CHIP,G21796-090!RES!!!F1572!!VDDQ_GHJ_PWR_VR!!
S!@baseboard_fab2_lib.baseboard_fab2(sch_1):page207_i39@mstr_discrete.res(chips)!RES_0402-1.0,1%,1/16W,CHIP,G21A!R9R11!//jf4cfls225.pdx.intel.com/apd_proj/ppg_lib/epg_masterlib/logical/mstr_discrete/res/chips/chips.prt!RES!RES_0402-1.0,1%,1/16W,CHIP,G21796-090!RES!!!F1574!!PVCCIN_CPU1_PWR_VR!!
S!@baseboard_fab2_lib.baseboard_fab2(sch_1):page207_i26@mstr_discrete.res(chips)!RES_0402-1.0,1%,1/16W,CHIP,G21A!R9R2!//jf4cfls225.pdx.intel.com/apd_proj/ppg_lib/epg_masterlib/logical/mstr_discrete/res/chips/chips.prt!RES!RES_0402-1.0,1%,1/16W,CHIP,G21796-090!RES!!!F1573!!PVCCIN_CPU1_PWR_VR!!
S!@baseboard_fab2_lib.baseboard_fab2(sch_1):page208_i36@mstr_discrete.res(chips)!RES_0402-1.0,1%,1/16W,CHIP,G21A!R9P22!//jf4cfls225.pdx.intel.com/apd_proj/ppg_lib/epg_masterlib/logical/mstr_discrete/res/chips/chips.prt!RES!RES_0402-1.0,1%,1/16W,CHIP,G21796-090!RES!!!F1575!!PVCCIN_CPU1_PWR_VR!!
S!@baseboard_fab2_lib.baseboard_fab2(sch_1):page208_i49@mstr_discrete.res(chips)!RES_0402-1.0,1%,1/16W,CHIP,G21A!R9P8!//jf4cfls225.pdx.intel.com/apd_proj/ppg_lib/epg_masterlib/logical/mstr_discrete/res/chips/chips.prt!RES!RES_0402-1.0,1%,1/16W,CHIP,G21796-090!RES!!!F1576!!PVCCIN_CPU1_PWR_VR!!
S!@baseboard_fab2_lib.baseboard_fab2(sch_1):page210_i20@mstr_discrete.res(chips)!RES_0402-1.0,1%,1/16W,CHIP,G21A!R9N3!//jf4cfls225.pdx.intel.com/apd_proj/ppg_lib/epg_masterlib/logical/mstr_discrete/res/chips/chips.prt!RES!RES_0402-1.0,1%,1/16W,CHIP,G21796-090!RES!!!F1578!!PVSA_CPU1_PWR_VR!!
S!@baseboard_fab2_lib.baseboard_fab2(sch_1):page156_i333@mstr_discrete.res(chips)!RES_0402-1.00K,1%,1/16W,CHIP,GA!R3P56!//jf4cfls225.pdx.intel.com/apd_proj/ppg_lib/epg_masterlib/logical/mstr_discrete/res/chips/chips.prt!RES!RES_0402-1.00K,1%,1/16W,CHIP,G21796-026!RES!!!F1432!!CPU0!!
S!@baseboard_fab2_lib.baseboard_fab2(sch_1):page156_i337@mstr_discrete.res(chips)!RES_0402-1.00K,1%,1/16W,CHIP,GA!R1C36!//jf4cfls225.pdx.intel.com/apd_proj/ppg_lib/epg_masterlib/logical/mstr_discrete/res/chips/chips.prt!RES!RES_0402-1.00K,1%,1/16W,CHIP,G21796-026!RES!!!F1431!!CPU1!!
S!@baseboard_fab2_lib.baseboard_fab2(sch_1):page156_i302@mstr_discrete.res(chips)!RES_0402-1.00K,1%,1/16W,CHIP,GA!R6N14!//jf4cfls225.pdx.intel.com/apd_proj/ppg_lib/epg_masterlib/logical/mstr_discrete/res/chips/chips.prt!RES!RES_0402-1.00K,1%,1/16W,CHIP,G21796-026!RES!!!F1438!!CPU0!!
S!@baseboard_fab2_lib.baseboard_fab2(sch_1):page156_i303@mstr_discrete.res(chips)!RES_0402-1.00K,1%,1/16W,CHIP,GA!R6N13!//jf4cfls225.pdx.intel.com/apd_proj/ppg_lib/epg_masterlib/logical/mstr_discrete/res/chips/chips.prt!RES!RES_0402-1.00K,1%,1/16W,CHIP,G21796-026!RES!!!F1437!!CPU0!!
S!@baseboard_fab2_lib.baseboard_fab2(sch_1):page156_i304@mstr_discrete.res(chips)!RES_0402-1.00K,1%,1/16W,CHIP,GA!R6N15!//jf4cfls225.pdx.intel.com/apd_proj/ppg_lib/epg_masterlib/logical/mstr_discrete/res/chips/chips.prt!RES!RES_0402-1.00K,1%,1/16W,CHIP,G21796-026!RES!!!F1436!!CPU0!!
S!@baseboard_fab2_lib.baseboard_fab2(sch_1):page156_i313@mstr_discrete.res(chips)!RES_0402-1.00K,1%,1/16W,CHIP,GA!R1C33!//jf4cfls225.pdx.intel.com/apd_proj/ppg_lib/epg_masterlib/logical/mstr_discrete/res/chips/chips.prt!RES!RES_0402-1.00K,1%,1/16W,CHIP,G21796-026!RES!!!F1435!!CPU1!!
S!@baseboard_fab2_lib.baseboard_fab2(sch_1):page156_i312@mstr_discrete.res(chips)!RES_0402-1.00K,1%,1/16W,CHIP,GA!R1C32!//jf4cfls225.pdx.intel.com/apd_proj/ppg_lib/epg_masterlib/logical/mstr_discrete/res/chips/chips.prt!RES!RES_0402-1.00K,1%,1/16W,CHIP,G21796-026!RES!!!F1434!!CPU1!!
S!@baseboard_fab2_lib.baseboard_fab2(sch_1):page192_i59@mstr_discrete.res(chips)!RES_0402-1.00K,1%,1/16W,CHIP,GA!R7E20!//jf4cfls225.pdx.intel.com/apd_proj/ppg_lib/epg_masterlib/logical/mstr_discrete/res/chips/chips.prt!RES!RES_0402-1.00K,1%,1/16W,CHIP,G21796-026!RES!!!F1433!!CPLD!!
S!@baseboard_fab2_lib.baseboard_fab2(sch_1):page113_i204@mstr_discrete.res(chips)!RES_0402-1.00K,1%,1/16W,CHIP,GA!R1M20!//jf4cfls225.pdx.intel.com/apd_proj/ppg_lib/epg_masterlib/logical/mstr_discrete/res/chips/chips.prt!RES!RES_0402-1.00K,1%,1/16W,CHIP,G21796-026!RES!!!F1443!!DEBUG!!
S!@baseboard_fab2_lib.baseboard_fab2(sch_1):page113_i202@mstr_discrete.res(chips)!RES_0402-1.00K,1%,1/16W,CHIP,GA!R1M19!//jf4cfls225.pdx.intel.com/apd_proj/ppg_lib/epg_masterlib/logical/mstr_discrete/res/chips/chips.prt!RES!RES_0402-1.00K,1%,1/16W,CHIP,G21796-026!RES!!!F1442!!DEBUG!!
S!@baseboard_fab2_lib.baseboard_fab2(sch_1):page113_i203@mstr_discrete.res(chips)!RES_0402-1.00K,1%,1/16W,CHIP,GA!R9B12!//jf4cfls225.pdx.intel.com/apd_proj/ppg_lib/epg_masterlib/logical/mstr_discrete/res/chips/chips.prt!RES!RES_0402-1.00K,1%,1/16W,CHIP,G21796-026!RES!!!F1441!!DEBUG!!
S!@baseboard_fab2_lib.baseboard_fab2(sch_1):page113_i205@mstr_discrete.res(chips)!RES_0402-1.00K,1%,1/16W,CHIP,GA!R1M21!//jf4cfls225.pdx.intel.com/apd_proj/ppg_lib/epg_masterlib/logical/mstr_discrete/res/chips/chips.prt!RES!RES_0402-1.00K,1%,1/16W,CHIP,G21796-026!RES!!!F1440!!DEBUG!!
S!@baseboard_fab2_lib.baseboard_fab2(sch_1):page113_i179@mstr_discrete.res(chips)!RES_0402-1.00K,1%,1/16W,CHIP,GA!R9B9!//jf4cfls225.pdx.intel.com/apd_proj/ppg_lib/epg_masterlib/logical/mstr_discrete/res/chips/chips.prt!RES!RES_0402-1.00K,1%,1/16W,CHIP,G21796-026!RES!!!F1439!!!!
S!@baseboard_fab2_lib.baseboard_fab2(sch_1):page113_i168@mstr_discrete.res(chips)!RES_0402-1.00K,1%,1/16W,CHIP,GA!R9B14!//jf4cfls225.pdx.intel.com/apd_proj/ppg_lib/epg_masterlib/logical/mstr_discrete/res/chips/chips.prt!RES!RES_0402-1.00K,1%,1/16W,CHIP,G21796-026!RES!!!F1464!!DEBUG!!
S!@baseboard_fab2_lib.baseboard_fab2(sch_1):page157_i326@mstr_discrete.res(chips)!RES_0402-1.00K,1%,1/16W,CHIP,GA!R2T5!//jf4cfls225.pdx.intel.com/apd_proj/ppg_lib/epg_masterlib/logical/mstr_discrete/res/chips/chips.prt!RES!RES_0402-1.00K,1%,1/16W,CHIP,G21796-026!RES!!!F1533!!PROC_SIDEBAND!!
S!@baseboard_fab2_lib.baseboard_fab2(sch_1):page157_i327@mstr_discrete.res(chips)!RES_0402-1.00K,1%,1/16W,CHIP,GA!R2T7!//jf4cfls225.pdx.intel.com/apd_proj/ppg_lib/epg_masterlib/logical/mstr_discrete/res/chips/chips.prt!RES!RES_0402-1.00K,1%,1/16W,CHIP,G21796-026!RES!!!F1532!!PROC_SIDEBAND!!
S!@baseboard_fab2_lib.baseboard_fab2(sch_1):page111_i89@mstr_discrete.res(chips)!RES_0402-1.00K,1%,1/16W,CHIP,GA!R8E2!//jf4cfls225.pdx.intel.com/apd_proj/ppg_lib/epg_masterlib/logical/mstr_discrete/res/chips/chips.prt!RES!RES_0402-1.00K,1%,1/16W,CHIP,G21796-026!RES!!!F1460!!DEBUG!!
S!@baseboard_fab2_lib.baseboard_fab2(sch_1):page157_i368@mstr_discrete.res(chips)!RES_0402-1.00K,1%,1/16W,CHIP,GA!R4R1!//jf4cfls225.pdx.intel.com/apd_proj/ppg_lib/epg_masterlib/logical/mstr_discrete/res/chips/chips.prt!RES!RES_0402-1.00K,1%,1/16W,CHIP,G21796-026!RES!!!F1498!!MIO_CHASSIS!!
S!@baseboard_fab2_lib.baseboard_fab2(sch_1):page183_i12@mstr_discrete.res(chips)!RES_0402-1.00K,1%,1/16W,CHIP,GA!R9F51!//jf4cfls225.pdx.intel.com/apd_proj/ppg_lib/epg_masterlib/logical/mstr_discrete/res/chips/chips.prt!RES!RES_0402-1.00K,1%,1/16W,CHIP,G21796-026!RES!!!F1451!!LBG!!
S!@baseboard_fab2_lib.baseboard_fab2(sch_1):page183_i11@mstr_discrete.res(chips)!RES_0402-1.00K,1%,1/16W,CHIP,GA!R9F50!//jf4cfls225.pdx.intel.com/apd_proj/ppg_lib/epg_masterlib/logical/mstr_discrete/res/chips/chips.prt!RES!RES_0402-1.00K,1%,1/16W,CHIP,G21796-026!RES!!!F1452!!LBG!!
S!@baseboard_fab2_lib.baseboard_fab2(sch_1):page133_i332@mstr_discrete.res(chips)!RES_0402-1.00K,1%,1/16W,CHIP,GA!R7D2!//jf4cfls225.pdx.intel.com/apd_proj/ppg_lib/epg_masterlib/logical/mstr_discrete/res/chips/chips.prt!RES!RES_0402-1.00K,1%,1/16W,CHIP,G21796-026!RES!!!F1481!!SB!!
S!@baseboard_fab2_lib.baseboard_fab2(sch_1):page133_i331@mstr_discrete.res(chips)!RES_0402-1.00K,1%,1/16W,CHIP,GA!R7D7!//jf4cfls225.pdx.intel.com/apd_proj/ppg_lib/epg_masterlib/logical/mstr_discrete/res/chips/chips.prt!RES!RES_0402-1.00K,1%,1/16W,CHIP,G21796-026!RES!!!F1480!!SB!!
S!@baseboard_fab2_lib.baseboard_fab2(sch_1):page189_i44@mstr_discrete.res(chips)!RES_0402-1.00K,1%,1/16W,CHIP,GA!R3R15!//jf4cfls225.pdx.intel.com/apd_proj/ppg_lib/epg_masterlib/logical/mstr_discrete/res/chips/chips.prt!RES!RES_0402-1.00K,1%,1/16W,CHIP,G21796-026!RES!!!F1514!!BMC_DEBUG_HEADER!!
S!@baseboard_fab2_lib.baseboard_fab2(sch_1):page201_i132@mstr_discrete.res(chips)!RES_0402-1.00K,1%,1/16W,CHIP,GA!R6P16!//jf4cfls225.pdx.intel.com/apd_proj/ppg_lib/epg_masterlib/logical/mstr_discrete/res/chips/chips.prt!RES!RES_0402-1.00K,1%,1/16W,CHIP,G21796-026!RES!!!F1491!!BMC!!
S!@baseboard_fab2_lib.baseboard_fab2(sch_1):page206_i120@mstr_discrete.res(chips)!RES_0402-1.00K,1%,1/16W,CHIP,GA!R9N14!//jf4cfls225.pdx.intel.com/apd_proj/ppg_lib/epg_masterlib/logical/mstr_discrete/res/chips/chips.prt!RES!RES_0402-1.00K,1%,1/16W,CHIP,G21796-026!RES!!!F1444!!BMC!!
S!@baseboard_fab2_lib.baseboard_fab2(sch_1):page102_i80@mstr_discrete.res(chips)!RES_0402-1.00K,1%,1/16W,CHIP,GA!R6P21!//jf4cfls225.pdx.intel.com/apd_proj/ppg_lib/epg_masterlib/logical/mstr_discrete/res/chips/chips.prt!RES!RES_0402-1.00K,1%,1/16W,CHIP,G21796-026!RES!!!F1489!!DB1200ZL!!
S!@baseboard_fab2_lib.baseboard_fab2(sch_1):page102_i81@mstr_discrete.res(chips)!RES_0402-1.00K,1%,1/16W,CHIP,GA!R6P20!//jf4cfls225.pdx.intel.com/apd_proj/ppg_lib/epg_masterlib/logical/mstr_discrete/res/chips/chips.prt!RES!RES_0402-1.00K,1%,1/16W,CHIP,G21796-026!RES!!!F1490!!DB1200ZL!!
S!@baseboard_fab2_lib.baseboard_fab2(sch_1):page135_i99@mstr_discrete.res(chips)!RES_0402-1.00K,1%,1/16W,CHIP,GA!R7D18!//jf4cfls225.pdx.intel.com/apd_proj/ppg_lib/epg_masterlib/logical/mstr_discrete/res/chips/chips.prt!RES!RES_0402-1.00K,1%,1/16W,CHIP,G21796-026!RES!!!F1479!!PROC_SIDEBAND!!
S!@baseboard_fab2_lib.baseboard_fab2(sch_1):page92_i75@mstr_discrete.res(chips)!RES_0402-1.00K,1%,1/16W,CHIP,GA!R3R2!//jf4cfls225.pdx.intel.com/apd_proj/ppg_lib/epg_masterlib/logical/mstr_discrete/res/chips/chips.prt!RES!RES_0402-1.00K,1%,1/16W,CHIP,G21796-026!RES!!!F1515!!PROC_SIDEBAND!!
S!@baseboard_fab2_lib.baseboard_fab2(sch_1):page133_i315@mstr_discrete.res(chips)!RES_0402-1.00K,1%,1/16W,CHIP,GA!R3P7!//jf4cfls225.pdx.intel.com/apd_proj/ppg_lib/epg_masterlib/logical/mstr_discrete/res/chips/chips.prt!RES!RES_0402-1.00K,1%,1/16W,CHIP,G21796-026!RES!!!F1523!!SB!!
S!@baseboard_fab2_lib.baseboard_fab2(sch_1):page133_i316@mstr_discrete.res(chips)!RES_0402-1.00K,1%,1/16W,CHIP,GA!R3P5!//jf4cfls225.pdx.intel.com/apd_proj/ppg_lib/epg_masterlib/logical/mstr_discrete/res/chips/chips.prt!RES!RES_0402-1.00K,1%,1/16W,CHIP,G21796-026!RES!!!F1525!!SB!!
S!@baseboard_fab2_lib.baseboard_fab2(sch_1):page133_i317@mstr_discrete.res(chips)!RES_0402-1.00K,1%,1/16W,CHIP,GA!R3P6!//jf4cfls225.pdx.intel.com/apd_proj/ppg_lib/epg_masterlib/logical/mstr_discrete/res/chips/chips.prt!RES!RES_0402-1.00K,1%,1/16W,CHIP,G21796-026!RES!!!F1524!!SB!!
S!@baseboard_fab2_lib.baseboard_fab2(sch_1):page133_i318@mstr_discrete.res(chips)!RES_0402-1.00K,1%,1/16W,CHIP,GA!R3N15!//jf4cfls225.pdx.intel.com/apd_proj/ppg_lib/epg_masterlib/logical/mstr_discrete/res/chips/chips.prt!RES!RES_0402-1.00K,1%,1/16W,CHIP,G21796-026!RES!!!F1527!!SB!!
S!@baseboard_fab2_lib.baseboard_fab2(sch_1):page133_i321@mstr_discrete.res(chips)!RES_0402-1.00K,1%,1/16W,CHIP,GA!R3N16!//jf4cfls225.pdx.intel.com/apd_proj/ppg_lib/epg_masterlib/logical/mstr_discrete/res/chips/chips.prt!RES!RES_0402-1.00K,1%,1/16W,CHIP,G21796-026!RES!!!F1526!!SB!!
S!@baseboard_fab2_lib.baseboard_fab2(sch_1):page133_i322@mstr_discrete.res(chips)!RES_0402-1.00K,1%,1/16W,CHIP,GA!R3P8!//jf4cfls225.pdx.intel.com/apd_proj/ppg_lib/epg_masterlib/logical/mstr_discrete/res/chips/chips.prt!RES!RES_0402-1.00K,1%,1/16W,CHIP,G21796-026!RES!!!F1522!!SB!!
S!@baseboard_fab2_lib.baseboard_fab2(sch_1):page167_i70@mstr_discrete.res(chips)!RES_0402-1.00K,1%,1/16W,CHIP,GA!R8D28!//jf4cfls225.pdx.intel.com/apd_proj/ppg_lib/epg_masterlib/logical/mstr_discrete/res/chips/chips.prt!RES!RES_0402-1.00K,1%,1/16W,CHIP,G21796-026!RES!!!F1461!!TEMP_SENSORS!!
S!@baseboard_fab2_lib.baseboard_fab2(sch_1):page167_i34@mstr_discrete.res(chips)!RES_0402-1.00K,1%,1/16W,CHIP,GA!R1E9!//jf4cfls225.pdx.intel.com/apd_proj/ppg_lib/epg_masterlib/logical/mstr_discrete/res/chips/chips.prt!RES!RES_0402-1.00K,1%,1/16W,CHIP,G21796-026!RES!!!F1564!!TEMP_SENSORS!!
S!@baseboard_fab2_lib.baseboard_fab2(sch_1):page136_i155@mstr_discrete.res(chips)!RES_0402-1.00K,1%,1/16W,CHIP,GA!R7G27!//jf4cfls225.pdx.intel.com/apd_proj/ppg_lib/epg_masterlib/logical/mstr_discrete/res/chips/chips.prt!RES!RES_0402-1.00K,1%,1/16W,CHIP,G21796-026!RES!!!F1478!!SB!!
S!@baseboard_fab2_lib.baseboard_fab2(sch_1):page232_i210@mstr_discrete.res(chips)!RES_0402-1.00K,1%,1/16W,CHIP,GA!R7B17!//jf4cfls225.pdx.intel.com/apd_proj/ppg_lib/epg_masterlib/logical/mstr_discrete/res/chips/chips.prt!RES!RES_0402-1.00K,1%,1/16W,CHIP,G21796-026!RES!!!F1485!!PVPP_KLM_VR!!
S!@baseboard_fab2_lib.baseboard_fab2(sch_1):page233_i185@mstr_discrete.res(chips)!RES_0402-1.00K,1%,1/16W,CHIP,GA!R4G14!//jf4cfls225.pdx.intel.com/apd_proj/ppg_lib/epg_masterlib/logical/mstr_discrete/res/chips/chips.prt!RES!RES_0402-1.00K,1%,1/16W,CHIP,G21796-026!RES!!!F1501!!PVPP_KLM_VR!!
S!@baseboard_fab2_lib.baseboard_fab2(sch_1):page234_i143@mstr_discrete.res(chips)!RES_0402-1.00K,1%,1/16W,CHIP,GA!R4B10!//jf4cfls225.pdx.intel.com/apd_proj/ppg_lib/epg_masterlib/logical/mstr_discrete/res/chips/chips.prt!RES!RES_0402-1.00K,1%,1/16W,CHIP,G21796-026!RES!!!F1513!!PVPP_KLM_VR!!
S!@baseboard_fab2_lib.baseboard_fab2(sch_1):page133_i286@mstr_discrete.res(chips)!RES_0402-1.00K,1%,1/16W,CHIP,GA!R8C4!//jf4cfls225.pdx.intel.com/apd_proj/ppg_lib/epg_masterlib/logical/mstr_discrete/res/chips/chips.prt!RES!RES_0402-1.00K,1%,1/16W,CHIP,G21796-026!RES!!!F1467!!SB!!
S!@baseboard_fab2_lib.baseboard_fab2(sch_1):page133_i280@mstr_discrete.res(chips)!RES_0402-1.00K,1%,1/16W,CHIP,GA!R8B23!//jf4cfls225.pdx.intel.com/apd_proj/ppg_lib/epg_masterlib/logical/mstr_discrete/res/chips/chips.prt!RES!RES_0402-1.00K,1%,1/16W,CHIP,G21796-026!RES!!!F1469!!SB!!
S!@baseboard_fab2_lib.baseboard_fab2(sch_1):page133_i282@mstr_discrete.res(chips)!RES_0402-1.00K,1%,1/16W,CHIP,GA!R8B30!//jf4cfls225.pdx.intel.com/apd_proj/ppg_lib/epg_masterlib/logical/mstr_discrete/res/chips/chips.prt!RES!RES_0402-1.00K,1%,1/16W,CHIP,G21796-026!RES!!!F1468!!SB!!
S!@baseboard_fab2_lib.baseboard_fab2(sch_1):page164_i32@mstr_discrete.res(chips)!RES_0402-1.00K,1%,1/16W,CHIP,GA!R2N18!//jf4cfls225.pdx.intel.com/apd_proj/ppg_lib/epg_masterlib/logical/mstr_discrete/res/chips/chips.prt!RES!RES_0402-1.00K,1%,1/16W,CHIP,G21796-026!RES!!!F1537!!BMC_MISC!!
S!@baseboard_fab2_lib.baseboard_fab2(sch_1):page133_i284@mstr_discrete.res(chips)!RES_0402-1.00K,1%,1/16W,CHIP,GA!R2M4!//jf4cfls225.pdx.intel.com/apd_proj/ppg_lib/epg_masterlib/logical/mstr_discrete/res/chips/chips.prt!RES!RES_0402-1.00K,1%,1/16W,CHIP,G21796-026!RES!!!F1538!!SB!!
S!@baseboard_fab2_lib.baseboard_fab2(sch_1):page231_i143@mstr_discrete.res(chips)!RES_0402-1.00K,1%,1/16W,CHIP,GA!R7F19!//jf4cfls225.pdx.intel.com/apd_proj/ppg_lib/epg_masterlib/logical/mstr_discrete/res/chips/chips.prt!RES!RES_0402-1.00K,1%,1/16W,CHIP,G21796-026!RES!!!F1475!!PVPP_KLM_VR!!
S!@baseboard_fab2_lib.baseboard_fab2(sch_1):page240_i117@mstr_discrete.res(chips)!RES_0402-1.00K,1%,1/16W,CHIP,GA!R8F5!//jf4cfls225.pdx.intel.com/apd_proj/ppg_lib/epg_masterlib/logical/mstr_discrete/res/chips/chips.prt!RES!RES_0402-1.00K,1%,1/16W,CHIP,G21796-026!RES!!!F1458!!PVPP_KLM_VR!!
S!@baseboard_fab2_lib.baseboard_fab2(sch_1):page134_i24@mstr_discrete.res(chips)!RES_0402-1.00K,1%,1/16W,CHIP,GA!R8D21!//jf4cfls225.pdx.intel.com/apd_proj/ppg_lib/epg_masterlib/logical/mstr_discrete/res/chips/chips.prt!RES!RES_0402-1.00K,1%,1/16W,CHIP,G21796-026!RES!!!F1463!!SB!!
S!@baseboard_fab2_lib.baseboard_fab2(sch_1):page173_i266@mstr_discrete.res(chips)!RES_0402-1.00K,1%,1/16W,CHIP,GA!R2L18!//jf4cfls225.pdx.intel.com/apd_proj/ppg_lib/epg_masterlib/logical/mstr_discrete/res/chips/chips.prt!RES!RES_0402-1.00K,1%,1/16W,CHIP,G21796-026!RES!!!F1540!!ST_SATA!!
S!@baseboard_fab2_lib.baseboard_fab2(sch_1):page173_i264@mstr_discrete.res(chips)!RES_0402-1.00K,1%,1/16W,CHIP,GA!R2L22!//jf4cfls225.pdx.intel.com/apd_proj/ppg_lib/epg_masterlib/logical/mstr_discrete/res/chips/chips.prt!RES!RES_0402-1.00K,1%,1/16W,CHIP,G21796-026!RES!!!F1539!!ST_SATA!!
S!@baseboard_fab2_lib.baseboard_fab2(sch_1):page137_i69@mstr_discrete.res(chips)!RES_0402-1.00K,1%,1/16W,CHIP,GA!R1U64!//jf4cfls225.pdx.intel.com/apd_proj/ppg_lib/epg_masterlib/logical/mstr_discrete/res/chips/chips.prt!RES!RES_0402-1.00K,1%,1/16W,CHIP,G21796-026!RES!!!F1484!!SB!!
S!@baseboard_fab2_lib.baseboard_fab2(sch_1):page112_i62@mstr_discrete.res(chips)!RES_0402-1.00K,1%,1/16W,CHIP,GA!R6T5!//jf4cfls225.pdx.intel.com/apd_proj/ppg_lib/epg_masterlib/logical/mstr_discrete/res/chips/chips.prt!RES!RES_0402-1.00K,1%,1/16W,CHIP,G21796-026!RES!!!F1488!!DEBUG!!
S!@baseboard_fab2_lib.baseboard_fab2(sch_1):page136_i102@mstr_discrete.res(chips)!RES_0402-1.00K,1%,1/16W,CHIP,GA!R7G28!//jf4cfls225.pdx.intel.com/apd_proj/ppg_lib/epg_masterlib/logical/mstr_discrete/res/chips/chips.prt!RES!RES_0402-1.00K,1%,1/16W,CHIP,G21796-026!RES!!!F1519!!SB!!
S!@baseboard_fab2_lib.baseboard_fab2(sch_1):page169_i83@mstr_discrete.res(chips)!RES_0402-1.00K,1%,1/16W,CHIP,GA!R1U33!//jf4cfls225.pdx.intel.com/apd_proj/ppg_lib/epg_masterlib/logical/mstr_discrete/res/chips/chips.prt!RES!RES_0402-1.00K,1%,1/16W,CHIP,G21796-026!RES!!!F1541!!BMC_VOLT_MONITOR!!
S!@baseboard_fab2_lib.baseboard_fab2(sch_1):page168_i11@mstr_discrete.res(chips)!RES_0402-1.00K,1%,1/16W,CHIP,GA!R1L36!//jf4cfls225.pdx.intel.com/apd_proj/ppg_lib/epg_masterlib/logical/mstr_discrete/res/chips/chips.prt!RES!RES_0402-1.00K,1%,1/16W,CHIP,G21796-026!RES!!!F1550!!UART_MUX!!
S!@baseboard_fab2_lib.baseboard_fab2(sch_1):page168_i22@mstr_discrete.res(chips)!RES_0402-1.00K,1%,1/16W,CHIP,GA!R1L38!//jf4cfls225.pdx.intel.com/apd_proj/ppg_lib/epg_masterlib/logical/mstr_discrete/res/chips/chips.prt!RES!RES_0402-1.00K,1%,1/16W,CHIP,G21796-026!RES!!!F1549!!UART_MUX!!
S!@baseboard_fab2_lib.baseboard_fab2(sch_1):page168_i10@mstr_discrete.res(chips)!RES_0402-1.00K,1%,1/16W,CHIP,GA!R1L5!//jf4cfls225.pdx.intel.com/apd_proj/ppg_lib/epg_masterlib/logical/mstr_discrete/res/chips/chips.prt!RES!RES_0402-1.00K,1%,1/16W,CHIP,G21796-026!RES!!!F1553!!UART_MUX!!
S!@baseboard_fab2_lib.baseboard_fab2(sch_1):page174_i5@mstr_discrete.res(chips)!RES_0402-1.00K,1%,1/16W,CHIP,GA!R1L3!//jf4cfls225.pdx.intel.com/apd_proj/ppg_lib/epg_masterlib/logical/mstr_discrete/res/chips/chips.prt!RES!RES_0402-1.00K,1%,1/16W,CHIP,G21796-026!RES!!!F1554!!ST_SATA!!
S!@baseboard_fab2_lib.baseboard_fab2(sch_1):page133_i258@mstr_discrete.res(chips)!RES_0402-1.00K,1%,1/16W,CHIP,GA!R2R5!//jf4cfls225.pdx.intel.com/apd_proj/ppg_lib/epg_masterlib/logical/mstr_discrete/res/chips/chips.prt!RES!RES_0402-1.00K,1%,1/16W,CHIP,G21796-026!RES!!!F1535!!SB!!
S!@baseboard_fab2_lib.baseboard_fab2(sch_1):page112_i94@mstr_discrete.res(chips)!RES_0402-1.00K,1%,1/16W,CHIP,GA!R8B2!//jf4cfls225.pdx.intel.com/apd_proj/ppg_lib/epg_masterlib/logical/mstr_discrete/res/chips/chips.prt!RES!RES_0402-1.00K,1%,1/16W,CHIP,G21796-026!RES!!!F1470!!DEBUG!!
S!@baseboard_fab2_lib.baseboard_fab2(sch_1):page112_i85@mstr_discrete.res(chips)!RES_0402-1.00K,1%,1/16W,CHIP,GA!R3M10!//jf4cfls225.pdx.intel.com/apd_proj/ppg_lib/epg_masterlib/logical/mstr_discrete/res/chips/chips.prt!RES!RES_0402-1.00K,1%,1/16W,CHIP,G21796-026!RES!!!F1528!!DEBUG!!
S!@baseboard_fab2_lib.baseboard_fab2(sch_1):page211_i64@mstr_discrete.res(chips)!RES_0402-1.00K,1%,1/16W,CHIP,GA!R3P18!//jf4cfls225.pdx.intel.com/apd_proj/ppg_lib/epg_masterlib/logical/mstr_discrete/res/chips/chips.prt!RES!RES_0402-1.00K,1%,1/16W,CHIP,G21796-026!RES!!!F1521!!!!
S!@baseboard_fab2_lib.baseboard_fab2(sch_1):page213_i63@mstr_discrete.res(chips)!RES_0402-1.00K,1%,1/16W,CHIP,GA!R4D49!//jf4cfls225.pdx.intel.com/apd_proj/ppg_lib/epg_masterlib/logical/mstr_discrete/res/chips/chips.prt!RES!RES_0402-1.00K,1%,1/16W,CHIP,G21796-026!RES!!!F1509!!!!
S!@baseboard_fab2_lib.baseboard_fab2(sch_1):page235_i216@mstr_discrete.res(chips)!RES_0402-1.00K,1%,1/16W,CHIP,GA!R8A5!//jf4cfls225.pdx.intel.com/apd_proj/ppg_lib/epg_masterlib/logical/mstr_discrete/res/chips/chips.prt!RES!RES_0402-1.00K,1%,1/16W,CHIP,G21796-026!RES!!!F1472!!!!
S!@baseboard_fab2_lib.baseboard_fab2(sch_1):page218_i17@mstr_discrete.res(chips)!RES_0402-1.00K,1%,1/16W,CHIP,GA!R7B4!//jf4cfls225.pdx.intel.com/apd_proj/ppg_lib/epg_masterlib/logical/mstr_discrete/res/chips/chips.prt!RES!RES_0402-1.00K,1%,1/16W,CHIP,G21796-026!RES!!!F1487!!VDDQ_DEF_PWR_VR!!
S!@baseboard_fab2_lib.baseboard_fab2(sch_1):page223_i79@mstr_discrete.res(chips)!RES_0402-1.00K,1%,1/16W,CHIP,GA!R1G11!//jf4cfls225.pdx.intel.com/apd_proj/ppg_lib/epg_masterlib/logical/mstr_discrete/res/chips/chips.prt!RES!RES_0402-1.00K,1%,1/16W,CHIP,G21796-026!RES!!!F1558!!RQ_PVDDQ_GHJ_VRHOT_LVT3_N!!
S!@baseboard_fab2_lib.baseboard_fab2(sch_1):page226_i79@mstr_discrete.res(chips)!RES_0402-1.00K,1%,1/16W,CHIP,GA!R1B1!//jf4cfls225.pdx.intel.com/apd_proj/ppg_lib/epg_masterlib/logical/mstr_discrete/res/chips/chips.prt!RES!RES_0402-1.00K,1%,1/16W,CHIP,G21796-026!RES!!!F1570!!RQ_PVDDQ_KLM_VRHOT_LVT3_N!!
S!@baseboard_fab2_lib.baseboard_fab2(sch_1):page215_i303@mstr_discrete.res(chips)!RES_0402-1.00K,1%,1/16W,CHIP,GA!R7F27!//jf4cfls225.pdx.intel.com/apd_proj/ppg_lib/epg_masterlib/logical/mstr_discrete/res/chips/chips.prt!RES!RES_0402-1.00K,1%,1/16W,CHIP,G21796-026!RES!!!F1473!!VDDQ_ABC_PWR_VR!!
S!@baseboard_fab2_lib.baseboard_fab2(sch_1):page235_i149@mstr_discrete.res(chips)!RES_0402-1.00K,1%,1/16W,CHIP,GA!R8A6!//jf4cfls225.pdx.intel.com/apd_proj/ppg_lib/epg_masterlib/logical/mstr_discrete/res/chips/chips.prt!RES!RES_0402-1.00K,1%,1/16W,CHIP,G21796-026!RES!!!F1471!!PVNN_PCH_STBY!!
S!@baseboard_fab2_lib.baseboard_fab2(sch_1):page164_i22@mstr_discrete.res(chips)!RES_0402-1.00K,1%,1/16W,CHIP,GA!R1U15!//jf4cfls225.pdx.intel.com/apd_proj/ppg_lib/epg_masterlib/logical/mstr_discrete/res/chips/chips.prt!RES!RES_0402-1.00K,1%,1/16W,CHIP,G21796-026!RES!!!F1544!!BMC_MISC!!
S!@baseboard_fab2_lib.baseboard_fab2(sch_1):page164_i7@mstr_discrete.res(chips)!RES_0402-1.00K,1%,1/16W,CHIP,GA!R1T11!//jf4cfls225.pdx.intel.com/apd_proj/ppg_lib/epg_masterlib/logical/mstr_discrete/res/chips/chips.prt!RES!RES_0402-1.00K,1%,1/16W,CHIP,G21796-026!RES!!!F1548!!BMC_MISC!!
S!@baseboard_fab2_lib.baseboard_fab2(sch_1):page164_i20@mstr_discrete.res(chips)!RES_0402-1.00K,1%,1/16W,CHIP,GA!R1U16!//jf4cfls225.pdx.intel.com/apd_proj/ppg_lib/epg_masterlib/logical/mstr_discrete/res/chips/chips.prt!RES!RES_0402-1.00K,1%,1/16W,CHIP,G21796-026!RES!!!F1543!!BMC_MISC!!
S!@baseboard_fab2_lib.baseboard_fab2(sch_1):page164_i6@mstr_discrete.res(chips)!RES_0402-1.00K,1%,1/16W,CHIP,GA!R1T12!//jf4cfls225.pdx.intel.com/apd_proj/ppg_lib/epg_masterlib/logical/mstr_discrete/res/chips/chips.prt!RES!RES_0402-1.00K,1%,1/16W,CHIP,G21796-026!RES!!!F1547!!BMC_MISC!!
S!@baseboard_fab2_lib.baseboard_fab2(sch_1):page152_i2@mstr_discrete.res(chips)!RES_0402-1.00K,1%,1/16W,CHIP,GA!R1U30!//jf4cfls225.pdx.intel.com/apd_proj/ppg_lib/epg_masterlib/logical/mstr_discrete/res/chips/chips.prt!RES!RES_0402-1.00K,1%,1/16W,CHIP,G21796-026!RES!!!F1542!!PROC_TRANSLATORS!!
S!@baseboard_fab2_lib.baseboard_fab2(sch_1):page211_i56@mstr_discrete.res(chips)!RES_0402-1.00K,1%,1/16W,CHIP,GA!R3P25!//jf4cfls225.pdx.intel.com/apd_proj/ppg_lib/epg_masterlib/logical/mstr_discrete/res/chips/chips.prt!RES!RES_0402-1.00K,1%,1/16W,CHIP,G21796-026!RES!!!F1520!!PVCCIO_CPU0!!
S!@baseboard_fab2_lib.baseboard_fab2(sch_1):page213_i15@mstr_discrete.res(chips)!RES_0402-1.00K,1%,1/16W,CHIP,GA!R4D42!//jf4cfls225.pdx.intel.com/apd_proj/ppg_lib/epg_masterlib/logical/mstr_discrete/res/chips/chips.prt!RES!RES_0402-1.00K,1%,1/16W,CHIP,G21796-026!RES!!!F1510!!PVCCIO_CPU1!!
S!@baseboard_fab2_lib.baseboard_fab2(sch_1):page96_i71@mstr_discrete.res(chips)!RES_0402-1.00K,1%,1/16W,CHIP,GA!R3P32!//jf4cfls225.pdx.intel.com/apd_proj/ppg_lib/epg_masterlib/logical/mstr_discrete/res/chips/chips.prt!RES!RES_0402-1.00K,1%,1/16W,CHIP,G21796-026!RES!!!F1518!!PROC_RSTS_PGOODS!!
S!@baseboard_fab2_lib.baseboard_fab2(sch_1):page96_i69@mstr_discrete.res(chips)!RES_0402-1.00K,1%,1/16W,CHIP,GA!R4C9!//jf4cfls225.pdx.intel.com/apd_proj/ppg_lib/epg_masterlib/logical/mstr_discrete/res/chips/chips.prt!RES!RES_0402-1.00K,1%,1/16W,CHIP,G21796-026!RES!!!F1511!!PROC_RSTS_PGOODS!!
S!@baseboard_fab2_lib.baseboard_fab2(sch_1):page167_i35@mstr_discrete.res(chips)!RES_0402-1.00K,1%,1/16W,CHIP,GA!R9B6!//jf4cfls225.pdx.intel.com/apd_proj/ppg_lib/epg_masterlib/logical/mstr_discrete/res/chips/chips.prt!RES!RES_0402-1.00K,1%,1/16W,CHIP,G21796-026!RES!!!F1454!!TEMP_SENSORS!!
S!@baseboard_fab2_lib.baseboard_fab2(sch_1):page167_i50@mstr_discrete.res(chips)!RES_0402-1.00K,1%,1/16W,CHIP,GA!R8D27!//jf4cfls225.pdx.intel.com/apd_proj/ppg_lib/epg_masterlib/logical/mstr_discrete/res/chips/chips.prt!RES!RES_0402-1.00K,1%,1/16W,CHIP,G21796-026!RES!!!F1462!!TEMP_SENSORS!!
S!@baseboard_fab2_lib.baseboard_fab2(sch_1):page167_i10@mstr_discrete.res(chips)!RES_0402-1.00K,1%,1/16W,CHIP,GA!R9B8!//jf4cfls225.pdx.intel.com/apd_proj/ppg_lib/epg_masterlib/logical/mstr_discrete/res/chips/chips.prt!RES!RES_0402-1.00K,1%,1/16W,CHIP,G21796-026!RES!!!F1453!!TEMP_SENSORS!!
S!@baseboard_fab2_lib.baseboard_fab2(sch_1):page125_i40@mstr_discrete.res(chips)!RES_0402-1.00K,1%,1/16W,CHIP,GA!R8C18!//jf4cfls225.pdx.intel.com/apd_proj/ppg_lib/epg_masterlib/logical/mstr_discrete/res/chips/chips.prt!RES!RES_0402-1.00K,1%,1/16W,CHIP,G21796-026!RES!!!F1465!!SB!!
S!@baseboard_fab2_lib.baseboard_fab2(sch_1):page125_i15@mstr_discrete.res(chips)!RES_0402-1.00K,1%,1/16W,CHIP,GA!R2T1!//jf4cfls225.pdx.intel.com/apd_proj/ppg_lib/epg_masterlib/logical/mstr_discrete/res/chips/chips.prt!RES!RES_0402-1.00K,1%,1/16W,CHIP,G21796-026!RES!!!F1534!!SB!!
S!@baseboard_fab2_lib.baseboard_fab2(sch_1):page125_i70@mstr_discrete.res(chips)!RES_0402-1.00K,1%,1/16W,CHIP,GA!R7D1!//jf4cfls225.pdx.intel.com/apd_proj/ppg_lib/epg_masterlib/logical/mstr_discrete/res/chips/chips.prt!RES!RES_0402-1.00K,1%,1/16W,CHIP,G21796-026!RES!!!F1482!!SB!!
S!@baseboard_fab2_lib.baseboard_fab2(sch_1):page167_i38@mstr_discrete.res(chips)!RES_0402-1.00K,1%,1/16W,CHIP,GA!R1E10!//jf4cfls225.pdx.intel.com/apd_proj/ppg_lib/epg_masterlib/logical/mstr_discrete/res/chips/chips.prt!RES!RES_0402-1.00K,1%,1/16W,CHIP,G21796-026!RES!!!F1563!!TEMP_SENSORS!!
S!@baseboard_fab2_lib.baseboard_fab2(sch_1):page218_i16@mstr_discrete.res(chips)!RES_0402-1.00K,1%,1/16W,CHIP,GA!R7B5!//jf4cfls225.pdx.intel.com/apd_proj/ppg_lib/epg_masterlib/logical/mstr_discrete/res/chips/chips.prt!RES!RES_0402-1.00K,1%,1/16W,CHIP,G21796-026!RES!!!F1486!!VDDQ_DEF_PWR_VR!!
S!@baseboard_fab2_lib.baseboard_fab2(sch_1):page223_i17@mstr_discrete.res(chips)!RES_0402-1.00K,1%,1/16W,CHIP,GA!R1G16!//jf4cfls225.pdx.intel.com/apd_proj/ppg_lib/epg_masterlib/logical/mstr_discrete/res/chips/chips.prt!RES!RES_0402-1.00K,1%,1/16W,CHIP,G21796-026!RES!!!F1556!!VDDQ_GHJ_PWR_VR!!
S!@baseboard_fab2_lib.baseboard_fab2(sch_1):page226_i17@mstr_discrete.res(chips)!RES_0402-1.00K,1%,1/16W,CHIP,GA!R1B2!//jf4cfls225.pdx.intel.com/apd_proj/ppg_lib/epg_masterlib/logical/mstr_discrete/res/chips/chips.prt!RES!RES_0402-1.00K,1%,1/16W,CHIP,G21796-026!RES!!!F1569!!VDDQ_KLM_PWR_VR!!
S!@baseboard_fab2_lib.baseboard_fab2(sch_1):page241_i11@mstr_discrete.res(chips)!RES_0402-1.00K,1%,1/16W,CHIP,GA!R7E12!//jf4cfls225.pdx.intel.com/apd_proj/ppg_lib/epg_masterlib/logical/mstr_discrete/res/chips/chips.prt!RES!RES_0402-1.00K,1%,1/16W,CHIP,G21796-026!RES!!!F1476!!P5V_STBY_VR!!
S!@baseboard_fab2_lib.baseboard_fab2(sch_1):page93_i127@mstr_discrete.res(chips)!RES_0402-1.00K,1%,1/16W,CHIP,GA!R2T50!//jf4cfls225.pdx.intel.com/apd_proj/ppg_lib/epg_masterlib/logical/mstr_discrete/res/chips/chips.prt!RES!RES_0402-1.00K,1%,1/16W,CHIP,G21796-026!RES!!!F1530!!PROC_SIDEBAND!!
S!@baseboard_fab2_lib.baseboard_fab2(sch_1):page101_i48@mstr_discrete.res(chips)!RES_0402-1.00K,1%,1/16W,CHIP,GA!R2T25!//jf4cfls225.pdx.intel.com/apd_proj/ppg_lib/epg_masterlib/logical/mstr_discrete/res/chips/chips.prt!RES!RES_0402-1.00K,1%,1/16W,CHIP,G21796-026!RES!!!F1531!!SYS_CLOCK!!
S!@baseboard_fab2_lib.baseboard_fab2(sch_1):page100_i19@mstr_discrete.res(chips)!RES_0402-1.00K,1%,1/16W,CHIP,GA!R1G2!//jf4cfls225.pdx.intel.com/apd_proj/ppg_lib/epg_masterlib/logical/mstr_discrete/res/chips/chips.prt!RES!RES_0402-1.00K,1%,1/16W,CHIP,G21796-026!RES!!!F1560!!MEM!!
S!@baseboard_fab2_lib.baseboard_fab2(sch_1):page100_i35@mstr_discrete.res(chips)!RES_0402-1.00K,1%,1/16W,CHIP,GA!R1G15!//jf4cfls225.pdx.intel.com/apd_proj/ppg_lib/epg_masterlib/logical/mstr_discrete/res/chips/chips.prt!RES!RES_0402-1.00K,1%,1/16W,CHIP,G21796-026!RES!!!F1557!!MEM!!
S!@baseboard_fab2_lib.baseboard_fab2(sch_1):page100_i22@mstr_discrete.res(chips)!RES_0402-1.00K,1%,1/16W,CHIP,GA!R9L7!//jf4cfls225.pdx.intel.com/apd_proj/ppg_lib/epg_masterlib/logical/mstr_discrete/res/chips/chips.prt!RES!RES_0402-1.00K,1%,1/16W,CHIP,G21796-026!RES!!!F1447!!MEM!!
S!@baseboard_fab2_lib.baseboard_fab2(sch_1):page100_i38@mstr_discrete.res(chips)!RES_0402-1.00K,1%,1/16W,CHIP,GA!R9L2!//jf4cfls225.pdx.intel.com/apd_proj/ppg_lib/epg_masterlib/logical/mstr_discrete/res/chips/chips.prt!RES!RES_0402-1.00K,1%,1/16W,CHIP,G21796-026!RES!!!F1449!!MEM!!
S!@baseboard_fab2_lib.baseboard_fab2(sch_1):page100_i20@mstr_discrete.res(chips)!RES_0402-1.00K,1%,1/16W,CHIP,GA!R1G3!//jf4cfls225.pdx.intel.com/apd_proj/ppg_lib/epg_masterlib/logical/mstr_discrete/res/chips/chips.prt!RES!RES_0402-1.00K,1%,1/16W,CHIP,G21796-026!RES!!!F1559!!MEM!!
S!@baseboard_fab2_lib.baseboard_fab2(sch_1):page100_i36@mstr_discrete.res(chips)!RES_0402-1.00K,1%,1/16W,CHIP,GA!R1G17!//jf4cfls225.pdx.intel.com/apd_proj/ppg_lib/epg_masterlib/logical/mstr_discrete/res/chips/chips.prt!RES!RES_0402-1.00K,1%,1/16W,CHIP,G21796-026!RES!!!F1555!!MEM!!
S!@baseboard_fab2_lib.baseboard_fab2(sch_1):page100_i24@mstr_discrete.res(chips)!RES_0402-1.00K,1%,1/16W,CHIP,GA!R9L6!//jf4cfls225.pdx.intel.com/apd_proj/ppg_lib/epg_masterlib/logical/mstr_discrete/res/chips/chips.prt!RES!RES_0402-1.00K,1%,1/16W,CHIP,G21796-026!RES!!!F1448!!PROC!!
S!@baseboard_fab2_lib.baseboard_fab2(sch_1):page100_i40@mstr_discrete.res(chips)!RES_0402-1.00K,1%,1/16W,CHIP,GA!R9L1!//jf4cfls225.pdx.intel.com/apd_proj/ppg_lib/epg_masterlib/logical/mstr_discrete/res/chips/chips.prt!RES!RES_0402-1.00K,1%,1/16W,CHIP,G21796-026!RES!!!F1450!!PROC!!
S!@baseboard_fab2_lib.baseboard_fab2(sch_1):page98_i54@mstr_discrete.res(chips)!RES_0402-1.00K,1%,1/16W,CHIP,GA!R6L13!//jf4cfls225.pdx.intel.com/apd_proj/ppg_lib/epg_masterlib/logical/mstr_discrete/res/chips/chips.prt!RES!RES_0402-1.00K,1%,1/16W,CHIP,G21796-026!RES!!!F1494!!MEM!!
S!@baseboard_fab2_lib.baseboard_fab2(sch_1):page98_i38@mstr_discrete.res(chips)!RES_0402-1.00K,1%,1/16W,CHIP,GA!R4G2!//jf4cfls225.pdx.intel.com/apd_proj/ppg_lib/epg_masterlib/logical/mstr_discrete/res/chips/chips.prt!RES!RES_0402-1.00K,1%,1/16W,CHIP,G21796-026!RES!!!F1503!!MEM!!
S!@baseboard_fab2_lib.baseboard_fab2(sch_1):page98_i46@mstr_discrete.res(chips)!RES_0402-1.00K,1%,1/16W,CHIP,GA!R4G21!//jf4cfls225.pdx.intel.com/apd_proj/ppg_lib/epg_masterlib/logical/mstr_discrete/res/chips/chips.prt!RES!RES_0402-1.00K,1%,1/16W,CHIP,G21796-026!RES!!!F1500!!MEM!!
S!@baseboard_fab2_lib.baseboard_fab2(sch_1):page98_i62@mstr_discrete.res(chips)!RES_0402-1.00K,1%,1/16W,CHIP,GA!R6L2!//jf4cfls225.pdx.intel.com/apd_proj/ppg_lib/epg_masterlib/logical/mstr_discrete/res/chips/chips.prt!RES!RES_0402-1.00K,1%,1/16W,CHIP,G21796-026!RES!!!F1496!!MEM!!
S!@baseboard_fab2_lib.baseboard_fab2(sch_1):page98_i56@mstr_discrete.res(chips)!RES_0402-1.00K,1%,1/16W,CHIP,GA!R6L12!//jf4cfls225.pdx.intel.com/apd_proj/ppg_lib/epg_masterlib/logical/mstr_discrete/res/chips/chips.prt!RES!RES_0402-1.00K,1%,1/16W,CHIP,G21796-026!RES!!!F1495!!PROC!!
S!@baseboard_fab2_lib.baseboard_fab2(sch_1):page98_i40@mstr_discrete.res(chips)!RES_0402-1.00K,1%,1/16W,CHIP,GA!R4G3!//jf4cfls225.pdx.intel.com/apd_proj/ppg_lib/epg_masterlib/logical/mstr_discrete/res/chips/chips.prt!RES!RES_0402-1.00K,1%,1/16W,CHIP,G21796-026!RES!!!F1502!!PROC!!
S!@baseboard_fab2_lib.baseboard_fab2(sch_1):page98_i48@mstr_discrete.res(chips)!RES_0402-1.00K,1%,1/16W,CHIP,GA!R4G22!//jf4cfls225.pdx.intel.com/apd_proj/ppg_lib/epg_masterlib/logical/mstr_discrete/res/chips/chips.prt!RES!RES_0402-1.00K,1%,1/16W,CHIP,G21796-026!RES!!!F1499!!PROC!!
S!@baseboard_fab2_lib.baseboard_fab2(sch_1):page98_i64@mstr_discrete.res(chips)!RES_0402-1.00K,1%,1/16W,CHIP,GA!R6L1!//jf4cfls225.pdx.intel.com/apd_proj/ppg_lib/epg_masterlib/logical/mstr_discrete/res/chips/chips.prt!RES!RES_0402-1.00K,1%,1/16W,CHIP,G21796-026!RES!!!F1497!!PROC!!
S!@baseboard_fab2_lib.baseboard_fab2(sch_1):page96_i36@mstr_discrete.res(chips)!RES_0402-1.00K,1%,1/16W,CHIP,GA!R3P36!//jf4cfls225.pdx.intel.com/apd_proj/ppg_lib/epg_masterlib/logical/mstr_discrete/res/chips/chips.prt!RES!RES_0402-1.00K,1%,1/16W,CHIP,G21796-026!RES!!!F1517!!PROC_RSTS_PGOODS!!
S!@baseboard_fab2_lib.baseboard_fab2(sch_1):page96_i55@mstr_discrete.res(chips)!RES_0402-1.00K,1%,1/16W,CHIP,GA!R4C8!//jf4cfls225.pdx.intel.com/apd_proj/ppg_lib/epg_masterlib/logical/mstr_discrete/res/chips/chips.prt!RES!RES_0402-1.00K,1%,1/16W,CHIP,G21796-026!RES!!!F1512!!PROC_RSTS_PGOODS!!
S!@baseboard_fab2_lib.baseboard_fab2(sch_1):page111_i57@mstr_discrete.res(chips)!RES_0402-1.00K,1%,1/16W,CHIP,GA!R9A17!//jf4cfls225.pdx.intel.com/apd_proj/ppg_lib/epg_masterlib/logical/mstr_discrete/res/chips/chips.prt!RES!RES_0402-1.00K,1%,1/16W,CHIP,G21796-026!RES!!!F1455!!DEBUG!!
S!@baseboard_fab2_lib.baseboard_fab2(sch_1):page111_i60@mstr_discrete.res(chips)!RES_0402-1.00K,1%,1/16W,CHIP,GA!R9A15!//jf4cfls225.pdx.intel.com/apd_proj/ppg_lib/epg_masterlib/logical/mstr_discrete/res/chips/chips.prt!RES!RES_0402-1.00K,1%,1/16W,CHIP,G21796-026!RES!!!F1456!!DEBUG!!
S!@baseboard_fab2_lib.baseboard_fab2(sch_1):page111_i37@mstr_discrete.res(chips)!RES_0402-1.00K,1%,1/16W,CHIP,GA!R2P2!//jf4cfls225.pdx.intel.com/apd_proj/ppg_lib/epg_masterlib/logical/mstr_discrete/res/chips/chips.prt!RES!RES_0402-1.00K,1%,1/16W,CHIP,G21796-026!RES!!!F1536!!DEBUG!!
S!@baseboard_fab2_lib.baseboard_fab2(sch_1):page98_i36@mstr_discrete.res(chips)!RES_0402-1.00K,1%,1/16W,CHIP,GA!R4F4!//jf4cfls225.pdx.intel.com/apd_proj/ppg_lib/epg_masterlib/logical/mstr_discrete/res/chips/chips.prt!RES!RES_0402-1.00K,1%,1/16W,CHIP,G21796-026!RES!!!F1505!!MEM!!
S!@baseboard_fab2_lib.baseboard_fab2(sch_1):page100_i11@mstr_discrete.res(chips)!RES_0402-1.00K,1%,1/16W,CHIP,GA!R9M1!//jf4cfls225.pdx.intel.com/apd_proj/ppg_lib/epg_masterlib/logical/mstr_discrete/res/chips/chips.prt!RES!RES_0402-1.00K,1%,1/16W,CHIP,G21796-026!RES!!!F1445!!MEM!!
S!@baseboard_fab2_lib.baseboard_fab2(sch_1):page100_i6@mstr_discrete.res(chips)!RES_0402-1.00K,1%,1/16W,CHIP,GA!R1F5!//jf4cfls225.pdx.intel.com/apd_proj/ppg_lib/epg_masterlib/logical/mstr_discrete/res/chips/chips.prt!RES!RES_0402-1.00K,1%,1/16W,CHIP,G21796-026!RES!!!F1562!!MEM!!
S!@baseboard_fab2_lib.baseboard_fab2(sch_1):page98_i9@mstr_discrete.res(chips)!RES_0402-1.00K,1%,1/16W,CHIP,GA!R6M1!//jf4cfls225.pdx.intel.com/apd_proj/ppg_lib/epg_masterlib/logical/mstr_discrete/res/chips/chips.prt!RES!RES_0402-1.00K,1%,1/16W,CHIP,G21796-026!RES!!!F1492!!MEM!!
S!@baseboard_fab2_lib.baseboard_fab2(sch_1):page111_i6@mstr_discrete.res(chips)!RES_0402-1.00K,1%,1/16W,CHIP,GA!R1L13!//jf4cfls225.pdx.intel.com/apd_proj/ppg_lib/epg_masterlib/logical/mstr_discrete/res/chips/chips.prt!RES!RES_0402-1.00K,1%,1/16W,CHIP,G21796-026!RES!!!F1552!!DEBUG!!
S!@baseboard_fab2_lib.baseboard_fab2(sch_1):page111_i11@mstr_discrete.res(chips)!RES_0402-1.00K,1%,1/16W,CHIP,GA!R9A14!//jf4cfls225.pdx.intel.com/apd_proj/ppg_lib/epg_masterlib/logical/mstr_discrete/res/chips/chips.prt!RES!RES_0402-1.00K,1%,1/16W,CHIP,G21796-026!RES!!!F1457!!DEBUG!!
S!@baseboard_fab2_lib.baseboard_fab2(sch_1):page111_i13@mstr_discrete.res(chips)!RES_0402-1.00K,1%,1/16W,CHIP,GA!R1L23!//jf4cfls225.pdx.intel.com/apd_proj/ppg_lib/epg_masterlib/logical/mstr_discrete/res/chips/chips.prt!RES!RES_0402-1.00K,1%,1/16W,CHIP,G21796-026!RES!!!F1551!!DEBUG!!
S!@baseboard_fab2_lib.baseboard_fab2(sch_1):page196_i46@mstr_discrete.res(chips)!RES_0402-1.00K,1%,1/16W,CHIP,GA!R2U43!//jf4cfls225.pdx.intel.com/apd_proj/ppg_lib/epg_masterlib/logical/mstr_discrete/res/chips/chips.prt!RES!RES_0402-1.00K,1%,1/16W,CHIP,G21796-026!RES!!!F1529!!SB_VRD!!
S!@baseboard_fab2_lib.baseboard_fab2(sch_1):page151_i60@mstr_discrete.res(chips)!RES_0402-1.00K,1%,1/16W,CHIP,GA!R1T30!//jf4cfls225.pdx.intel.com/apd_proj/ppg_lib/epg_masterlib/logical/mstr_discrete/res/chips/chips.prt!RES!RES_0402-1.00K,1%,1/16W,CHIP,G21796-026!RES!!!F1545!!BMC_MEMORY!!
S!@baseboard_fab2_lib.baseboard_fab2(sch_1):page151_i61@mstr_discrete.res(chips)!RES_0402-1.00K,1%,1/16W,CHIP,GA!R1T29!//jf4cfls225.pdx.intel.com/apd_proj/ppg_lib/epg_masterlib/logical/mstr_discrete/res/chips/chips.prt!RES!RES_0402-1.00K,1%,1/16W,CHIP,G21796-026!RES!!!F1546!!BMC_MEMORY!!
S!@baseboard_fab2_lib.baseboard_fab2(sch_1):page136_i148@mstr_discrete.res(chips)!RES_0402-1.00K,1%,1/16W,CHIP,GA!R7G29!//jf4cfls225.pdx.intel.com/apd_proj/ppg_lib/epg_masterlib/logical/mstr_discrete/res/chips/chips.prt!RES!RES_0402-1.00K,1%,1/16W,CHIP,G21796-026!RES!!!F1466!!SB!!
S!@baseboard_fab2_lib.baseboard_fab2(sch_1):page136_i139@mstr_discrete.res(chips)!RES_0402-1.00K,1%,1/16W,CHIP,GA!R7G31!//jf4cfls225.pdx.intel.com/apd_proj/ppg_lib/epg_masterlib/logical/mstr_discrete/res/chips/chips.prt!RES!RES_0402-1.00K,1%,1/16W,CHIP,G21796-026!RES!!!F1459!!SB!!
S!@baseboard_fab2_lib.baseboard_fab2(sch_1):page137_i15@mstr_discrete.res(chips)!RES_0402-1.00K,1%,1/16W,CHIP,GA!R1U63!//jf4cfls225.pdx.intel.com/apd_proj/ppg_lib/epg_masterlib/logical/mstr_discrete/res/chips/chips.prt!RES!RES_0402-1.00K,1%,1/16W,CHIP,G21796-026!RES!!!F1483!!SB!!
S!@baseboard_fab2_lib.baseboard_fab2(sch_1):page100_i2@mstr_discrete.res(chips)!RES_0402-1.00K,1%,1/16W,CHIP,GA!R1F6!//jf4cfls225.pdx.intel.com/apd_proj/ppg_lib/epg_masterlib/logical/mstr_discrete/res/chips/chips.prt!RES!RES_0402-1.00K,1%,1/16W,CHIP,G21796-026!RES!!!F1561!!MEM!!
S!@baseboard_fab2_lib.baseboard_fab2(sch_1):page98_i4@mstr_discrete.res(chips)!RES_0402-1.00K,1%,1/16W,CHIP,GA!R4F5!//jf4cfls225.pdx.intel.com/apd_proj/ppg_lib/epg_masterlib/logical/mstr_discrete/res/chips/chips.prt!RES!RES_0402-1.00K,1%,1/16W,CHIP,G21796-026!RES!!!F1504!!PROC!!
S!@baseboard_fab2_lib.baseboard_fab2(sch_1):page98_i12@mstr_discrete.res(chips)!RES_0402-1.00K,1%,1/16W,CHIP,GA!R6L16!//jf4cfls225.pdx.intel.com/apd_proj/ppg_lib/epg_masterlib/logical/mstr_discrete/res/chips/chips.prt!RES!RES_0402-1.00K,1%,1/16W,CHIP,G21796-026!RES!!!F1493!!PROC!!
S!@baseboard_fab2_lib.baseboard_fab2(sch_1):page100_i4@mstr_discrete.res(chips)!RES_0402-1.00K,1%,1/16W,CHIP,GA!R9L11!//jf4cfls225.pdx.intel.com/apd_proj/ppg_lib/epg_masterlib/logical/mstr_discrete/res/chips/chips.prt!RES!RES_0402-1.00K,1%,1/16W,CHIP,G21796-026!RES!!!F1446!!PROC!!
S!@baseboard_fab2_lib.baseboard_fab2(sch_1):page215_i301@mstr_discrete.res(chips)!RES_0402-1.00K,1%,1/16W,CHIP,GA!R7F22!//jf4cfls225.pdx.intel.com/apd_proj/ppg_lib/epg_masterlib/logical/mstr_discrete/res/chips/chips.prt!RES!RES_0402-1.00K,1%,1/16W,CHIP,G21796-026!RES!!!F1474!!VDDQ_ABC_PWR_VR!!
S!@baseboard_fab2_lib.baseboard_fab2(sch_1):page201_i27@mstr_discrete.res(chips)!RES_0402-1.00K,1%,1/16W,CHIP,GA!R4E5!//jf4cfls225.pdx.intel.com/apd_proj/ppg_lib/epg_masterlib/logical/mstr_discrete/res/chips/chips.prt!RES!RES_0402-1.00K,1%,1/16W,CHIP,G21796-026!RES!!!F1506!!PVCCIN_CPU0_VR!!
S!@baseboard_fab2_lib.baseboard_fab2(sch_1):page201_i25@mstr_discrete.res(chips)!RES_0402-1.00K,1%,1/16W,CHIP,GA!R4D58!//jf4cfls225.pdx.intel.com/apd_proj/ppg_lib/epg_masterlib/logical/mstr_discrete/res/chips/chips.prt!RES!RES_0402-1.00K,1%,1/16W,CHIP,G21796-026!RES!!!F1508!!PVCCIN_CPU0_VR!!
S!@baseboard_fab2_lib.baseboard_fab2(sch_1):page201_i111@mstr_discrete.res(chips)!RES_0402-1.00K,1%,1/16W,CHIP,GA!R4E3!//jf4cfls225.pdx.intel.com/apd_proj/ppg_lib/epg_masterlib/logical/mstr_discrete/res/chips/chips.prt!RES!RES_0402-1.00K,1%,1/16W,CHIP,G21796-026!RES!!!F1507!!PVCCIN_CPU0_VR!!
S!@baseboard_fab2_lib.baseboard_fab2(sch_1):page206_i36@mstr_discrete.res(chips)!RES_0402-1.00K,1%,1/16W,CHIP,GA!R1D8!//jf4cfls225.pdx.intel.com/apd_proj/ppg_lib/epg_masterlib/logical/mstr_discrete/res/chips/chips.prt!RES!RES_0402-1.00K,1%,1/16W,CHIP,G21796-026!RES!!!F1566!!PVCCIN_CPU1_VR!!
S!@baseboard_fab2_lib.baseboard_fab2(sch_1):page206_i35@mstr_discrete.res(chips)!RES_0402-1.00K,1%,1/16W,CHIP,GA!R1C28!//jf4cfls225.pdx.intel.com/apd_proj/ppg_lib/epg_masterlib/logical/mstr_discrete/res/chips/chips.prt!RES!RES_0402-1.00K,1%,1/16W,CHIP,G21796-026!RES!!!F1568!!PVCCIN_CPU1_VR!!
S!@baseboard_fab2_lib.baseboard_fab2(sch_1):page206_i6@mstr_discrete.res(chips)!RES_0402-1.00K,1%,1/16W,CHIP,GA!R1D6!//jf4cfls225.pdx.intel.com/apd_proj/ppg_lib/epg_masterlib/logical/mstr_discrete/res/chips/chips.prt!RES!RES_0402-1.00K,1%,1/16W,CHIP,G21796-026!RES!!!F1567!!PVCCIN_CPU1_VR!!
S!@baseboard_fab2_lib.baseboard_fab2(sch_1):page199_i65@mstr_discrete.res(chips)!RES_0402-1.00K,1%,1/16W,CHIP,GA!R1D36!//jf4cfls225.pdx.intel.com/apd_proj/ppg_lib/epg_masterlib/logical/mstr_discrete/res/chips/chips.prt!RES!RES_0402-1.00K,1%,1/16W,CHIP,G21796-026!RES!!!F1565!!HOT_SWAP!!
S!@baseboard_fab2_lib.baseboard_fab2(sch_1):page92_i54@mstr_discrete.res(chips)!RES_0402-1.00K,1%,1/16W,CHIP,GA!R7D26!//jf4cfls225.pdx.intel.com/apd_proj/ppg_lib/epg_masterlib/logical/mstr_discrete/res/chips/chips.prt!RES!RES_0402-1.00K,1%,1/16W,CHIP,G21796-026!RES!!!F1477!!PROC_SIDEBAND!!
S!@baseboard_fab2_lib.baseboard_fab2(sch_1):page92_i46@mstr_discrete.res(chips)!RES_0402-1.00K,1%,1/16W,CHIP,GA!R3R1!//jf4cfls225.pdx.intel.com/apd_proj/ppg_lib/epg_masterlib/logical/mstr_discrete/res/chips/chips.prt!RES!RES_0402-1.00K,1%,1/16W,CHIP,G21796-026!RES!!!F1516!!PROC_SIDEBAND!!
S!@baseboard_fab2_lib.baseboard_fab2(sch_1):page155_i186@mstr_discrete.res(chips)!RES_0402-10.0,1%,1/16W,CHIP,G2A!R1L2!//jf4cfls225.pdx.intel.com/apd_proj/ppg_lib/epg_masterlib/logical/mstr_discrete/res/chips/chips.prt!RES!RES_0402-10.0,1%,1/16W,CHIP,G21796-066!RES!!!F1367!!BMC_DEBUG_HEADER!!
S!@baseboard_fab2_lib.baseboard_fab2(sch_1):page201_i109@mstr_discrete.res(chips)!RES_0402-10.0,1%,1/16W,CHIP,G2A!R4E8!//jf4cfls225.pdx.intel.com/apd_proj/ppg_lib/epg_masterlib/logical/mstr_discrete/res/chips/chips.prt!RES!RES_0402-10.0,1%,1/16W,CHIP,G21796-066!RES!!!F1352!!PVCCIN_CPU0_VR!!
S!@baseboard_fab2_lib.baseboard_fab2(sch_1):page201_i110@mstr_discrete.res(chips)!RES_0402-10.0,1%,1/16W,CHIP,G2A!R4D39!//jf4cfls225.pdx.intel.com/apd_proj/ppg_lib/epg_masterlib/logical/mstr_discrete/res/chips/chips.prt!RES!RES_0402-10.0,1%,1/16W,CHIP,G21796-066!RES!!!F1354!!PVCCIN_CPU0_VR!!
S!@baseboard_fab2_lib.baseboard_fab2(sch_1):page206_i79@mstr_discrete.res(chips)!RES_0402-10.0,1%,1/16W,CHIP,G2A!R1D4!//jf4cfls225.pdx.intel.com/apd_proj/ppg_lib/epg_masterlib/logical/mstr_discrete/res/chips/chips.prt!RES!RES_0402-10.0,1%,1/16W,CHIP,G21796-066!RES!!!F1374!!PVCCIN_CPU1_VR!!
S!@baseboard_fab2_lib.baseboard_fab2(sch_1):page206_i77@mstr_discrete.res(chips)!RES_0402-10.0,1%,1/16W,CHIP,G2A!R1C21!//jf4cfls225.pdx.intel.com/apd_proj/ppg_lib/epg_masterlib/logical/mstr_discrete/res/chips/chips.prt!RES!RES_0402-10.0,1%,1/16W,CHIP,G21796-066!RES!!!F1375!!PVCCIN_CPU1_VR!!
S!@baseboard_fab2_lib.baseboard_fab2(sch_1):page211_i81@mstr_discrete.res(chips)!RES_0402-10.0,1%,1/16W,CHIP,G2A!R3N19!//jf4cfls225.pdx.intel.com/apd_proj/ppg_lib/epg_masterlib/logical/mstr_discrete/res/chips/chips.prt!RES!RES_0402-10.0,1%,1/16W,CHIP,G21796-066!RES!!!F1357!!PVCCIO_CPU0!!
S!@baseboard_fab2_lib.baseboard_fab2(sch_1):page213_i84@mstr_discrete.res(chips)!RES_0402-10.0,1%,1/16W,CHIP,G2A!R4E7!//jf4cfls225.pdx.intel.com/apd_proj/ppg_lib/epg_masterlib/logical/mstr_discrete/res/chips/chips.prt!RES!RES_0402-10.0,1%,1/16W,CHIP,G21796-066!RES!!!F1353!!PVCCIO_CPU1!!
S!@baseboard_fab2_lib.baseboard_fab2(sch_1):page163_i2@mstr_discrete.res(chips)!RES_0402-10.0,1%,1/16W,CHIP,G2A!R6N8!//jf4cfls225.pdx.intel.com/apd_proj/ppg_lib/epg_masterlib/logical/mstr_discrete/res/chips/chips.prt!RES!RES_0402-10.0,1%,1/16W,CHIP,G21796-066!RES!!!F1349!!CPU1!!
S!@baseboard_fab2_lib.baseboard_fab2(sch_1):page163_i3@mstr_discrete.res(chips)!RES_0402-10.0,1%,1/16W,CHIP,G2A!R6N9!//jf4cfls225.pdx.intel.com/apd_proj/ppg_lib/epg_masterlib/logical/mstr_discrete/res/chips/chips.prt!RES!RES_0402-10.0,1%,1/16W,CHIP,G21796-066!RES!!!F1348!!CPU1!!
S!@baseboard_fab2_lib.baseboard_fab2(sch_1):page200_i154@mstr_discrete.res(chips)!RES_0402-10.0,1%,1/16W,CHIP,G2A!R1D51!//jf4cfls225.pdx.intel.com/apd_proj/ppg_lib/epg_masterlib/logical/mstr_discrete/res/chips/chips.prt!RES!RES_0402-10.0,1%,1/16W,CHIP,G21796-066!RES!!!F1370!!HOT_SWAP!!
S!@baseboard_fab2_lib.baseboard_fab2(sch_1):page236_i93@mstr_discrete.res(chips)!RES_0402-10.0,1%,1/16W,CHIP,G2A!R7A19!//jf4cfls225.pdx.intel.com/apd_proj/ppg_lib/epg_masterlib/logical/mstr_discrete/res/chips/chips.prt!RES!RES_0402-10.0,1%,1/16W,CHIP,G21796-066!RES!!!F1343!!P1V05_PCH_STBY!!
S!@baseboard_fab2_lib.baseboard_fab2(sch_1):page236_i94@mstr_discrete.res(chips)!RES_0402-10.0,1%,1/16W,CHIP,G2A!R7A14!//jf4cfls225.pdx.intel.com/apd_proj/ppg_lib/epg_masterlib/logical/mstr_discrete/res/chips/chips.prt!RES!RES_0402-10.0,1%,1/16W,CHIP,G21796-066!RES!!!F1344!!P1V05_PCH_STBY!!
S!@baseboard_fab2_lib.baseboard_fab2(sch_1):page118_i66@mstr_discrete.res(chips)!RES_0402-10.0,1%,1/16W,CHIP,G2A!R3N9!//jf4cfls225.pdx.intel.com/apd_proj/ppg_lib/epg_masterlib/logical/mstr_discrete/res/chips/chips.prt!RES!RES_0402-10.0,1%,1/16W,CHIP,G21796-066!RES!!!F1358!!SB!!
S!@baseboard_fab2_lib.baseboard_fab2(sch_1):page114_i110@mstr_discrete.res(chips)!RES_0402-10.0,1%,1/16W,CHIP,G2A!R8B20!//jf4cfls225.pdx.intel.com/apd_proj/ppg_lib/epg_masterlib/logical/mstr_discrete/res/chips/chips.prt!RES!RES_0402-10.0,1%,1/16W,CHIP,G21796-066!RES!!!F1338!!SB!!
S!@baseboard_fab2_lib.baseboard_fab2(sch_1):page235_i210@mstr_discrete.res(chips)!RES_0402-10.0,1%,1/16W,CHIP,G2A!R8A1!//jf4cfls225.pdx.intel.com/apd_proj/ppg_lib/epg_masterlib/logical/mstr_discrete/res/chips/chips.prt!RES!RES_0402-10.0,1%,1/16W,CHIP,G21796-066!RES!!!F1339!!PVNN_PCH_STBY!!
S!@baseboard_fab2_lib.baseboard_fab2(sch_1):page218_i60@mstr_discrete.res(chips)!RES_0402-10.0,1%,1/16W,CHIP,G2A!R7A7!//jf4cfls225.pdx.intel.com/apd_proj/ppg_lib/epg_masterlib/logical/mstr_discrete/res/chips/chips.prt!RES!RES_0402-10.0,1%,1/16W,CHIP,G21796-066!RES!!!F1345!!VDDQ_DEF_PWR_VR!!
S!@baseboard_fab2_lib.baseboard_fab2(sch_1):page223_i32@mstr_discrete.res(chips)!RES_0402-10.0,1%,1/16W,CHIP,G2A!R1G5!//jf4cfls225.pdx.intel.com/apd_proj/ppg_lib/epg_masterlib/logical/mstr_discrete/res/chips/chips.prt!RES!RES_0402-10.0,1%,1/16W,CHIP,G21796-066!RES!!!F1368!!VDDQ_GHJ_PWR_VR!!
S!@baseboard_fab2_lib.baseboard_fab2(sch_1):page226_i32@mstr_discrete.res(chips)!RES_0402-10.0,1%,1/16W,CHIP,G2A!R1B16!//jf4cfls225.pdx.intel.com/apd_proj/ppg_lib/epg_masterlib/logical/mstr_discrete/res/chips/chips.prt!RES!RES_0402-10.0,1%,1/16W,CHIP,G21796-066!RES!!!F1376!!VDDQ_KLM_PWR_VR!!
S!@baseboard_fab2_lib.baseboard_fab2(sch_1):page155_i65@mstr_discrete.res(chips)!RES_0402-10.0,1%,1/16W,CHIP,G2A!R1L32!//jf4cfls225.pdx.intel.com/apd_proj/ppg_lib/epg_masterlib/logical/mstr_discrete/res/chips/chips.prt!RES!RES_0402-10.0,1%,1/16W,CHIP,G21796-066!RES!!!F1359!!BMC_DEBUG_HEADER!!
S!@baseboard_fab2_lib.baseboard_fab2(sch_1):page155_i66@mstr_discrete.res(chips)!RES_0402-10.0,1%,1/16W,CHIP,G2A!R1L30!//jf4cfls225.pdx.intel.com/apd_proj/ppg_lib/epg_masterlib/logical/mstr_discrete/res/chips/chips.prt!RES!RES_0402-10.0,1%,1/16W,CHIP,G21796-066!RES!!!F1360!!BMC_DEBUG_HEADER!!
S!@baseboard_fab2_lib.baseboard_fab2(sch_1):page155_i67@mstr_discrete.res(chips)!RES_0402-10.0,1%,1/16W,CHIP,G2A!R1L25!//jf4cfls225.pdx.intel.com/apd_proj/ppg_lib/epg_masterlib/logical/mstr_discrete/res/chips/chips.prt!RES!RES_0402-10.0,1%,1/16W,CHIP,G21796-066!RES!!!F1361!!BMC_DEBUG_HEADER!!
S!@baseboard_fab2_lib.baseboard_fab2(sch_1):page155_i68@mstr_discrete.res(chips)!RES_0402-10.0,1%,1/16W,CHIP,G2A!R1L24!//jf4cfls225.pdx.intel.com/apd_proj/ppg_lib/epg_masterlib/logical/mstr_discrete/res/chips/chips.prt!RES!RES_0402-10.0,1%,1/16W,CHIP,G21796-066!RES!!!F1362!!BMC_DEBUG_HEADER!!
S!@baseboard_fab2_lib.baseboard_fab2(sch_1):page155_i73@mstr_discrete.res(chips)!RES_0402-10.0,1%,1/16W,CHIP,G2A!R1L20!//jf4cfls225.pdx.intel.com/apd_proj/ppg_lib/epg_masterlib/logical/mstr_discrete/res/chips/chips.prt!RES!RES_0402-10.0,1%,1/16W,CHIP,G21796-066!RES!!!F1363!!BMC_DEBUG_HEADER!!
S!@baseboard_fab2_lib.baseboard_fab2(sch_1):page155_i74@mstr_discrete.res(chips)!RES_0402-10.0,1%,1/16W,CHIP,G2A!R1L18!//jf4cfls225.pdx.intel.com/apd_proj/ppg_lib/epg_masterlib/logical/mstr_discrete/res/chips/chips.prt!RES!RES_0402-10.0,1%,1/16W,CHIP,G21796-066!RES!!!F1364!!BMC_DEBUG_HEADER!!
S!@baseboard_fab2_lib.baseboard_fab2(sch_1):page155_i75@mstr_discrete.res(chips)!RES_0402-10.0,1%,1/16W,CHIP,G2A!R1L14!//jf4cfls225.pdx.intel.com/apd_proj/ppg_lib/epg_masterlib/logical/mstr_discrete/res/chips/chips.prt!RES!RES_0402-10.0,1%,1/16W,CHIP,G21796-066!RES!!!F1365!!BMC_DEBUG_HEADER!!
S!@baseboard_fab2_lib.baseboard_fab2(sch_1):page155_i76@mstr_discrete.res(chips)!RES_0402-10.0,1%,1/16W,CHIP,G2A!R1L11!//jf4cfls225.pdx.intel.com/apd_proj/ppg_lib/epg_masterlib/logical/mstr_discrete/res/chips/chips.prt!RES!RES_0402-10.0,1%,1/16W,CHIP,G21796-066!RES!!!F1366!!BMC_DEBUG_HEADER!!
S!@baseboard_fab2_lib.baseboard_fab2(sch_1):page99_i88@mstr_discrete.res(chips)!RES_0402-10.0,1%,1/16W,CHIP,G2A!R3R7!//jf4cfls225.pdx.intel.com/apd_proj/ppg_lib/epg_masterlib/logical/mstr_discrete/res/chips/chips.prt!RES!RES_0402-10.0,1%,1/16W,CHIP,G21796-066!RES!!!F1356!!MEM!!
S!@baseboard_fab2_lib.baseboard_fab2(sch_1):page99_i92@mstr_discrete.res(chips)!RES_0402-10.0,1%,1/16W,CHIP,G2A!R6T3!//jf4cfls225.pdx.intel.com/apd_proj/ppg_lib/epg_masterlib/logical/mstr_discrete/res/chips/chips.prt!RES!RES_0402-10.0,1%,1/16W,CHIP,G21796-066!RES!!!F1347!!MEM!!
S!@baseboard_fab2_lib.baseboard_fab2(sch_1):page99_i83@mstr_discrete.res(chips)!RES_0402-10.0,1%,1/16W,CHIP,G2A!R4T3!//jf4cfls225.pdx.intel.com/apd_proj/ppg_lib/epg_masterlib/logical/mstr_discrete/res/chips/chips.prt!RES!RES_0402-10.0,1%,1/16W,CHIP,G21796-066!RES!!!F1351!!MEM!!
S!@baseboard_fab2_lib.baseboard_fab2(sch_1):page99_i98@mstr_discrete.res(chips)!RES_0402-10.0,1%,1/16W,CHIP,G2A!R7M3!//jf4cfls225.pdx.intel.com/apd_proj/ppg_lib/epg_masterlib/logical/mstr_discrete/res/chips/chips.prt!RES!RES_0402-10.0,1%,1/16W,CHIP,G21796-066!RES!!!F1341!!MEM!!
S!@baseboard_fab2_lib.baseboard_fab2(sch_1):page99_i112@mstr_discrete.res(chips)!RES_0402-10.0,1%,1/16W,CHIP,G2A!R7M8!//jf4cfls225.pdx.intel.com/apd_proj/ppg_lib/epg_masterlib/logical/mstr_discrete/res/chips/chips.prt!RES!RES_0402-10.0,1%,1/16W,CHIP,G21796-066!RES!!!F1340!!MEM!!
S!@baseboard_fab2_lib.baseboard_fab2(sch_1):page99_i110@mstr_discrete.res(chips)!RES_0402-10.0,1%,1/16W,CHIP,G2A!R3R14!//jf4cfls225.pdx.intel.com/apd_proj/ppg_lib/epg_masterlib/logical/mstr_discrete/res/chips/chips.prt!RES!RES_0402-10.0,1%,1/16W,CHIP,G21796-066!RES!!!F1355!!MEM!!
S!@baseboard_fab2_lib.baseboard_fab2(sch_1):page99_i111@mstr_discrete.res(chips)!RES_0402-10.0,1%,1/16W,CHIP,G2A!R6T4!//jf4cfls225.pdx.intel.com/apd_proj/ppg_lib/epg_masterlib/logical/mstr_discrete/res/chips/chips.prt!RES!RES_0402-10.0,1%,1/16W,CHIP,G21796-066!RES!!!F1346!!MEM!!
S!@baseboard_fab2_lib.baseboard_fab2(sch_1):page215_i344@mstr_discrete.res(chips)!RES_0402-10.0,1%,1/16W,CHIP,G2A!R7G9!//jf4cfls225.pdx.intel.com/apd_proj/ppg_lib/epg_masterlib/logical/mstr_discrete/res/chips/chips.prt!RES!RES_0402-10.0,1%,1/16W,CHIP,G21796-066!RES!!!F1342!!VDDQ_ABC_PWR_VR!!
S!@baseboard_fab2_lib.baseboard_fab2(sch_1):page99_i20@mstr_discrete.res(chips)!RES_0402-10.0,1%,1/16W,CHIP,G2A!R4T4!//jf4cfls225.pdx.intel.com/apd_proj/ppg_lib/epg_masterlib/logical/mstr_discrete/res/chips/chips.prt!RES!RES_0402-10.0,1%,1/16W,CHIP,G21796-066!RES!!!F1350!!MEM!!
S!@baseboard_fab2_lib.baseboard_fab2(sch_1):page200_i48@mstr_discrete.res(chips)!RES_0402-10.0,1%,1/16W,CHIP,G2A!R1D46!//jf4cfls225.pdx.intel.com/apd_proj/ppg_lib/epg_masterlib/logical/mstr_discrete/res/chips/chips.prt!RES!RES_0402-10.0,1%,1/16W,CHIP,G21796-066!RES!!!F1373!!HOT_SWAP!!
S!@baseboard_fab2_lib.baseboard_fab2(sch_1):page200_i47@mstr_discrete.res(chips)!RES_0402-10.0,1%,1/16W,CHIP,G2A!R9P27!//jf4cfls225.pdx.intel.com/apd_proj/ppg_lib/epg_masterlib/logical/mstr_discrete/res/chips/chips.prt!RES!RES_0402-10.0,1%,1/16W,CHIP,G21796-066!RES!!!F1336!!HOT_SWAP!!
S!@baseboard_fab2_lib.baseboard_fab2(sch_1):page200_i51@mstr_discrete.res(chips)!RES_0402-10.0,1%,1/16W,CHIP,G2A!R9P26!//jf4cfls225.pdx.intel.com/apd_proj/ppg_lib/epg_masterlib/logical/mstr_discrete/res/chips/chips.prt!RES!RES_0402-10.0,1%,1/16W,CHIP,G21796-066!RES!!!F1337!!HOT_SWAP!!
S!@baseboard_fab2_lib.baseboard_fab2(sch_1):page200_i52@mstr_discrete.res(chips)!RES_0402-10.0,1%,1/16W,CHIP,G2A!R1D47!//jf4cfls225.pdx.intel.com/apd_proj/ppg_lib/epg_masterlib/logical/mstr_discrete/res/chips/chips.prt!RES!RES_0402-10.0,1%,1/16W,CHIP,G21796-066!RES!!!F1372!!HOT_SWAP!!
S!@baseboard_fab2_lib.baseboard_fab2(sch_1):page200_i60@mstr_discrete.res(chips)!RES_0402-10.0,1%,1/16W,CHIP,G2A!R1D48!//jf4cfls225.pdx.intel.com/apd_proj/ppg_lib/epg_masterlib/logical/mstr_discrete/res/chips/chips.prt!RES!RES_0402-10.0,1%,1/16W,CHIP,G21796-066!RES!!!F1371!!HOT_SWAP!!
S!@baseboard_fab2_lib.baseboard_fab2(sch_1):page200_i58@mstr_discrete.res(chips)!RES_0402-10.0,1%,1/16W,CHIP,G2A!R9R4!//jf4cfls225.pdx.intel.com/apd_proj/ppg_lib/epg_masterlib/logical/mstr_discrete/res/chips/chips.prt!RES!RES_0402-10.0,1%,1/16W,CHIP,G21796-066!RES!!!F1335!!HOT_SWAP!!
S!@baseboard_fab2_lib.baseboard_fab2(sch_1):page200_i56@mstr_discrete.res(chips)!RES_0402-10.0,1%,1/16W,CHIP,G2A!R1E1!//jf4cfls225.pdx.intel.com/apd_proj/ppg_lib/epg_masterlib/logical/mstr_discrete/res/chips/chips.prt!RES!RES_0402-10.0,1%,1/16W,CHIP,G21796-066!RES!!!F1369!!HOT_SWAP!!
S!@baseboard_fab2_lib.baseboard_fab2(sch_1):page199_i26@mstr_discrete.res(chips)!RES_0402-100.0,1%,1/16W,EMPTY,A!R1D28!//jf4cfls225.pdx.intel.com/apd_proj/ppg_lib/epg_masterlib/logical/mstr_discrete/res/chips/chips.prt!RES!RES_0402-100.0,1%,1/16W,EMPTY,G21796-017!RES!!!F1167!!HOT_SWAP!!
S!@baseboard_fab2_lib.baseboard_fab2(sch_1):page213_i27@mstr_discrete.res(chips)!RES_0402-100.0,1%,1/16W,EMPTY,A!R6P35!//jf4cfls225.pdx.intel.com/apd_proj/ppg_lib/epg_masterlib/logical/mstr_discrete/res/chips/chips.prt!RES!RES_0402-100.0,1%,1/16W,EMPTY,G21796-017!RES!!!F1162!!PVCCIO_CPU1!!
S!@baseboard_fab2_lib.baseboard_fab2(sch_1):page218_i7@mstr_discrete.res(chips)!RES_0402-100.0,1%,1/16W,EMPTY,A!R3L11!//jf4cfls225.pdx.intel.com/apd_proj/ppg_lib/epg_masterlib/logical/mstr_discrete/res/chips/chips.prt!RES!RES_0402-100.0,1%,1/16W,EMPTY,G21796-017!RES!!!F1166!!VDDQ_DEF_PWR_VR!!
S!@baseboard_fab2_lib.baseboard_fab2(sch_1):page226_i8@mstr_discrete.res(chips)!RES_0402-100.0,1%,1/16W,EMPTY,A!R9M7!//jf4cfls225.pdx.intel.com/apd_proj/ppg_lib/epg_masterlib/logical/mstr_discrete/res/chips/chips.prt!RES!RES_0402-100.0,1%,1/16W,EMPTY,G21796-017!RES!!!F1158!!VDDQ_KLM_PWR_VR!!
S!@baseboard_fab2_lib.baseboard_fab2(sch_1):page211_i17@mstr_discrete.res(chips)!RES_0402-100.0,1%,1/16W,EMPTY,A!R3P13!//jf4cfls225.pdx.intel.com/apd_proj/ppg_lib/epg_masterlib/logical/mstr_discrete/res/chips/chips.prt!RES!RES_0402-100.0,1%,1/16W,EMPTY,G21796-017!RES!!!F1165!!PVCCIO_CPU0!!
S!@baseboard_fab2_lib.baseboard_fab2(sch_1):page236_i57@mstr_discrete.res(chips)!RES_0402-100.0,1%,1/16W,EMPTY,A!R8B15!//jf4cfls225.pdx.intel.com/apd_proj/ppg_lib/epg_masterlib/logical/mstr_discrete/res/chips/chips.prt!RES!RES_0402-100.0,1%,1/16W,EMPTY,G21796-017!RES!!!F1159!!P1V05_PCH_STBY!!
S!@baseboard_fab2_lib.baseboard_fab2(sch_1):page217_i74@mstr_discrete.res(chips)!RES_0402-100.0,1%,1/16W,EMPTY,A!R4U6!//jf4cfls225.pdx.intel.com/apd_proj/ppg_lib/epg_masterlib/logical/mstr_discrete/res/chips/chips.prt!RES!RES_0402-100.0,1%,1/16W,EMPTY,G21796-017!RES!!!F1163!!VDDQ_ABC_PWR_VR!!
S!@baseboard_fab2_lib.baseboard_fab2(sch_1):page220_i74@mstr_discrete.res(chips)!RES_0402-100.0,1%,1/16W,EMPTY,A!R4L2!//jf4cfls225.pdx.intel.com/apd_proj/ppg_lib/epg_masterlib/logical/mstr_discrete/res/chips/chips.prt!RES!RES_0402-100.0,1%,1/16W,EMPTY,G21796-017!RES!!!F1164!!VDDQ_DEF_PWR_VR!!
S!@baseboard_fab2_lib.baseboard_fab2(sch_1):page225_i74@mstr_discrete.res(chips)!RES_0402-100.0,1%,1/16W,EMPTY,A!R7U2!//jf4cfls225.pdx.intel.com/apd_proj/ppg_lib/epg_masterlib/logical/mstr_discrete/res/chips/chips.prt!RES!RES_0402-100.0,1%,1/16W,EMPTY,G21796-017!RES!!!F1160!!VDDQ_GHJ_PWR_VR!!
S!@baseboard_fab2_lib.baseboard_fab2(sch_1):page228_i74@mstr_discrete.res(chips)!RES_0402-100.0,1%,1/16W,EMPTY,A!R7L2!//jf4cfls225.pdx.intel.com/apd_proj/ppg_lib/epg_masterlib/logical/mstr_discrete/res/chips/chips.prt!RES!RES_0402-100.0,1%,1/16W,EMPTY,G21796-017!RES!!!F1161!!VDDQ_KLM_PWR_VR!!
S!@baseboard_fab2_lib.baseboard_fab2(sch_1):page112_i55@mstr_discrete.res(chips)!RES_0402-150.0,1%,1/16W,CHIP,GA!R6T7!//jf4cfls225.pdx.intel.com/apd_proj/ppg_lib/epg_masterlib/logical/mstr_discrete/res/chips/chips.prt!RES!RES_0402-150.0,1%,1/16W,CHIP,G21796-009!RES!!!F1080!!DEBUG!!
S!@baseboard_fab2_lib.baseboard_fab2(sch_1):page112_i56@mstr_discrete.res(chips)!RES_0402-150.0,1%,1/16W,CHIP,GA!R6T6!//jf4cfls225.pdx.intel.com/apd_proj/ppg_lib/epg_masterlib/logical/mstr_discrete/res/chips/chips.prt!RES!RES_0402-150.0,1%,1/16W,CHIP,G21796-009!RES!!!F1081!!DEBUG!!
S!@baseboard_fab2_lib.baseboard_fab2(sch_1):page112_i60@mstr_discrete.res(chips)!RES_0402-150.0,1%,1/16W,CHIP,GA!R1L15!//jf4cfls225.pdx.intel.com/apd_proj/ppg_lib/epg_masterlib/logical/mstr_discrete/res/chips/chips.prt!RES!RES_0402-150.0,1%,1/16W,CHIP,G21796-009!RES!!!F1099!!DEBUG!!
S!@baseboard_fab2_lib.baseboard_fab2(sch_1):page93_i104@mstr_discrete.res(chips)!RES_0402-150.0,1%,1/16W,CHIP,GA!R3P40!//jf4cfls225.pdx.intel.com/apd_proj/ppg_lib/epg_masterlib/logical/mstr_discrete/res/chips/chips.prt!RES!RES_0402-150.0,1%,1/16W,CHIP,G21796-009!RES!!!F1092!!PROC_SIDEBAND!!
S!@baseboard_fab2_lib.baseboard_fab2(sch_1):page93_i80@mstr_discrete.res(chips)!RES_0402-150.0,1%,1/16W,CHIP,GA!R7E1!//jf4cfls225.pdx.intel.com/apd_proj/ppg_lib/epg_masterlib/logical/mstr_discrete/res/chips/chips.prt!RES!RES_0402-150.0,1%,1/16W,CHIP,G21796-009!RES!!!F1078!!PROC_SIDEBAND!!
S!@baseboard_fab2_lib.baseboard_fab2(sch_1):page152_i62@mstr_discrete.res(chips)!RES_0402-150.0,1%,1/16W,CHIP,GA!R7P21!//jf4cfls225.pdx.intel.com/apd_proj/ppg_lib/epg_masterlib/logical/mstr_discrete/res/chips/chips.prt!RES!RES_0402-150.0,1%,1/16W,CHIP,G21796-009!RES!!!F1073!!PROC_SIDEBAND!!
S!@baseboard_fab2_lib.baseboard_fab2(sch_1):page152_i57@mstr_discrete.res(chips)!RES_0402-150.0,1%,1/16W,CHIP,GA!R1U35!//jf4cfls225.pdx.intel.com/apd_proj/ppg_lib/epg_masterlib/logical/mstr_discrete/res/chips/chips.prt!RES!RES_0402-150.0,1%,1/16W,CHIP,G21796-009!RES!!!F1097!!PROC_SIDEBAND!!
S!@baseboard_fab2_lib.baseboard_fab2(sch_1):page152_i61@mstr_discrete.res(chips)!RES_0402-150.0,1%,1/16W,CHIP,GA!R7P5!//jf4cfls225.pdx.intel.com/apd_proj/ppg_lib/epg_masterlib/logical/mstr_discrete/res/chips/chips.prt!RES!RES_0402-150.0,1%,1/16W,CHIP,G21796-009!RES!!!F1076!!PROC_SIDEBAND!!
S!@baseboard_fab2_lib.baseboard_fab2(sch_1):page152_i56@mstr_discrete.res(chips)!RES_0402-150.0,1%,1/16W,CHIP,GA!R1U41!//jf4cfls225.pdx.intel.com/apd_proj/ppg_lib/epg_masterlib/logical/mstr_discrete/res/chips/chips.prt!RES!RES_0402-150.0,1%,1/16W,CHIP,G21796-009!RES!!!F1096!!PROC_SIDEBAND!!
S!@baseboard_fab2_lib.baseboard_fab2(sch_1):page152_i53@mstr_discrete.res(chips)!RES_0402-150.0,1%,1/16W,CHIP,GA!R2U40!//jf4cfls225.pdx.intel.com/apd_proj/ppg_lib/epg_masterlib/logical/mstr_discrete/res/chips/chips.prt!RES!RES_0402-150.0,1%,1/16W,CHIP,G21796-009!RES!!!F1095!!PROC_SIDEBAND!!
S!@baseboard_fab2_lib.baseboard_fab2(sch_1):page152_i54@mstr_discrete.res(chips)!RES_0402-150.0,1%,1/16W,CHIP,GA!R2U41!//jf4cfls225.pdx.intel.com/apd_proj/ppg_lib/epg_masterlib/logical/mstr_discrete/res/chips/chips.prt!RES!RES_0402-150.0,1%,1/16W,CHIP,G21796-009!RES!!!F1094!!PROC_SIDEBAND!!
S!@baseboard_fab2_lib.baseboard_fab2(sch_1):page152_i58@mstr_discrete.res(chips)!RES_0402-150.0,1%,1/16W,CHIP,GA!R4P17!//jf4cfls225.pdx.intel.com/apd_proj/ppg_lib/epg_masterlib/logical/mstr_discrete/res/chips/chips.prt!RES!RES_0402-150.0,1%,1/16W,CHIP,G21796-009!RES!!!F1089!!PROC_SIDEBAND!!
S!@baseboard_fab2_lib.baseboard_fab2(sch_1):page152_i59@mstr_discrete.res(chips)!RES_0402-150.0,1%,1/16W,CHIP,GA!R4P20!//jf4cfls225.pdx.intel.com/apd_proj/ppg_lib/epg_masterlib/logical/mstr_discrete/res/chips/chips.prt!RES!RES_0402-150.0,1%,1/16W,CHIP,G21796-009!RES!!!F1088!!PROC_SIDEBAND!!
S!@baseboard_fab2_lib.baseboard_fab2(sch_1):page93_i106@mstr_discrete.res(chips)!RES_0402-150.0,1%,1/16W,CHIP,GA!R7P28!//jf4cfls225.pdx.intel.com/apd_proj/ppg_lib/epg_masterlib/logical/mstr_discrete/res/chips/chips.prt!RES!RES_0402-150.0,1%,1/16W,CHIP,G21796-009!RES!!!F1071!!PROC_SIDEBAND!!
S!@baseboard_fab2_lib.baseboard_fab2(sch_1):page93_i79@mstr_discrete.res(chips)!RES_0402-150.0,1%,1/16W,CHIP,GA!R4R3!//jf4cfls225.pdx.intel.com/apd_proj/ppg_lib/epg_masterlib/logical/mstr_discrete/res/chips/chips.prt!RES!RES_0402-150.0,1%,1/16W,CHIP,G21796-009!RES!!!F1084!!PROC_SIDEBAND!!
S!@baseboard_fab2_lib.baseboard_fab2(sch_1):page112_i59@mstr_discrete.res(chips)!RES_0402-150.0,1%,1/16W,CHIP,GA!R4P24!//jf4cfls225.pdx.intel.com/apd_proj/ppg_lib/epg_masterlib/logical/mstr_discrete/res/chips/chips.prt!RES!RES_0402-150.0,1%,1/16W,CHIP,G21796-009!RES!!!F1086!!DEBUG!!
S!@baseboard_fab2_lib.baseboard_fab2(sch_1):page112_i58@mstr_discrete.res(chips)!RES_0402-150.0,1%,1/16W,CHIP,GA!R4P23!//jf4cfls225.pdx.intel.com/apd_proj/ppg_lib/epg_masterlib/logical/mstr_discrete/res/chips/chips.prt!RES!RES_0402-150.0,1%,1/16W,CHIP,G21796-009!RES!!!F1087!!DEBUG!!
S!@baseboard_fab2_lib.baseboard_fab2(sch_1):page112_i80@mstr_discrete.res(chips)!RES_0402-150.0,1%,1/16W,CHIP,GA!R8A14!//jf4cfls225.pdx.intel.com/apd_proj/ppg_lib/epg_masterlib/logical/mstr_discrete/res/chips/chips.prt!RES!RES_0402-150.0,1%,1/16W,CHIP,G21796-009!RES!!!F1069!!DEBUG!!
S!@baseboard_fab2_lib.baseboard_fab2(sch_1):page112_i79@mstr_discrete.res(chips)!RES_0402-150.0,1%,1/16W,CHIP,GA!R8A13!//jf4cfls225.pdx.intel.com/apd_proj/ppg_lib/epg_masterlib/logical/mstr_discrete/res/chips/chips.prt!RES!RES_0402-150.0,1%,1/16W,CHIP,G21796-009!RES!!!F1070!!DEBUG!!
S!@baseboard_fab2_lib.baseboard_fab2(sch_1):page112_i78@mstr_discrete.res(chips)!RES_0402-150.0,1%,1/16W,CHIP,GA!R9A11!//jf4cfls225.pdx.intel.com/apd_proj/ppg_lib/epg_masterlib/logical/mstr_discrete/res/chips/chips.prt!RES!RES_0402-150.0,1%,1/16W,CHIP,G21796-009!RES!!!F1068!!DEBUG!!
S!@baseboard_fab2_lib.baseboard_fab2(sch_1):page213_i46@mstr_discrete.res(chips)!RES_0402-150.0,1%,1/16W,CHIP,GA!R4D51!//jf4cfls225.pdx.intel.com/apd_proj/ppg_lib/epg_masterlib/logical/mstr_discrete/res/chips/chips.prt!RES!RES_0402-150.0,1%,1/16W,CHIP,G21796-009!RES!!!F1091!!PVCCIO_CPU1!!
S!@baseboard_fab2_lib.baseboard_fab2(sch_1):page211_i29@mstr_discrete.res(chips)!RES_0402-150.0,1%,1/16W,CHIP,GA!R3P15!//jf4cfls225.pdx.intel.com/apd_proj/ppg_lib/epg_masterlib/logical/mstr_discrete/res/chips/chips.prt!RES!RES_0402-150.0,1%,1/16W,CHIP,G21796-009!RES!!!F1093!!PVCCIO_CPU0!!
S!@baseboard_fab2_lib.baseboard_fab2(sch_1):page218_i48@mstr_discrete.res(chips)!RES_0402-150.0,1%,1/16W,CHIP,GA!R7A17!//jf4cfls225.pdx.intel.com/apd_proj/ppg_lib/epg_masterlib/logical/mstr_discrete/res/chips/chips.prt!RES!RES_0402-150.0,1%,1/16W,CHIP,G21796-009!RES!!!F1079!!VDDQ_DEF_PWR_VR!!
S!@baseboard_fab2_lib.baseboard_fab2(sch_1):page223_i53@mstr_discrete.res(chips)!RES_0402-150.0,1%,1/16W,CHIP,GA!R1G7!//jf4cfls225.pdx.intel.com/apd_proj/ppg_lib/epg_masterlib/logical/mstr_discrete/res/chips/chips.prt!RES!RES_0402-150.0,1%,1/16W,CHIP,G21796-009!RES!!!F1100!!VDDQ_GHJ_PWR_VR!!
S!@baseboard_fab2_lib.baseboard_fab2(sch_1):page226_i53@mstr_discrete.res(chips)!RES_0402-150.0,1%,1/16W,CHIP,GA!R1B8!//jf4cfls225.pdx.intel.com/apd_proj/ppg_lib/epg_masterlib/logical/mstr_discrete/res/chips/chips.prt!RES!RES_0402-150.0,1%,1/16W,CHIP,G21796-009!RES!!!F1102!!VDDQ_KLM_PWR_VR!!
S!@baseboard_fab2_lib.baseboard_fab2(sch_1):page215_i331@mstr_discrete.res(chips)!RES_0402-150.0,1%,1/16W,CHIP,GA!R7G24!//jf4cfls225.pdx.intel.com/apd_proj/ppg_lib/epg_masterlib/logical/mstr_discrete/res/chips/chips.prt!RES!RES_0402-150.0,1%,1/16W,CHIP,G21796-009!RES!!!F1077!!VDDQ_ABC_PWR_VR!!
S!@baseboard_fab2_lib.baseboard_fab2(sch_1):page206_i54@mstr_discrete.res(chips)!RES_0402-150.0,1%,1/16W,CHIP,GA!R1D9!//jf4cfls225.pdx.intel.com/apd_proj/ppg_lib/epg_masterlib/logical/mstr_discrete/res/chips/chips.prt!RES!RES_0402-150.0,1%,1/16W,CHIP,G21796-009!RES!!!F1101!!PVCCIN_CPU1_VR!!
S!@baseboard_fab2_lib.baseboard_fab2(sch_1):page111_i56@mstr_discrete.res(chips)!RES_0402-150.0,1%,1/16W,CHIP,GA!R1L17!//jf4cfls225.pdx.intel.com/apd_proj/ppg_lib/epg_masterlib/logical/mstr_discrete/res/chips/chips.prt!RES!RES_0402-150.0,1%,1/16W,CHIP,G21796-009!RES!!!F1098!!DEBUG!!
S!@baseboard_fab2_lib.baseboard_fab2(sch_1):page92_i101@mstr_discrete.res(chips)!RES_0402-150.0,1%,1/16W,CHIP,GA!R4R2!//jf4cfls225.pdx.intel.com/apd_proj/ppg_lib/epg_masterlib/logical/mstr_discrete/res/chips/chips.prt!RES!RES_0402-150.0,1%,1/16W,CHIP,G21796-009!RES!!!F1085!!PROC_SIDEBAND!!
S!@baseboard_fab2_lib.baseboard_fab2(sch_1):page92_i100@mstr_discrete.res(chips)!RES_0402-150.0,1%,1/16W,CHIP,GA!R7P18!//jf4cfls225.pdx.intel.com/apd_proj/ppg_lib/epg_masterlib/logical/mstr_discrete/res/chips/chips.prt!RES!RES_0402-150.0,1%,1/16W,CHIP,G21796-009!RES!!!F1075!!PROC_SIDEBAND!!
S!@baseboard_fab2_lib.baseboard_fab2(sch_1):page97_i44@mstr_discrete.res(chips)!RES_0402-150.0,1%,1/16W,CHIP,GA!R7P20!//jf4cfls225.pdx.intel.com/apd_proj/ppg_lib/epg_masterlib/logical/mstr_discrete/res/chips/chips.prt!RES!RES_0402-150.0,1%,1/16W,CHIP,G21796-009!RES!!!F1074!!PROC_SIDEBAND!!
S!@baseboard_fab2_lib.baseboard_fab2(sch_1):page201_i56@mstr_discrete.res(chips)!RES_0402-150.0,1%,1/16W,CHIP,GA!R4E6!//jf4cfls225.pdx.intel.com/apd_proj/ppg_lib/epg_masterlib/logical/mstr_discrete/res/chips/chips.prt!RES!RES_0402-150.0,1%,1/16W,CHIP,G21796-009!RES!!!F1090!!PVCCIN_CPU0_VR!!
S!@baseboard_fab2_lib.baseboard_fab2(sch_1):page97_i42@mstr_discrete.res(chips)!RES_0402-150.0,1%,1/16W,CHIP,GA!R4R4!//jf4cfls225.pdx.intel.com/apd_proj/ppg_lib/epg_masterlib/logical/mstr_discrete/res/chips/chips.prt!RES!RES_0402-150.0,1%,1/16W,CHIP,G21796-009!RES!!!F1083!!PROC_SIDEBAND!!
S!@baseboard_fab2_lib.baseboard_fab2(sch_1):page92_i64@mstr_discrete.res(chips)!RES_0402-150.0,1%,1/16W,CHIP,GA!R6D9!//jf4cfls225.pdx.intel.com/apd_proj/ppg_lib/epg_masterlib/logical/mstr_discrete/res/chips/chips.prt!RES!RES_0402-150.0,1%,1/16W,CHIP,G21796-009!RES!!!F1082!!PROC_SIDEBAND!!
S!@baseboard_fab2_lib.baseboard_fab2(sch_1):page92_i65@mstr_discrete.res(chips)!RES_0402-150.0,1%,1/16W,CHIP,GA!R7P27!//jf4cfls225.pdx.intel.com/apd_proj/ppg_lib/epg_masterlib/logical/mstr_discrete/res/chips/chips.prt!RES!RES_0402-150.0,1%,1/16W,CHIP,G21796-009!RES!!!F1072!!PROC_SIDEBAND!!
S!@baseboard_fab2_lib.baseboard_fab2(sch_1):page100_i25@mstr_discrete.res(chips)!RES_0402-2,1.0%,1/16W,CHIP,G21A!R1G1!//jf4cfls225.pdx.intel.com/apd_proj/ppg_lib/epg_masterlib/logical/mstr_discrete/res/chips/chips.prt!RES!RES_0402-2,1.0%,1/16W,CHIP,G21796-274!RES!!!F1061!!PROC!!
S!@baseboard_fab2_lib.baseboard_fab2(sch_1):page100_i41@mstr_discrete.res(chips)!RES_0402-2,1.0%,1/16W,CHIP,G21A!R1G14!//jf4cfls225.pdx.intel.com/apd_proj/ppg_lib/epg_masterlib/logical/mstr_discrete/res/chips/chips.prt!RES!RES_0402-2,1.0%,1/16W,CHIP,G21796-274!RES!!!F1060!!PROC!!
S!@baseboard_fab2_lib.baseboard_fab2(sch_1):page100_i29@mstr_discrete.res(chips)!RES_0402-2,1.0%,1/16W,CHIP,G21A!R9L8!//jf4cfls225.pdx.intel.com/apd_proj/ppg_lib/epg_masterlib/logical/mstr_discrete/res/chips/chips.prt!RES!RES_0402-2,1.0%,1/16W,CHIP,G21796-274!RES!!!F1052!!PROC!!
S!@baseboard_fab2_lib.baseboard_fab2(sch_1):page100_i45@mstr_discrete.res(chips)!RES_0402-2,1.0%,1/16W,CHIP,G21A!R9L3!//jf4cfls225.pdx.intel.com/apd_proj/ppg_lib/epg_masterlib/logical/mstr_discrete/res/chips/chips.prt!RES!RES_0402-2,1.0%,1/16W,CHIP,G21796-274!RES!!!F1053!!PROC!!
S!@baseboard_fab2_lib.baseboard_fab2(sch_1):page98_i58@mstr_discrete.res(chips)!RES_0402-2,1.0%,1/16W,CHIP,G21A!R6L14!//jf4cfls225.pdx.intel.com/apd_proj/ppg_lib/epg_masterlib/logical/mstr_discrete/res/chips/chips.prt!RES!RES_0402-2,1.0%,1/16W,CHIP,G21796-274!RES!!!F1055!!PROC!!
S!@baseboard_fab2_lib.baseboard_fab2(sch_1):page98_i42@mstr_discrete.res(chips)!RES_0402-2,1.0%,1/16W,CHIP,G21A!R4G1!//jf4cfls225.pdx.intel.com/apd_proj/ppg_lib/epg_masterlib/logical/mstr_discrete/res/chips/chips.prt!RES!RES_0402-2,1.0%,1/16W,CHIP,G21796-274!RES!!!F1058!!PROC!!
S!@baseboard_fab2_lib.baseboard_fab2(sch_1):page98_i50@mstr_discrete.res(chips)!RES_0402-2,1.0%,1/16W,CHIP,G21A!R4G20!//jf4cfls225.pdx.intel.com/apd_proj/ppg_lib/epg_masterlib/logical/mstr_discrete/res/chips/chips.prt!RES!RES_0402-2,1.0%,1/16W,CHIP,G21796-274!RES!!!F1057!!PROC!!
S!@baseboard_fab2_lib.baseboard_fab2(sch_1):page98_i66@mstr_discrete.res(chips)!RES_0402-2,1.0%,1/16W,CHIP,G21A!R6L3!//jf4cfls225.pdx.intel.com/apd_proj/ppg_lib/epg_masterlib/logical/mstr_discrete/res/chips/chips.prt!RES!RES_0402-2,1.0%,1/16W,CHIP,G21796-274!RES!!!F1056!!PROC!!
S!@baseboard_fab2_lib.baseboard_fab2(sch_1):page100_i7@mstr_discrete.res(chips)!RES_0402-2,1.0%,1/16W,CHIP,G21A!R1F4!//jf4cfls225.pdx.intel.com/apd_proj/ppg_lib/epg_masterlib/logical/mstr_discrete/res/chips/chips.prt!RES!RES_0402-2,1.0%,1/16W,CHIP,G21796-274!RES!!!F1062!!PROC!!
S!@baseboard_fab2_lib.baseboard_fab2(sch_1):page98_i5@mstr_discrete.res(chips)!RES_0402-2,1.0%,1/16W,CHIP,G21A!R4F3!//jf4cfls225.pdx.intel.com/apd_proj/ppg_lib/epg_masterlib/logical/mstr_discrete/res/chips/chips.prt!RES!RES_0402-2,1.0%,1/16W,CHIP,G21796-274!RES!!!F1059!!PROC!!
S!@baseboard_fab2_lib.baseboard_fab2(sch_1):page100_i13@mstr_discrete.res(chips)!RES_0402-2,1.0%,1/16W,CHIP,G21A!R9M2!//jf4cfls225.pdx.intel.com/apd_proj/ppg_lib/epg_masterlib/logical/mstr_discrete/res/chips/chips.prt!RES!RES_0402-2,1.0%,1/16W,CHIP,G21796-274!RES!!!F1051!!PROC!!
S!@baseboard_fab2_lib.baseboard_fab2(sch_1):page98_i14@mstr_discrete.res(chips)!RES_0402-2,1.0%,1/16W,CHIP,G21A!R6M2!//jf4cfls225.pdx.intel.com/apd_proj/ppg_lib/epg_masterlib/logical/mstr_discrete/res/chips/chips.prt!RES!RES_0402-2,1.0%,1/16W,CHIP,G21796-274!RES!!!F1054!!PROC!!
S!@baseboard_fab2_lib.baseboard_fab2(sch_1):page181_i199@mstr_discrete.res(chips)!RES_0402-2.26K,1.0%,1/16W,CHIPA!R7D5!//jf4cfls225.pdx.intel.com/apd_proj/ppg_lib/epg_masterlib/logical/mstr_discrete/res/chips/chips.prt!RES!RES_0402-2.26K,1.0%,1/16W,CHIP,G21796-311!RES!!!F1013!!IO_SLOT!!
S!@baseboard_fab2_lib.baseboard_fab2(sch_1):page181_i200@mstr_discrete.res(chips)!RES_0402-2.26K,1.0%,1/16W,CHIPA!R7D9!//jf4cfls225.pdx.intel.com/apd_proj/ppg_lib/epg_masterlib/logical/mstr_discrete/res/chips/chips.prt!RES!RES_0402-2.26K,1.0%,1/16W,CHIP,G21796-311!RES!!!F1012!!IO_SLOT!!
S!@baseboard_fab2_lib.baseboard_fab2(sch_1):page181_i201@mstr_discrete.res(chips)!RES_0402-2.26K,1.0%,1/16W,CHIPA!R7D11!//jf4cfls225.pdx.intel.com/apd_proj/ppg_lib/epg_masterlib/logical/mstr_discrete/res/chips/chips.prt!RES!RES_0402-2.26K,1.0%,1/16W,CHIP,G21796-311!RES!!!F1011!!IO_SLOT!!
S!@baseboard_fab2_lib.baseboard_fab2(sch_1):page201_i19@mstr_discrete.res(chips)!RES_0402-2.26K,1.0%,1/16W,CHIPA!R4E4!//jf4cfls225.pdx.intel.com/apd_proj/ppg_lib/epg_masterlib/logical/mstr_discrete/res/chips/chips.prt!RES!RES_0402-2.26K,1.0%,1/16W,CHIP,G21796-311!RES!!!F1014!!PVCCIN_CPU0_VR!!
S!@baseboard_fab2_lib.baseboard_fab2(sch_1):page206_i7@mstr_discrete.res(chips)!RES_0402-2.26K,1.0%,1/16W,CHIPA!R1D7!//jf4cfls225.pdx.intel.com/apd_proj/ppg_lib/epg_masterlib/logical/mstr_discrete/res/chips/chips.prt!RES!RES_0402-2.26K,1.0%,1/16W,CHIP,G21796-311!RES!!!F1015!!PVCCIN_CPU1_VR!!
S!@baseboard_fab2_lib.baseboard_fab2(sch_1):page167_i84@mstr_discrete.res(chips)!RES_0402-20.0,1%,1/16W,CHIP,G2A!R8D24!//jf4cfls225.pdx.intel.com/apd_proj/ppg_lib/epg_masterlib/logical/mstr_discrete/res/chips/chips.prt!RES!RES_0402-20.0,1%,1/16W,CHIP,G21796-173!RES!!!F928!!TEMP_SENSORS!!
S!@baseboard_fab2_lib.baseboard_fab2(sch_1):page167_i85@mstr_discrete.res(chips)!RES_0402-20.0,1%,1/16W,CHIP,G2A!R8D23!//jf4cfls225.pdx.intel.com/apd_proj/ppg_lib/epg_masterlib/logical/mstr_discrete/res/chips/chips.prt!RES!RES_0402-20.0,1%,1/16W,CHIP,G21796-173!RES!!!F929!!TEMP_SENSORS!!
S!@baseboard_fab2_lib.baseboard_fab2(sch_1):page160_i4@mstr_discrete.res(chips)!RES_0402-20.0,1%,1/16W,CHIP,G2A!R1T8!//jf4cfls225.pdx.intel.com/apd_proj/ppg_lib/epg_masterlib/logical/mstr_discrete/res/chips/chips.prt!RES!RES_0402-20.0,1%,1/16W,CHIP,G21796-173!RES!!!F976!!SMBUS!!
S!@baseboard_fab2_lib.baseboard_fab2(sch_1):page160_i50@mstr_discrete.res(chips)!RES_0402-20.0,1%,1/16W,CHIP,G2A!R1T7!//jf4cfls225.pdx.intel.com/apd_proj/ppg_lib/epg_masterlib/logical/mstr_discrete/res/chips/chips.prt!RES!RES_0402-20.0,1%,1/16W,CHIP,G21796-173!RES!!!F977!!SMBUS!!
S!@baseboard_fab2_lib.baseboard_fab2(sch_1):page160_i51@mstr_discrete.res(chips)!RES_0402-20.0,1%,1/16W,CHIP,G2A!R9F23!//jf4cfls225.pdx.intel.com/apd_proj/ppg_lib/epg_masterlib/logical/mstr_discrete/res/chips/chips.prt!RES!RES_0402-20.0,1%,1/16W,CHIP,G21796-173!RES!!!F924!!SMBUS!!
S!@baseboard_fab2_lib.baseboard_fab2(sch_1):page160_i52@mstr_discrete.res(chips)!RES_0402-20.0,1%,1/16W,CHIP,G2A!R9F22!//jf4cfls225.pdx.intel.com/apd_proj/ppg_lib/epg_masterlib/logical/mstr_discrete/res/chips/chips.prt!RES!RES_0402-20.0,1%,1/16W,CHIP,G21796-173!RES!!!F925!!SMBUS!!
S!@baseboard_fab2_lib.baseboard_fab2(sch_1):page108_i330@mstr_discrete.res(chips)!RES_0402-20.0,1%,1/16W,CHIP,G2A!R2U31!//jf4cfls225.pdx.intel.com/apd_proj/ppg_lib/epg_masterlib/logical/mstr_discrete/res/chips/chips.prt!RES!RES_0402-20.0,1%,1/16W,CHIP,G21796-173!RES!!!F961!!SMBUS!!
S!@baseboard_fab2_lib.baseboard_fab2(sch_1):page108_i339@mstr_discrete.res(chips)!RES_0402-20.0,1%,1/16W,CHIP,G2A!R2U32!//jf4cfls225.pdx.intel.com/apd_proj/ppg_lib/epg_masterlib/logical/mstr_discrete/res/chips/chips.prt!RES!RES_0402-20.0,1%,1/16W,CHIP,G21796-173!RES!!!F960!!SMBUS!!
S!@baseboard_fab2_lib.baseboard_fab2(sch_1):page159_i224@mstr_discrete.res(chips)!RES_0402-20.0,1%,1/16W,CHIP,G2A!R9G12!//jf4cfls225.pdx.intel.com/apd_proj/ppg_lib/epg_masterlib/logical/mstr_discrete/res/chips/chips.prt!RES!RES_0402-20.0,1%,1/16W,CHIP,G21796-173!RES!!!F923!!SMBUS!!
S!@baseboard_fab2_lib.baseboard_fab2(sch_1):page159_i225@mstr_discrete.res(chips)!RES_0402-20.0,1%,1/16W,CHIP,G2A!R1U20!//jf4cfls225.pdx.intel.com/apd_proj/ppg_lib/epg_masterlib/logical/mstr_discrete/res/chips/chips.prt!RES!RES_0402-20.0,1%,1/16W,CHIP,G21796-173!RES!!!F972!!SMBUS!!
S!@baseboard_fab2_lib.baseboard_fab2(sch_1):page159_i226@mstr_discrete.res(chips)!RES_0402-20.0,1%,1/16W,CHIP,G2A!R1U19!//jf4cfls225.pdx.intel.com/apd_proj/ppg_lib/epg_masterlib/logical/mstr_discrete/res/chips/chips.prt!RES!RES_0402-20.0,1%,1/16W,CHIP,G21796-173!RES!!!F973!!SMBUS!!
S!@baseboard_fab2_lib.baseboard_fab2(sch_1):page159_i227@mstr_discrete.res(chips)!RES_0402-20.0,1%,1/16W,CHIP,G2A!R9G13!//jf4cfls225.pdx.intel.com/apd_proj/ppg_lib/epg_masterlib/logical/mstr_discrete/res/chips/chips.prt!RES!RES_0402-20.0,1%,1/16W,CHIP,G21796-173!RES!!!F922!!SMBUS!!
S!@baseboard_fab2_lib.baseboard_fab2(sch_1):page167_i58@mstr_discrete.res(chips)!RES_0402-20.0,1%,1/16W,CHIP,G2A!R9G15!//jf4cfls225.pdx.intel.com/apd_proj/ppg_lib/epg_masterlib/logical/mstr_discrete/res/chips/chips.prt!RES!RES_0402-20.0,1%,1/16W,CHIP,G21796-173!RES!!!F920!!SMBUS!!
S!@baseboard_fab2_lib.baseboard_fab2(sch_1):page167_i77@mstr_discrete.res(chips)!RES_0402-20.0,1%,1/16W,CHIP,G2A!R9G14!//jf4cfls225.pdx.intel.com/apd_proj/ppg_lib/epg_masterlib/logical/mstr_discrete/res/chips/chips.prt!RES!RES_0402-20.0,1%,1/16W,CHIP,G21796-173!RES!!!F921!!SMBUS!!
S!@baseboard_fab2_lib.baseboard_fab2(sch_1):page167_i78@mstr_discrete.res(chips)!RES_0402-20.0,1%,1/16W,CHIP,G2A!R1U31!//jf4cfls225.pdx.intel.com/apd_proj/ppg_lib/epg_masterlib/logical/mstr_discrete/res/chips/chips.prt!RES!RES_0402-20.0,1%,1/16W,CHIP,G21796-173!RES!!!F970!!SMBUS!!
S!@baseboard_fab2_lib.baseboard_fab2(sch_1):page167_i79@mstr_discrete.res(chips)!RES_0402-20.0,1%,1/16W,CHIP,G2A!R1U25!//jf4cfls225.pdx.intel.com/apd_proj/ppg_lib/epg_masterlib/logical/mstr_discrete/res/chips/chips.prt!RES!RES_0402-20.0,1%,1/16W,CHIP,G21796-173!RES!!!F971!!SMBUS!!
S!@baseboard_fab2_lib.baseboard_fab2(sch_1):page163_i20@mstr_discrete.res(chips)!RES_0402-20.0,1%,1/16W,CHIP,G2A!R9M14!//jf4cfls225.pdx.intel.com/apd_proj/ppg_lib/epg_masterlib/logical/mstr_discrete/res/chips/chips.prt!RES!RES_0402-20.0,1%,1/16W,CHIP,G21796-173!RES!!!F917!!SMB_PE_HP_CPU1!!
S!@baseboard_fab2_lib.baseboard_fab2(sch_1):page163_i25@mstr_discrete.res(chips)!RES_0402-20.0,1%,1/16W,CHIP,G2A!R9M15!//jf4cfls225.pdx.intel.com/apd_proj/ppg_lib/epg_masterlib/logical/mstr_discrete/res/chips/chips.prt!RES!RES_0402-20.0,1%,1/16W,CHIP,G21796-173!RES!!!F916!!SMB_PE_HP_CPU1!!
S!@baseboard_fab2_lib.baseboard_fab2(sch_1):page163_i21@mstr_discrete.res(chips)!RES_0402-20.0,1%,1/16W,CHIP,G2A!R9M13!//jf4cfls225.pdx.intel.com/apd_proj/ppg_lib/epg_masterlib/logical/mstr_discrete/res/chips/chips.prt!RES!RES_0402-20.0,1%,1/16W,CHIP,G21796-173!RES!!!F918!!SMB_PE_HP_CPU1!!
S!@baseboard_fab2_lib.baseboard_fab2(sch_1):page163_i24@mstr_discrete.res(chips)!RES_0402-20.0,1%,1/16W,CHIP,G2A!R9M12!//jf4cfls225.pdx.intel.com/apd_proj/ppg_lib/epg_masterlib/logical/mstr_discrete/res/chips/chips.prt!RES!RES_0402-20.0,1%,1/16W,CHIP,G21796-173!RES!!!F919!!SMB_PE_HP_CPU1!!
S!@baseboard_fab2_lib.baseboard_fab2(sch_1):page138_i116@mstr_discrete.res(chips)!RES_0402-20.0,1%,1/16W,CHIP,G2A!R2T55!//jf4cfls225.pdx.intel.com/apd_proj/ppg_lib/epg_masterlib/logical/mstr_discrete/res/chips/chips.prt!RES!RES_0402-20.0,1%,1/16W,CHIP,G21796-173!RES!!!F968!!SMBUS!!
S!@baseboard_fab2_lib.baseboard_fab2(sch_1):page138_i160@mstr_discrete.res(chips)!RES_0402-20.0,1%,1/16W,CHIP,G2A!R2T56!//jf4cfls225.pdx.intel.com/apd_proj/ppg_lib/epg_masterlib/logical/mstr_discrete/res/chips/chips.prt!RES!RES_0402-20.0,1%,1/16W,CHIP,G21796-173!RES!!!F967!!SMBUS!!
S!@baseboard_fab2_lib.baseboard_fab2(sch_1):page138_i169@mstr_discrete.res(chips)!RES_0402-20.0,1%,1/16W,CHIP,G2A!R8C11!//jf4cfls225.pdx.intel.com/apd_proj/ppg_lib/epg_masterlib/logical/mstr_discrete/res/chips/chips.prt!RES!RES_0402-20.0,1%,1/16W,CHIP,G21796-173!RES!!!F937!!SMBUS!!
S!@baseboard_fab2_lib.baseboard_fab2(sch_1):page138_i170@mstr_discrete.res(chips)!RES_0402-20.0,1%,1/16W,CHIP,G2A!R8C12!//jf4cfls225.pdx.intel.com/apd_proj/ppg_lib/epg_masterlib/logical/mstr_discrete/res/chips/chips.prt!RES!RES_0402-20.0,1%,1/16W,CHIP,G21796-173!RES!!!F936!!SMBUS!!
S!@baseboard_fab2_lib.baseboard_fab2(sch_1):page138_i167@mstr_discrete.res(chips)!RES_0402-20.0,1%,1/16W,CHIP,G2A!R8C20!//jf4cfls225.pdx.intel.com/apd_proj/ppg_lib/epg_masterlib/logical/mstr_discrete/res/chips/chips.prt!RES!RES_0402-20.0,1%,1/16W,CHIP,G21796-173!RES!!!F934!!SMBUS!!
S!@baseboard_fab2_lib.baseboard_fab2(sch_1):page138_i168@mstr_discrete.res(chips)!RES_0402-20.0,1%,1/16W,CHIP,G2A!R8C14!//jf4cfls225.pdx.intel.com/apd_proj/ppg_lib/epg_masterlib/logical/mstr_discrete/res/chips/chips.prt!RES!RES_0402-20.0,1%,1/16W,CHIP,G21796-173!RES!!!F935!!SMBUS!!
S!@baseboard_fab2_lib.baseboard_fab2(sch_1):page211_i46@mstr_discrete.res(chips)!RES_0402-20.0,1%,1/16W,CHIP,G2A!R3P24!//jf4cfls225.pdx.intel.com/apd_proj/ppg_lib/epg_masterlib/logical/mstr_discrete/res/chips/chips.prt!RES!RES_0402-20.0,1%,1/16W,CHIP,G21796-173!RES!!!F956!!PVCCIO_CPU0!!
S!@baseboard_fab2_lib.baseboard_fab2(sch_1):page215_i298@mstr_discrete.res(chips)!RES_0402-20.0,1%,1/16W,CHIP,G2A!R7F25!//jf4cfls225.pdx.intel.com/apd_proj/ppg_lib/epg_masterlib/logical/mstr_discrete/res/chips/chips.prt!RES!RES_0402-20.0,1%,1/16W,CHIP,G21796-173!RES!!!F945!!VDDQ_ABC_PWR_VR!!
S!@baseboard_fab2_lib.baseboard_fab2(sch_1):page159_i219@mstr_discrete.res(chips)!RES_0402-20.0,1%,1/16W,CHIP,G2A!R2T49!//jf4cfls225.pdx.intel.com/apd_proj/ppg_lib/epg_masterlib/logical/mstr_discrete/res/chips/chips.prt!RES!RES_0402-20.0,1%,1/16W,CHIP,G21796-173!RES!!!F969!!SMBUS!!
S!@baseboard_fab2_lib.baseboard_fab2(sch_1):page159_i218@mstr_discrete.res(chips)!RES_0402-20.0,1%,1/16W,CHIP,G2A!R2U1!//jf4cfls225.pdx.intel.com/apd_proj/ppg_lib/epg_masterlib/logical/mstr_discrete/res/chips/chips.prt!RES!RES_0402-20.0,1%,1/16W,CHIP,G21796-173!RES!!!F966!!SMBUS!!
S!@baseboard_fab2_lib.baseboard_fab2(sch_1):page218_i24@mstr_discrete.res(chips)!RES_0402-20.0,1%,1/16W,CHIP,G2A!R7B2!//jf4cfls225.pdx.intel.com/apd_proj/ppg_lib/epg_masterlib/logical/mstr_discrete/res/chips/chips.prt!RES!RES_0402-20.0,1%,1/16W,CHIP,G21796-173!RES!!!F947!!VDDQ_DEF_PWR_VR!!
S!@baseboard_fab2_lib.baseboard_fab2(sch_1):page218_i21@mstr_discrete.res(chips)!RES_0402-20.0,1%,1/16W,CHIP,G2A!R7B3!//jf4cfls225.pdx.intel.com/apd_proj/ppg_lib/epg_masterlib/logical/mstr_discrete/res/chips/chips.prt!RES!RES_0402-20.0,1%,1/16W,CHIP,G21796-173!RES!!!F946!!VDDQ_DEF_PWR_VR!!
S!@baseboard_fab2_lib.baseboard_fab2(sch_1):page226_i22@mstr_discrete.res(chips)!RES_0402-20.0,1%,1/16W,CHIP,G2A!R1B7!//jf4cfls225.pdx.intel.com/apd_proj/ppg_lib/epg_masterlib/logical/mstr_discrete/res/chips/chips.prt!RES!RES_0402-20.0,1%,1/16W,CHIP,G21796-173!RES!!!F980!!VDDQ_KLM_PWR_VR!!
S!@baseboard_fab2_lib.baseboard_fab2(sch_1):page226_i21@mstr_discrete.res(chips)!RES_0402-20.0,1%,1/16W,CHIP,G2A!R1B6!//jf4cfls225.pdx.intel.com/apd_proj/ppg_lib/epg_masterlib/logical/mstr_discrete/res/chips/chips.prt!RES!RES_0402-20.0,1%,1/16W,CHIP,G21796-173!RES!!!F981!!VDDQ_KLM_PWR_VR!!
S!@baseboard_fab2_lib.baseboard_fab2(sch_1):page159_i221@mstr_discrete.res(chips)!RES_0402-20.0,1%,1/16W,CHIP,G2A!R2U10!//jf4cfls225.pdx.intel.com/apd_proj/ppg_lib/epg_masterlib/logical/mstr_discrete/res/chips/chips.prt!RES!RES_0402-20.0,1%,1/16W,CHIP,G21796-173!RES!!!F962!!SMBUS!!
S!@baseboard_fab2_lib.baseboard_fab2(sch_1):page159_i220@mstr_discrete.res(chips)!RES_0402-20.0,1%,1/16W,CHIP,G2A!R2U7!//jf4cfls225.pdx.intel.com/apd_proj/ppg_lib/epg_masterlib/logical/mstr_discrete/res/chips/chips.prt!RES!RES_0402-20.0,1%,1/16W,CHIP,G21796-173!RES!!!F964!!SMBUS!!
S!@baseboard_fab2_lib.baseboard_fab2(sch_1):page138_i174@mstr_discrete.res(chips)!RES_0402-20.0,1%,1/16W,CHIP,G2A!R8B28!//jf4cfls225.pdx.intel.com/apd_proj/ppg_lib/epg_masterlib/logical/mstr_discrete/res/chips/chips.prt!RES!RES_0402-20.0,1%,1/16W,CHIP,G21796-173!RES!!!F938!!SMBUS!!
S!@baseboard_fab2_lib.baseboard_fab2(sch_1):page138_i173@mstr_discrete.res(chips)!RES_0402-20.0,1%,1/16W,CHIP,G2A!R8B27!//jf4cfls225.pdx.intel.com/apd_proj/ppg_lib/epg_masterlib/logical/mstr_discrete/res/chips/chips.prt!RES!RES_0402-20.0,1%,1/16W,CHIP,G21796-173!RES!!!F939!!SMBUS!!
S!@baseboard_fab2_lib.baseboard_fab2(sch_1):page167_i8@mstr_discrete.res(chips)!RES_0402-20.0,1%,1/16W,CHIP,G2A!R1M9!//jf4cfls225.pdx.intel.com/apd_proj/ppg_lib/epg_masterlib/logical/mstr_discrete/res/chips/chips.prt!RES!RES_0402-20.0,1%,1/16W,CHIP,G21796-173!RES!!!F978!!TEMP_SENSORS!!
S!@baseboard_fab2_lib.baseboard_fab2(sch_1):page167_i76@mstr_discrete.res(chips)!RES_0402-20.0,1%,1/16W,CHIP,G2A!R9R8!//jf4cfls225.pdx.intel.com/apd_proj/ppg_lib/epg_masterlib/logical/mstr_discrete/res/chips/chips.prt!RES!RES_0402-20.0,1%,1/16W,CHIP,G21796-173!RES!!!F914!!TEMP_SENSORS!!
S!@baseboard_fab2_lib.baseboard_fab2(sch_1):page167_i74@mstr_discrete.res(chips)!RES_0402-20.0,1%,1/16W,CHIP,G2A!R1M8!//jf4cfls225.pdx.intel.com/apd_proj/ppg_lib/epg_masterlib/logical/mstr_discrete/res/chips/chips.prt!RES!RES_0402-20.0,1%,1/16W,CHIP,G21796-173!RES!!!F979!!TEMP_SENSORS!!
S!@baseboard_fab2_lib.baseboard_fab2(sch_1):page167_i75@mstr_discrete.res(chips)!RES_0402-20.0,1%,1/16W,CHIP,G2A!R9R7!//jf4cfls225.pdx.intel.com/apd_proj/ppg_lib/epg_masterlib/logical/mstr_discrete/res/chips/chips.prt!RES!RES_0402-20.0,1%,1/16W,CHIP,G21796-173!RES!!!F915!!TEMP_SENSORS!!
S!@baseboard_fab2_lib.baseboard_fab2(sch_1):page138_i165@mstr_discrete.res(chips)!RES_0402-20.0,1%,1/16W,CHIP,G2A!R2U9!//jf4cfls225.pdx.intel.com/apd_proj/ppg_lib/epg_masterlib/logical/mstr_discrete/res/chips/chips.prt!RES!RES_0402-20.0,1%,1/16W,CHIP,G21796-173!RES!!!F963!!SMBUS!!
S!@baseboard_fab2_lib.baseboard_fab2(sch_1):page138_i166@mstr_discrete.res(chips)!RES_0402-20.0,1%,1/16W,CHIP,G2A!R2U6!//jf4cfls225.pdx.intel.com/apd_proj/ppg_lib/epg_masterlib/logical/mstr_discrete/res/chips/chips.prt!RES!RES_0402-20.0,1%,1/16W,CHIP,G21796-173!RES!!!F965!!SMBUS!!
S!@baseboard_fab2_lib.baseboard_fab2(sch_1):page138_i162@mstr_discrete.res(chips)!RES_0402-20.0,1%,1/16W,CHIP,G2A!R8D6!//jf4cfls225.pdx.intel.com/apd_proj/ppg_lib/epg_masterlib/logical/mstr_discrete/res/chips/chips.prt!RES!RES_0402-20.0,1%,1/16W,CHIP,G21796-173!RES!!!F931!!SMBUS!!
S!@baseboard_fab2_lib.baseboard_fab2(sch_1):page138_i161@mstr_discrete.res(chips)!RES_0402-20.0,1%,1/16W,CHIP,G2A!R8D3!//jf4cfls225.pdx.intel.com/apd_proj/ppg_lib/epg_masterlib/logical/mstr_discrete/res/chips/chips.prt!RES!RES_0402-20.0,1%,1/16W,CHIP,G21796-173!RES!!!F933!!SMBUS!!
S!@baseboard_fab2_lib.baseboard_fab2(sch_1):page138_i163@mstr_discrete.res(chips)!RES_0402-20.0,1%,1/16W,CHIP,G2A!R8D7!//jf4cfls225.pdx.intel.com/apd_proj/ppg_lib/epg_masterlib/logical/mstr_discrete/res/chips/chips.prt!RES!RES_0402-20.0,1%,1/16W,CHIP,G21796-173!RES!!!F930!!SMBUS!!
S!@baseboard_fab2_lib.baseboard_fab2(sch_1):page138_i164@mstr_discrete.res(chips)!RES_0402-20.0,1%,1/16W,CHIP,G2A!R8D4!//jf4cfls225.pdx.intel.com/apd_proj/ppg_lib/epg_masterlib/logical/mstr_discrete/res/chips/chips.prt!RES!RES_0402-20.0,1%,1/16W,CHIP,G21796-173!RES!!!F932!!SMBUS!!
S!@baseboard_fab2_lib.baseboard_fab2(sch_1):page159_i233@mstr_discrete.res(chips)!RES_0402-20.0,1%,1/16W,CHIP,G2A!R1U10!//jf4cfls225.pdx.intel.com/apd_proj/ppg_lib/epg_masterlib/logical/mstr_discrete/res/chips/chips.prt!RES!RES_0402-20.0,1%,1/16W,CHIP,G21796-173!RES!!!F974!!SMBUS!!
S!@baseboard_fab2_lib.baseboard_fab2(sch_1):page159_i232@mstr_discrete.res(chips)!RES_0402-20.0,1%,1/16W,CHIP,G2A!R1U9!//jf4cfls225.pdx.intel.com/apd_proj/ppg_lib/epg_masterlib/logical/mstr_discrete/res/chips/chips.prt!RES!RES_0402-20.0,1%,1/16W,CHIP,G21796-173!RES!!!F975!!SMBUS!!
S!@baseboard_fab2_lib.baseboard_fab2(sch_1):page159_i231@mstr_discrete.res(chips)!RES_0402-20.0,1%,1/16W,CHIP,G2A!R2U33!//jf4cfls225.pdx.intel.com/apd_proj/ppg_lib/epg_masterlib/logical/mstr_discrete/res/chips/chips.prt!RES!RES_0402-20.0,1%,1/16W,CHIP,G21796-173!RES!!!F959!!SMBUS!!
S!@baseboard_fab2_lib.baseboard_fab2(sch_1):page159_i230@mstr_discrete.res(chips)!RES_0402-20.0,1%,1/16W,CHIP,G2A!R2U34!//jf4cfls225.pdx.intel.com/apd_proj/ppg_lib/epg_masterlib/logical/mstr_discrete/res/chips/chips.prt!RES!RES_0402-20.0,1%,1/16W,CHIP,G21796-173!RES!!!F958!!SMBUS!!
S!@baseboard_fab2_lib.baseboard_fab2(sch_1):page159_i228@mstr_discrete.res(chips)!RES_0402-20.0,1%,1/16W,CHIP,G2A!R8G5!//jf4cfls225.pdx.intel.com/apd_proj/ppg_lib/epg_masterlib/logical/mstr_discrete/res/chips/chips.prt!RES!RES_0402-20.0,1%,1/16W,CHIP,G21796-173!RES!!!F926!!SMBUS!!
S!@baseboard_fab2_lib.baseboard_fab2(sch_1):page159_i229@mstr_discrete.res(chips)!RES_0402-20.0,1%,1/16W,CHIP,G2A!R8G4!//jf4cfls225.pdx.intel.com/apd_proj/ppg_lib/epg_masterlib/logical/mstr_discrete/res/chips/chips.prt!RES!RES_0402-20.0,1%,1/16W,CHIP,G21796-173!RES!!!F927!!SMBUS!!
S!@baseboard_fab2_lib.baseboard_fab2(sch_1):page213_i38@mstr_discrete.res(chips)!RES_0402-20.0,1%,1/16W,CHIP,G2A!R4D44!//jf4cfls225.pdx.intel.com/apd_proj/ppg_lib/epg_masterlib/logical/mstr_discrete/res/chips/chips.prt!RES!RES_0402-20.0,1%,1/16W,CHIP,G21796-173!RES!!!F952!!PVCCIO_CPU1!!
S!@baseboard_fab2_lib.baseboard_fab2(sch_1):page215_i304@mstr_discrete.res(chips)!RES_0402-20.0,1%,1/16W,CHIP,G2A!R7F26!//jf4cfls225.pdx.intel.com/apd_proj/ppg_lib/epg_masterlib/logical/mstr_discrete/res/chips/chips.prt!RES!RES_0402-20.0,1%,1/16W,CHIP,G21796-173!RES!!!F944!!VDDQ_ABC_PWR_VR!!
S!@baseboard_fab2_lib.baseboard_fab2(sch_1):page211_i47@mstr_discrete.res(chips)!RES_0402-20.0,1%,1/16W,CHIP,G2A!R3P23!//jf4cfls225.pdx.intel.com/apd_proj/ppg_lib/epg_masterlib/logical/mstr_discrete/res/chips/chips.prt!RES!RES_0402-20.0,1%,1/16W,CHIP,G21796-173!RES!!!F957!!PVCCIO_CPU0!!
S!@baseboard_fab2_lib.baseboard_fab2(sch_1):page213_i39@mstr_discrete.res(chips)!RES_0402-20.0,1%,1/16W,CHIP,G2A!R4D43!//jf4cfls225.pdx.intel.com/apd_proj/ppg_lib/epg_masterlib/logical/mstr_discrete/res/chips/chips.prt!RES!RES_0402-20.0,1%,1/16W,CHIP,G21796-173!RES!!!F953!!PVCCIO_CPU1!!
S!@baseboard_fab2_lib.baseboard_fab2(sch_1):page235_i172@mstr_discrete.res(chips)!RES_0402-20.0,1%,1/16W,CHIP,G2A!R8A8!//jf4cfls225.pdx.intel.com/apd_proj/ppg_lib/epg_masterlib/logical/mstr_discrete/res/chips/chips.prt!RES!RES_0402-20.0,1%,1/16W,CHIP,G21796-173!RES!!!F941!!PVNN_PCH_STBY!!
S!@baseboard_fab2_lib.baseboard_fab2(sch_1):page235_i173@mstr_discrete.res(chips)!RES_0402-20.0,1%,1/16W,CHIP,G2A!R8A9!//jf4cfls225.pdx.intel.com/apd_proj/ppg_lib/epg_masterlib/logical/mstr_discrete/res/chips/chips.prt!RES!RES_0402-20.0,1%,1/16W,CHIP,G21796-173!RES!!!F940!!PVNN_PCH_STBY!!
S!@baseboard_fab2_lib.baseboard_fab2(sch_1):page99_i34@mstr_discrete.res(chips)!RES_0402-20.0,1%,1/16W,CHIP,G2A!R3R9!//jf4cfls225.pdx.intel.com/apd_proj/ppg_lib/epg_masterlib/logical/mstr_discrete/res/chips/chips.prt!RES!RES_0402-20.0,1%,1/16W,CHIP,G21796-173!RES!!!F954!!MEM!!
S!@baseboard_fab2_lib.baseboard_fab2(sch_1):page99_i35@mstr_discrete.res(chips)!RES_0402-20.0,1%,1/16W,CHIP,G2A!R3R8!//jf4cfls225.pdx.intel.com/apd_proj/ppg_lib/epg_masterlib/logical/mstr_discrete/res/chips/chips.prt!RES!RES_0402-20.0,1%,1/16W,CHIP,G21796-173!RES!!!F955!!MEM!!
S!@baseboard_fab2_lib.baseboard_fab2(sch_1):page99_i43@mstr_discrete.res(chips)!RES_0402-20.0,1%,1/16W,CHIP,G2A!R6U14!//jf4cfls225.pdx.intel.com/apd_proj/ppg_lib/epg_masterlib/logical/mstr_discrete/res/chips/chips.prt!RES!RES_0402-20.0,1%,1/16W,CHIP,G21796-173!RES!!!F948!!MEM!!
S!@baseboard_fab2_lib.baseboard_fab2(sch_1):page99_i42@mstr_discrete.res(chips)!RES_0402-20.0,1%,1/16W,CHIP,G2A!R6U13!//jf4cfls225.pdx.intel.com/apd_proj/ppg_lib/epg_masterlib/logical/mstr_discrete/res/chips/chips.prt!RES!RES_0402-20.0,1%,1/16W,CHIP,G21796-173!RES!!!F949!!MEM!!
S!@baseboard_fab2_lib.baseboard_fab2(sch_1):page99_i10@mstr_discrete.res(chips)!RES_0402-20.0,1%,1/16W,CHIP,G2A!R4T10!//jf4cfls225.pdx.intel.com/apd_proj/ppg_lib/epg_masterlib/logical/mstr_discrete/res/chips/chips.prt!RES!RES_0402-20.0,1%,1/16W,CHIP,G21796-173!RES!!!F950!!MEM!!
S!@baseboard_fab2_lib.baseboard_fab2(sch_1):page99_i56@mstr_discrete.res(chips)!RES_0402-20.0,1%,1/16W,CHIP,G2A!R7M4!//jf4cfls225.pdx.intel.com/apd_proj/ppg_lib/epg_masterlib/logical/mstr_discrete/res/chips/chips.prt!RES!RES_0402-20.0,1%,1/16W,CHIP,G21796-173!RES!!!F943!!MEM!!
S!@baseboard_fab2_lib.baseboard_fab2(sch_1):page99_i55@mstr_discrete.res(chips)!RES_0402-20.0,1%,1/16W,CHIP,G2A!R7M5!//jf4cfls225.pdx.intel.com/apd_proj/ppg_lib/epg_masterlib/logical/mstr_discrete/res/chips/chips.prt!RES!RES_0402-20.0,1%,1/16W,CHIP,G21796-173!RES!!!F942!!MEM!!
S!@baseboard_fab2_lib.baseboard_fab2(sch_1):page99_i9@mstr_discrete.res(chips)!RES_0402-20.0,1%,1/16W,CHIP,G2A!R4T9!//jf4cfls225.pdx.intel.com/apd_proj/ppg_lib/epg_masterlib/logical/mstr_discrete/res/chips/chips.prt!RES!RES_0402-20.0,1%,1/16W,CHIP,G21796-173!RES!!!F951!!MEM!!
S!@baseboard_fab2_lib.baseboard_fab2(sch_1):page90_i31@mstr_discrete.res(chips)!RES_0402-240,1.0%,1/16W,CHIP,GA!R6D7!//jf4cfls225.pdx.intel.com/apd_proj/ppg_lib/epg_masterlib/logical/mstr_discrete/res/chips/chips.prt!RES!RES_0402-240,1.0%,1/16W,CHIP,G21796-294!RES!!!F832!!PROC_SIDEBAND!!
S!@baseboard_fab2_lib.baseboard_fab2(sch_1):page90_i32@mstr_discrete.res(chips)!RES_0402-240,1.0%,1/16W,CHIP,GA!R5D4!//jf4cfls225.pdx.intel.com/apd_proj/ppg_lib/epg_masterlib/logical/mstr_discrete/res/chips/chips.prt!RES!RES_0402-240,1.0%,1/16W,CHIP,G21796-294!RES!!!F833!!PROC_SIDEBAND!!
S!@baseboard_fab2_lib.baseboard_fab2(sch_1):page163_i7@mstr_discrete.res(chips)!RES_0402-240,1.0%,1/16W,CHIP,GA!R9M19!//jf4cfls225.pdx.intel.com/apd_proj/ppg_lib/epg_masterlib/logical/mstr_discrete/res/chips/chips.prt!RES!RES_0402-240,1.0%,1/16W,CHIP,G21796-294!RES!!!F825!!SMB_PE_HP_CPU1!!
S!@baseboard_fab2_lib.baseboard_fab2(sch_1):page163_i6@mstr_discrete.res(chips)!RES_0402-240,1.0%,1/16W,CHIP,GA!R9M18!//jf4cfls225.pdx.intel.com/apd_proj/ppg_lib/epg_masterlib/logical/mstr_discrete/res/chips/chips.prt!RES!RES_0402-240,1.0%,1/16W,CHIP,G21796-294!RES!!!F826!!SMB_PE_HP_CPU1!!
S!@baseboard_fab2_lib.baseboard_fab2(sch_1):page90_i70@mstr_discrete.res(chips)!RES_0402-240,1.0%,1/16W,CHIP,GA!R7P14!//jf4cfls225.pdx.intel.com/apd_proj/ppg_lib/epg_masterlib/logical/mstr_discrete/res/chips/chips.prt!RES!RES_0402-240,1.0%,1/16W,CHIP,G21796-294!RES!!!F827!!PROC_SIDEBAND!!
S!@baseboard_fab2_lib.baseboard_fab2(sch_1):page90_i53@mstr_discrete.res(chips)!RES_0402-240,1.0%,1/16W,CHIP,GA!R4P14!//jf4cfls225.pdx.intel.com/apd_proj/ppg_lib/epg_masterlib/logical/mstr_discrete/res/chips/chips.prt!RES!RES_0402-240,1.0%,1/16W,CHIP,G21796-294!RES!!!F838!!PROC_SIDEBAND!!
S!@baseboard_fab2_lib.baseboard_fab2(sch_1):page97_i72@mstr_discrete.res(chips)!RES_0402-240,1.0%,1/16W,CHIP,GA!R4P21!//jf4cfls225.pdx.intel.com/apd_proj/ppg_lib/epg_masterlib/logical/mstr_discrete/res/chips/chips.prt!RES!RES_0402-240,1.0%,1/16W,CHIP,G21796-294!RES!!!F837!!PROC_SIDEBAND!!
S!@baseboard_fab2_lib.baseboard_fab2(sch_1):page97_i76@mstr_discrete.res(chips)!RES_0402-240,1.0%,1/16W,CHIP,GA!R4C10!//jf4cfls225.pdx.intel.com/apd_proj/ppg_lib/epg_masterlib/logical/mstr_discrete/res/chips/chips.prt!RES!RES_0402-240,1.0%,1/16W,CHIP,G21796-294!RES!!!F839!!PROC_SIDEBAND!!
S!@baseboard_fab2_lib.baseboard_fab2(sch_1):page99_i65@mstr_discrete.res(chips)!RES_0402-240,1.0%,1/16W,CHIP,GA!R3R13!//jf4cfls225.pdx.intel.com/apd_proj/ppg_lib/epg_masterlib/logical/mstr_discrete/res/chips/chips.prt!RES!RES_0402-240,1.0%,1/16W,CHIP,G21796-294!RES!!!F840!!MEM!!
S!@baseboard_fab2_lib.baseboard_fab2(sch_1):page99_i67@mstr_discrete.res(chips)!RES_0402-240,1.0%,1/16W,CHIP,GA!R3P60!//jf4cfls225.pdx.intel.com/apd_proj/ppg_lib/epg_masterlib/logical/mstr_discrete/res/chips/chips.prt!RES!RES_0402-240,1.0%,1/16W,CHIP,G21796-294!RES!!!F841!!MEM!!
S!@baseboard_fab2_lib.baseboard_fab2(sch_1):page99_i72@mstr_discrete.res(chips)!RES_0402-240,1.0%,1/16W,CHIP,GA!R6T2!//jf4cfls225.pdx.intel.com/apd_proj/ppg_lib/epg_masterlib/logical/mstr_discrete/res/chips/chips.prt!RES!RES_0402-240,1.0%,1/16W,CHIP,G21796-294!RES!!!F830!!MEM!!
S!@baseboard_fab2_lib.baseboard_fab2(sch_1):page99_i70@mstr_discrete.res(chips)!RES_0402-240,1.0%,1/16W,CHIP,GA!R6T1!//jf4cfls225.pdx.intel.com/apd_proj/ppg_lib/epg_masterlib/logical/mstr_discrete/res/chips/chips.prt!RES!RES_0402-240,1.0%,1/16W,CHIP,G21796-294!RES!!!F831!!MEM!!
S!@baseboard_fab2_lib.baseboard_fab2(sch_1):page99_i19@mstr_discrete.res(chips)!RES_0402-240,1.0%,1/16W,CHIP,GA!R4T5!//jf4cfls225.pdx.intel.com/apd_proj/ppg_lib/epg_masterlib/logical/mstr_discrete/res/chips/chips.prt!RES!RES_0402-240,1.0%,1/16W,CHIP,G21796-294!RES!!!F836!!MEM!!
S!@baseboard_fab2_lib.baseboard_fab2(sch_1):page90_i29@mstr_discrete.res(chips)!RES_0402-240,1.0%,1/16W,CHIP,GA!R5D3!//jf4cfls225.pdx.intel.com/apd_proj/ppg_lib/epg_masterlib/logical/mstr_discrete/res/chips/chips.prt!RES!RES_0402-240,1.0%,1/16W,CHIP,G21796-294!RES!!!F834!!PROC_SIDEBAND!!
S!@baseboard_fab2_lib.baseboard_fab2(sch_1):page99_i79@mstr_discrete.res(chips)!RES_0402-240,1.0%,1/16W,CHIP,GA!R7M2!//jf4cfls225.pdx.intel.com/apd_proj/ppg_lib/epg_masterlib/logical/mstr_discrete/res/chips/chips.prt!RES!RES_0402-240,1.0%,1/16W,CHIP,G21796-294!RES!!!F829!!MEM!!
S!@baseboard_fab2_lib.baseboard_fab2(sch_1):page99_i77@mstr_discrete.res(chips)!RES_0402-240,1.0%,1/16W,CHIP,GA!R7M7!//jf4cfls225.pdx.intel.com/apd_proj/ppg_lib/epg_masterlib/logical/mstr_discrete/res/chips/chips.prt!RES!RES_0402-240,1.0%,1/16W,CHIP,G21796-294!RES!!!F828!!MEM!!
S!@baseboard_fab2_lib.baseboard_fab2(sch_1):page90_i59@mstr_discrete.res(chips)!RES_0402-240,1.0%,1/16W,CHIP,GA!R3D24!//jf4cfls225.pdx.intel.com/apd_proj/ppg_lib/epg_masterlib/logical/mstr_discrete/res/chips/chips.prt!RES!RES_0402-240,1.0%,1/16W,CHIP,G21796-294!RES!!!F842!!PROC_SIDEBAND!!
S!@baseboard_fab2_lib.baseboard_fab2(sch_1):page151_i32@mstr_discrete.res(chips)!RES_0402-240,1.0%,1/16W,CHIP,GA!R1T27!//jf4cfls225.pdx.intel.com/apd_proj/ppg_lib/epg_masterlib/logical/mstr_discrete/res/chips/chips.prt!RES!RES_0402-240,1.0%,1/16W,CHIP,G21796-294!RES!!!F843!!BMC_MEMORY!!
S!@baseboard_fab2_lib.baseboard_fab2(sch_1):page99_i17@mstr_discrete.res(chips)!RES_0402-240,1.0%,1/16W,CHIP,GA!R4T6!//jf4cfls225.pdx.intel.com/apd_proj/ppg_lib/epg_masterlib/logical/mstr_discrete/res/chips/chips.prt!RES!RES_0402-240,1.0%,1/16W,CHIP,G21796-294!RES!!!F835!!MEM!!
S!@baseboard_fab2_lib.baseboard_fab2(sch_1):page90_i3@mstr_discrete.res(chips)!RES_0402-240,1.0%,1/16W,EMPTY,A!R6D6!//jf4cfls225.pdx.intel.com/apd_proj/ppg_lib/epg_masterlib/logical/mstr_discrete/res/chips/chips.prt!RES!RES_0402-240,1.0%,1/16W,EMPTY,G21796-294!RES!!!F814!!PROC_SIDEBAND!!
S!@baseboard_fab2_lib.baseboard_fab2(sch_1):page90_i11@mstr_discrete.res(chips)!RES_0402-240,1.0%,1/16W,EMPTY,A!R3D12!//jf4cfls225.pdx.intel.com/apd_proj/ppg_lib/epg_masterlib/logical/mstr_discrete/res/chips/chips.prt!RES!RES_0402-240,1.0%,1/16W,EMPTY,G21796-294!RES!!!F824!!PROC_SIDEBAND!!
S!@baseboard_fab2_lib.baseboard_fab2(sch_1):page90_i76@mstr_discrete.res(chips)!RES_0402-240,1.0%,1/16W,EMPTY,A!R7P22!//jf4cfls225.pdx.intel.com/apd_proj/ppg_lib/epg_masterlib/logical/mstr_discrete/res/chips/chips.prt!RES!RES_0402-240,1.0%,1/16W,EMPTY,G21796-294!RES!!!F809!!PROC_SIDEBAND!!
S!@baseboard_fab2_lib.baseboard_fab2(sch_1):page90_i66@mstr_discrete.res(chips)!RES_0402-240,1.0%,1/16W,EMPTY,A!R3D25!//jf4cfls225.pdx.intel.com/apd_proj/ppg_lib/epg_masterlib/logical/mstr_discrete/res/chips/chips.prt!RES!RES_0402-240,1.0%,1/16W,EMPTY,G21796-294!RES!!!F818!!PROC_SIDEBAND!!
S!@baseboard_fab2_lib.baseboard_fab2(sch_1):page90_i52@mstr_discrete.res(chips)!RES_0402-240,1.0%,1/16W,EMPTY,A!R6D14!//jf4cfls225.pdx.intel.com/apd_proj/ppg_lib/epg_masterlib/logical/mstr_discrete/res/chips/chips.prt!RES!RES_0402-240,1.0%,1/16W,EMPTY,G21796-294!RES!!!F811!!PROC_SIDEBAND!!
S!@baseboard_fab2_lib.baseboard_fab2(sch_1):page90_i68@mstr_discrete.res(chips)!RES_0402-240,1.0%,1/16W,EMPTY,A!R4P6!//jf4cfls225.pdx.intel.com/apd_proj/ppg_lib/epg_masterlib/logical/mstr_discrete/res/chips/chips.prt!RES!RES_0402-240,1.0%,1/16W,EMPTY,G21796-294!RES!!!F815!!PROC_SIDEBAND!!
S!@baseboard_fab2_lib.baseboard_fab2(sch_1):page90_i49@mstr_discrete.res(chips)!RES_0402-240,1.0%,1/16W,EMPTY,A!R6D10!//jf4cfls225.pdx.intel.com/apd_proj/ppg_lib/epg_masterlib/logical/mstr_discrete/res/chips/chips.prt!RES!RES_0402-240,1.0%,1/16W,EMPTY,G21796-294!RES!!!F813!!PROC_SIDEBAND!!
S!@baseboard_fab2_lib.baseboard_fab2(sch_1):page90_i33@mstr_discrete.res(chips)!RES_0402-240,1.0%,1/16W,EMPTY,A!R6D13!//jf4cfls225.pdx.intel.com/apd_proj/ppg_lib/epg_masterlib/logical/mstr_discrete/res/chips/chips.prt!RES!RES_0402-240,1.0%,1/16W,EMPTY,G21796-294!RES!!!F812!!PROC_SIDEBAND!!
S!@baseboard_fab2_lib.baseboard_fab2(sch_1):page90_i28@mstr_discrete.res(chips)!RES_0402-240,1.0%,1/16W,EMPTY,A!R3D26!//jf4cfls225.pdx.intel.com/apd_proj/ppg_lib/epg_masterlib/logical/mstr_discrete/res/chips/chips.prt!RES!RES_0402-240,1.0%,1/16W,EMPTY,G21796-294!RES!!!F817!!PROC_SIDEBAND!!
S!@baseboard_fab2_lib.baseboard_fab2(sch_1):page90_i12@mstr_discrete.res(chips)!RES_0402-240,1.0%,1/16W,EMPTY,A!R3D13!//jf4cfls225.pdx.intel.com/apd_proj/ppg_lib/epg_masterlib/logical/mstr_discrete/res/chips/chips.prt!RES!RES_0402-240,1.0%,1/16W,EMPTY,G21796-294!RES!!!F823!!PROC_SIDEBAND!!
S!@baseboard_fab2_lib.baseboard_fab2(sch_1):page90_i25@mstr_discrete.res(chips)!RES_0402-240,1.0%,1/16W,EMPTY,A!R3D23!//jf4cfls225.pdx.intel.com/apd_proj/ppg_lib/epg_masterlib/logical/mstr_discrete/res/chips/chips.prt!RES!RES_0402-240,1.0%,1/16W,EMPTY,G21796-294!RES!!!F819!!PROC_SIDEBAND!!
S!@baseboard_fab2_lib.baseboard_fab2(sch_1):page90_i24@mstr_discrete.res(chips)!RES_0402-240,1.0%,1/16W,EMPTY,A!R3D16!//jf4cfls225.pdx.intel.com/apd_proj/ppg_lib/epg_masterlib/logical/mstr_discrete/res/chips/chips.prt!RES!RES_0402-240,1.0%,1/16W,EMPTY,G21796-294!RES!!!F822!!PROC_SIDEBAND!!
S!@baseboard_fab2_lib.baseboard_fab2(sch_1):page90_i17@mstr_discrete.res(chips)!RES_0402-240,1.0%,1/16W,EMPTY,A!R3D22!//jf4cfls225.pdx.intel.com/apd_proj/ppg_lib/epg_masterlib/logical/mstr_discrete/res/chips/chips.prt!RES!RES_0402-240,1.0%,1/16W,EMPTY,G21796-294!RES!!!F820!!PROC_SIDEBAND!!
S!@baseboard_fab2_lib.baseboard_fab2(sch_1):page90_i4@mstr_discrete.res(chips)!RES_0402-240,1.0%,1/16W,EMPTY,A!R4P1!//jf4cfls225.pdx.intel.com/apd_proj/ppg_lib/epg_masterlib/logical/mstr_discrete/res/chips/chips.prt!RES!RES_0402-240,1.0%,1/16W,EMPTY,G21796-294!RES!!!F816!!PROC_SIDEBAND!!
S!@baseboard_fab2_lib.baseboard_fab2(sch_1):page90_i60@mstr_discrete.res(chips)!RES_0402-240,1.0%,1/16W,EMPTY,A!R3D17!//jf4cfls225.pdx.intel.com/apd_proj/ppg_lib/epg_masterlib/logical/mstr_discrete/res/chips/chips.prt!RES!RES_0402-240,1.0%,1/16W,EMPTY,G21796-294!RES!!!F821!!PROC_SIDEBAND!!
S!@baseboard_fab2_lib.baseboard_fab2(sch_1):page90_i48@mstr_discrete.res(chips)!RES_0402-240,1.0%,1/16W,EMPTY,A!R6D15!//jf4cfls225.pdx.intel.com/apd_proj/ppg_lib/epg_masterlib/logical/mstr_discrete/res/chips/chips.prt!RES!RES_0402-240,1.0%,1/16W,EMPTY,G21796-294!RES!!!F810!!PROC_SIDEBAND!!
S!@baseboard_fab2_lib.baseboard_fab2(sch_1):page157_i388@mstr_discrete.res(chips)!RES_0402-33.2,1%,1/16W,CHIP,G2A!R8D36!//jf4cfls225.pdx.intel.com/apd_proj/ppg_lib/epg_masterlib/logical/mstr_discrete/res/chips/chips.prt!RES!RES_0402-33.2,1%,1/16W,CHIP,G21796-074!RES!!!F667!!BMC_MISC!!
S!@baseboard_fab2_lib.baseboard_fab2(sch_1):page102_i82@mstr_discrete.res(chips)!RES_0402-33.2,1%,1/16W,CHIP,G2A!R4D36!//jf4cfls225.pdx.intel.com/apd_proj/ppg_lib/epg_masterlib/logical/mstr_discrete/res/chips/chips.prt!RES!RES_0402-33.2,1%,1/16W,CHIP,G21796-074!RES!!!F713!!DB1200ZL!!
S!@baseboard_fab2_lib.baseboard_fab2(sch_1):page102_i87@mstr_discrete.res(chips)!RES_0402-33.2,1%,1/16W,CHIP,G2A!R4D37!//jf4cfls225.pdx.intel.com/apd_proj/ppg_lib/epg_masterlib/logical/mstr_discrete/res/chips/chips.prt!RES!RES_0402-33.2,1%,1/16W,CHIP,G21796-074!RES!!!F712!!DB1200ZL!!
S!@baseboard_fab2_lib.baseboard_fab2(sch_1):page156_i289@mstr_discrete.res(chips)!RES_0402-33.2,1%,1/16W,CHIP,G2A!R2T28!//jf4cfls225.pdx.intel.com/apd_proj/ppg_lib/epg_masterlib/logical/mstr_discrete/res/chips/chips.prt!RES!RES_0402-33.2,1%,1/16W,CHIP,G21796-074!RES!!!F733!!BMC_MISC!!
S!@baseboard_fab2_lib.baseboard_fab2(sch_1):page157_i386@mstr_discrete.res(chips)!RES_0402-33.2,1%,1/16W,CHIP,G2A!R8D22!//jf4cfls225.pdx.intel.com/apd_proj/ppg_lib/epg_masterlib/logical/mstr_discrete/res/chips/chips.prt!RES!RES_0402-33.2,1%,1/16W,CHIP,G21796-074!RES!!!F692!!BMC_MISC!!
S!@baseboard_fab2_lib.baseboard_fab2(sch_1):page170_i74@mstr_discrete.res(chips)!RES_0402-33.2,1%,1/16W,CHIP,G2A!R2P4!//jf4cfls225.pdx.intel.com/apd_proj/ppg_lib/epg_masterlib/logical/mstr_discrete/res/chips/chips.prt!RES!RES_0402-33.2,1%,1/16W,CHIP,G21796-074!RES!!!F738!!!!
S!@baseboard_fab2_lib.baseboard_fab2(sch_1):page190_i338@mstr_discrete.res(chips)!RES_0402-33.2,1%,1/16W,CHIP,G2A!R2R2!//jf4cfls225.pdx.intel.com/apd_proj/ppg_lib/epg_masterlib/logical/mstr_discrete/res/chips/chips.prt!RES!RES_0402-33.2,1%,1/16W,CHIP,G21796-074!RES!!!F737!!CPLD!!
S!@baseboard_fab2_lib.baseboard_fab2(sch_1):page151_i70@mstr_discrete.res(chips)!RES_0402-33.2,1%,1/16W,CHIP,G2A!R9F34!//jf4cfls225.pdx.intel.com/apd_proj/ppg_lib/epg_masterlib/logical/mstr_discrete/res/chips/chips.prt!RES!RES_0402-33.2,1%,1/16W,CHIP,G21796-074!RES!!!F672!!BMC_MEMORY!!
S!@baseboard_fab2_lib.baseboard_fab2(sch_1):page165_i81@mstr_discrete.res(chips)!RES_0402-33.2,1%,1/16W,CHIP,G2A!R1U40!//jf4cfls225.pdx.intel.com/apd_proj/ppg_lib/epg_masterlib/logical/mstr_discrete/res/chips/chips.prt!RES!RES_0402-33.2,1%,1/16W,CHIP,G21796-074!RES!!!F746!!!!
S!@baseboard_fab2_lib.baseboard_fab2(sch_1):page199_i110@mstr_discrete.res(chips)!RES_0402-33.2,1%,1/16W,CHIP,G2A!R1D30!//jf4cfls225.pdx.intel.com/apd_proj/ppg_lib/epg_masterlib/logical/mstr_discrete/res/chips/chips.prt!RES!RES_0402-33.2,1%,1/16W,CHIP,G21796-074!RES!!!F754!!!!
S!@baseboard_fab2_lib.baseboard_fab2(sch_1):page199_i109@mstr_discrete.res(chips)!RES_0402-33.2,1%,1/16W,CHIP,G2A!R1D26!//jf4cfls225.pdx.intel.com/apd_proj/ppg_lib/epg_masterlib/logical/mstr_discrete/res/chips/chips.prt!RES!RES_0402-33.2,1%,1/16W,CHIP,G21796-074!RES!!!F755!!!!
S!@baseboard_fab2_lib.baseboard_fab2(sch_1):page201_i128@mstr_discrete.res(chips)!RES_0402-33.2,1%,1/16W,CHIP,G2A!R6P45!//jf4cfls225.pdx.intel.com/apd_proj/ppg_lib/epg_masterlib/logical/mstr_discrete/res/chips/chips.prt!RES!RES_0402-33.2,1%,1/16W,CHIP,G21796-074!RES!!!F708!!!!
S!@baseboard_fab2_lib.baseboard_fab2(sch_1):page201_i127@mstr_discrete.res(chips)!RES_0402-33.2,1%,1/16W,CHIP,G2A!R4D65!//jf4cfls225.pdx.intel.com/apd_proj/ppg_lib/epg_masterlib/logical/mstr_discrete/res/chips/chips.prt!RES!RES_0402-33.2,1%,1/16W,CHIP,G21796-074!RES!!!F711!!!!
S!@baseboard_fab2_lib.baseboard_fab2(sch_1):page206_i117@mstr_discrete.res(chips)!RES_0402-33.2,1%,1/16W,CHIP,G2A!R9P3!//jf4cfls225.pdx.intel.com/apd_proj/ppg_lib/epg_masterlib/logical/mstr_discrete/res/chips/chips.prt!RES!RES_0402-33.2,1%,1/16W,CHIP,G21796-074!RES!!!F668!!!!
S!@baseboard_fab2_lib.baseboard_fab2(sch_1):page206_i116@mstr_discrete.res(chips)!RES_0402-33.2,1%,1/16W,CHIP,G2A!R1D1!//jf4cfls225.pdx.intel.com/apd_proj/ppg_lib/epg_masterlib/logical/mstr_discrete/res/chips/chips.prt!RES!RES_0402-33.2,1%,1/16W,CHIP,G21796-074!RES!!!F756!!!!
S!@baseboard_fab2_lib.baseboard_fab2(sch_1):page221_i54@mstr_discrete.res(chips)!RES_0402-33.2,1%,1/16W,CHIP,G2A!R4G19!//jf4cfls225.pdx.intel.com/apd_proj/ppg_lib/epg_masterlib/logical/mstr_discrete/res/chips/chips.prt!RES!RES_0402-33.2,1%,1/16W,CHIP,G21796-074!RES!!!F709!!!!
S!@baseboard_fab2_lib.baseboard_fab2(sch_1):page222_i51@mstr_discrete.res(chips)!RES_0402-33.2,1%,1/16W,CHIP,G2A!R4A6!//jf4cfls225.pdx.intel.com/apd_proj/ppg_lib/epg_masterlib/logical/mstr_discrete/res/chips/chips.prt!RES!RES_0402-33.2,1%,1/16W,CHIP,G21796-074!RES!!!F714!!!!
S!@baseboard_fab2_lib.baseboard_fab2(sch_1):page223_i82@mstr_discrete.res(chips)!RES_0402-33.2,1%,1/16W,CHIP,G2A!R1G8!//jf4cfls225.pdx.intel.com/apd_proj/ppg_lib/epg_masterlib/logical/mstr_discrete/res/chips/chips.prt!RES!RES_0402-33.2,1%,1/16W,CHIP,G21796-074!RES!!!F752!!!!
S!@baseboard_fab2_lib.baseboard_fab2(sch_1):page226_i82@mstr_discrete.res(chips)!RES_0402-33.2,1%,1/16W,CHIP,G2A!R1B4!//jf4cfls225.pdx.intel.com/apd_proj/ppg_lib/epg_masterlib/logical/mstr_discrete/res/chips/chips.prt!RES!RES_0402-33.2,1%,1/16W,CHIP,G21796-074!RES!!!F757!!!!
S!@baseboard_fab2_lib.baseboard_fab2(sch_1):page229_i51@mstr_discrete.res(chips)!RES_0402-33.2,1%,1/16W,CHIP,G2A!R4G15!//jf4cfls225.pdx.intel.com/apd_proj/ppg_lib/epg_masterlib/logical/mstr_discrete/res/chips/chips.prt!RES!RES_0402-33.2,1%,1/16W,CHIP,G21796-074!RES!!!F710!!!!
S!@baseboard_fab2_lib.baseboard_fab2(sch_1):page230_i51@mstr_discrete.res(chips)!RES_0402-33.2,1%,1/16W,CHIP,G2A!R4A4!//jf4cfls225.pdx.intel.com/apd_proj/ppg_lib/epg_masterlib/logical/mstr_discrete/res/chips/chips.prt!RES!RES_0402-33.2,1%,1/16W,CHIP,G21796-074!RES!!!F715!!!!
S!@baseboard_fab2_lib.baseboard_fab2(sch_1):page215_i297@mstr_discrete.res(chips)!RES_0402-33.2,1%,1/16W,CHIP,G2A!R7F23!//jf4cfls225.pdx.intel.com/apd_proj/ppg_lib/epg_masterlib/logical/mstr_discrete/res/chips/chips.prt!RES!RES_0402-33.2,1%,1/16W,CHIP,G21796-074!RES!!!F696!!!!
S!@baseboard_fab2_lib.baseboard_fab2(sch_1):page218_i12@mstr_discrete.res(chips)!RES_0402-33.2,1%,1/16W,CHIP,G2A!R7B1!//jf4cfls225.pdx.intel.com/apd_proj/ppg_lib/epg_masterlib/logical/mstr_discrete/res/chips/chips.prt!RES!RES_0402-33.2,1%,1/16W,CHIP,G21796-074!RES!!!F707!!!!
S!@baseboard_fab2_lib.baseboard_fab2(sch_1):page199_i108@mstr_discrete.res(chips)!RES_0402-33.2,1%,1/16W,CHIP,G2A!R1D33!//jf4cfls225.pdx.intel.com/apd_proj/ppg_lib/epg_masterlib/logical/mstr_discrete/res/chips/chips.prt!RES!RES_0402-33.2,1%,1/16W,CHIP,G21796-074!RES!!!F753!!!!
S!@baseboard_fab2_lib.baseboard_fab2(sch_1):page111_i68@mstr_discrete.res(chips)!RES_0402-33.2,1%,1/16W,CHIP,G2A!R1L29!//jf4cfls225.pdx.intel.com/apd_proj/ppg_lib/epg_masterlib/logical/mstr_discrete/res/chips/chips.prt!RES!RES_0402-33.2,1%,1/16W,CHIP,G21796-074!RES!!!F750!!M-SATA!!
S!@baseboard_fab2_lib.baseboard_fab2(sch_1):page145_i187@mstr_discrete.res(chips)!RES_0402-33.2,1%,1/16W,CHIP,G2A!R9G10!//jf4cfls225.pdx.intel.com/apd_proj/ppg_lib/epg_masterlib/logical/mstr_discrete/res/chips/chips.prt!RES!RES_0402-33.2,1%,1/16W,CHIP,G21796-074!RES!!!F670!!BMC!!
S!@baseboard_fab2_lib.baseboard_fab2(sch_1):page145_i188@mstr_discrete.res(chips)!RES_0402-33.2,1%,1/16W,CHIP,G2A!R9G16!//jf4cfls225.pdx.intel.com/apd_proj/ppg_lib/epg_masterlib/logical/mstr_discrete/res/chips/chips.prt!RES!RES_0402-33.2,1%,1/16W,CHIP,G21796-074!RES!!!F669!!BMC!!
S!@baseboard_fab2_lib.baseboard_fab2(sch_1):page136_i126@mstr_discrete.res(chips)!RES_0402-33.2,1%,1/16W,CHIP,G2A!R8E20!//jf4cfls225.pdx.intel.com/apd_proj/ppg_lib/epg_masterlib/logical/mstr_discrete/res/chips/chips.prt!RES!RES_0402-33.2,1%,1/16W,CHIP,G21796-074!RES!!!F686!!SB!!
S!@baseboard_fab2_lib.baseboard_fab2(sch_1):page156_i214@mstr_discrete.res(chips)!RES_0402-33.2,1%,1/16W,CHIP,G2A!R8E24!//jf4cfls225.pdx.intel.com/apd_proj/ppg_lib/epg_masterlib/logical/mstr_discrete/res/chips/chips.prt!RES!RES_0402-33.2,1%,1/16W,CHIP,G21796-074!RES!!!F685!!BMC_MISC!!
S!@baseboard_fab2_lib.baseboard_fab2(sch_1):page153_i109@mstr_discrete.res(chips)!RES_0402-33.2,1%,1/16W,CHIP,G2A!R7F3!//jf4cfls225.pdx.intel.com/apd_proj/ppg_lib/epg_masterlib/logical/mstr_discrete/res/chips/chips.prt!RES!RES_0402-33.2,1%,1/16W,CHIP,G21796-074!RES!!!F698!!SB_SPI!!
S!@baseboard_fab2_lib.baseboard_fab2(sch_1):page153_i157@mstr_discrete.res(chips)!RES_0402-33.2,1%,1/16W,CHIP,G2A!R3T1!//jf4cfls225.pdx.intel.com/apd_proj/ppg_lib/epg_masterlib/logical/mstr_discrete/res/chips/chips.prt!RES!RES_0402-33.2,1%,1/16W,CHIP,G21796-074!RES!!!F719!!SB_SPI!!
S!@baseboard_fab2_lib.baseboard_fab2(sch_1):page153_i181@mstr_discrete.res(chips)!RES_0402-33.2,1%,1/16W,CHIP,G2A!R7F29!//jf4cfls225.pdx.intel.com/apd_proj/ppg_lib/epg_masterlib/logical/mstr_discrete/res/chips/chips.prt!RES!RES_0402-33.2,1%,1/16W,CHIP,G21796-074!RES!!!F695!!SB_SPI!!
S!@baseboard_fab2_lib.baseboard_fab2(sch_1):page153_i184@mstr_discrete.res(chips)!RES_0402-33.2,1%,1/16W,CHIP,G2A!R3T10!//jf4cfls225.pdx.intel.com/apd_proj/ppg_lib/epg_masterlib/logical/mstr_discrete/res/chips/chips.prt!RES!RES_0402-33.2,1%,1/16W,CHIP,G21796-074!RES!!!F717!!SB_SPI!!
S!@baseboard_fab2_lib.baseboard_fab2(sch_1):page153_i108@mstr_discrete.res(chips)!RES_0402-33.2,1%,1/16W,CHIP,G2A!R7F37!//jf4cfls225.pdx.intel.com/apd_proj/ppg_lib/epg_masterlib/logical/mstr_discrete/res/chips/chips.prt!RES!RES_0402-33.2,1%,1/16W,CHIP,G21796-074!RES!!!F694!!SB_SPI!!
S!@baseboard_fab2_lib.baseboard_fab2(sch_1):page153_i156@mstr_discrete.res(chips)!RES_0402-33.2,1%,1/16W,CHIP,G2A!R3U1!//jf4cfls225.pdx.intel.com/apd_proj/ppg_lib/epg_masterlib/logical/mstr_discrete/res/chips/chips.prt!RES!RES_0402-33.2,1%,1/16W,CHIP,G21796-074!RES!!!F716!!SB_SPI!!
S!@baseboard_fab2_lib.baseboard_fab2(sch_1):page184_i88@mstr_discrete.res(chips)!RES_0402-33.2,1%,1/16W,CHIP,G2A!R8E9!//jf4cfls225.pdx.intel.com/apd_proj/ppg_lib/epg_masterlib/logical/mstr_discrete/res/chips/chips.prt!RES!RES_0402-33.2,1%,1/16W,CHIP,G21796-074!RES!!!F690!!TPM!!
S!@baseboard_fab2_lib.baseboard_fab2(sch_1):page184_i95@mstr_discrete.res(chips)!RES_0402-33.2,1%,1/16W,CHIP,G2A!R8E10!//jf4cfls225.pdx.intel.com/apd_proj/ppg_lib/epg_masterlib/logical/mstr_discrete/res/chips/chips.prt!RES!RES_0402-33.2,1%,1/16W,CHIP,G21796-074!RES!!!F689!!TPM!!
S!@baseboard_fab2_lib.baseboard_fab2(sch_1):page184_i93@mstr_discrete.res(chips)!RES_0402-33.2,1%,1/16W,CHIP,G2A!R8E13!//jf4cfls225.pdx.intel.com/apd_proj/ppg_lib/epg_masterlib/logical/mstr_discrete/res/chips/chips.prt!RES!RES_0402-33.2,1%,1/16W,CHIP,G21796-074!RES!!!F688!!TPM!!
S!@baseboard_fab2_lib.baseboard_fab2(sch_1):page121_i68@mstr_discrete.res(chips)!RES_0402-33.2,1%,1/16W,CHIP,G2A!R8D11!//jf4cfls225.pdx.intel.com/apd_proj/ppg_lib/epg_masterlib/logical/mstr_discrete/res/chips/chips.prt!RES!RES_0402-33.2,1%,1/16W,CHIP,G21796-074!RES!!!F693!!SB!!
S!@baseboard_fab2_lib.baseboard_fab2(sch_1):page121_i69@mstr_discrete.res(chips)!RES_0402-33.2,1%,1/16W,CHIP,G2A!R7C14!//jf4cfls225.pdx.intel.com/apd_proj/ppg_lib/epg_masterlib/logical/mstr_discrete/res/chips/chips.prt!RES!RES_0402-33.2,1%,1/16W,CHIP,G21796-074!RES!!!F706!!SB!!
S!@baseboard_fab2_lib.baseboard_fab2(sch_1):page139_i235@mstr_discrete.res(chips)!RES_0402-33.2,1%,1/16W,CHIP,G2A!R9E16!//jf4cfls225.pdx.intel.com/apd_proj/ppg_lib/epg_masterlib/logical/mstr_discrete/res/chips/chips.prt!RES!RES_0402-33.2,1%,1/16W,CHIP,G21796-074!RES!!!F674!!SB!!
S!@baseboard_fab2_lib.baseboard_fab2(sch_1):page101_i130@mstr_discrete.res(chips)!RES_0402-33.2,1%,1/16W,CHIP,G2A!R2T47!//jf4cfls225.pdx.intel.com/apd_proj/ppg_lib/epg_masterlib/logical/mstr_discrete/res/chips/chips.prt!RES!RES_0402-33.2,1%,1/16W,CHIP,G21796-074!RES!!!F729!!SYS_CLOCK!!
S!@baseboard_fab2_lib.baseboard_fab2(sch_1):page101_i133@mstr_discrete.res(chips)!RES_0402-33.2,1%,1/16W,CHIP,G2A!R8G1!//jf4cfls225.pdx.intel.com/apd_proj/ppg_lib/epg_masterlib/logical/mstr_discrete/res/chips/chips.prt!RES!RES_0402-33.2,1%,1/16W,CHIP,G21796-074!RES!!!F680!!!!
S!@baseboard_fab2_lib.baseboard_fab2(sch_1):page144_i554@mstr_discrete.res(chips)!RES_0402-33.2,1%,1/16W,CHIP,G2A!R3N28!//jf4cfls225.pdx.intel.com/apd_proj/ppg_lib/epg_masterlib/logical/mstr_discrete/res/chips/chips.prt!RES!RES_0402-33.2,1%,1/16W,CHIP,G21796-074!RES!!!F724!!BMC!!
S!@baseboard_fab2_lib.baseboard_fab2(sch_1):page144_i553@mstr_discrete.res(chips)!RES_0402-33.2,1%,1/16W,CHIP,G2A!R3N24!//jf4cfls225.pdx.intel.com/apd_proj/ppg_lib/epg_masterlib/logical/mstr_discrete/res/chips/chips.prt!RES!RES_0402-33.2,1%,1/16W,CHIP,G21796-074!RES!!!F728!!BMC!!
S!@baseboard_fab2_lib.baseboard_fab2(sch_1):page144_i555@mstr_discrete.res(chips)!RES_0402-33.2,1%,1/16W,CHIP,G2A!R3N26!//jf4cfls225.pdx.intel.com/apd_proj/ppg_lib/epg_masterlib/logical/mstr_discrete/res/chips/chips.prt!RES!RES_0402-33.2,1%,1/16W,CHIP,G21796-074!RES!!!F726!!BMC!!
S!@baseboard_fab2_lib.baseboard_fab2(sch_1):page101_i131@mstr_discrete.res(chips)!RES_0402-33.2,1%,1/16W,CHIP,G2A!R1T31!//jf4cfls225.pdx.intel.com/apd_proj/ppg_lib/epg_masterlib/logical/mstr_discrete/res/chips/chips.prt!RES!RES_0402-33.2,1%,1/16W,CHIP,G21796-074!RES!!!F749!!!!
S!@baseboard_fab2_lib.baseboard_fab2(sch_1):page101_i132@mstr_discrete.res(chips)!RES_0402-33.2,1%,1/16W,CHIP,G2A!R7D14!//jf4cfls225.pdx.intel.com/apd_proj/ppg_lib/epg_masterlib/logical/mstr_discrete/res/chips/chips.prt!RES!RES_0402-33.2,1%,1/16W,CHIP,G21796-074!RES!!!F704!!SB!!
S!@baseboard_fab2_lib.baseboard_fab2(sch_1):page144_i527@mstr_discrete.res(chips)!RES_0402-33.2,1%,1/16W,CHIP,G2A!R3N25!//jf4cfls225.pdx.intel.com/apd_proj/ppg_lib/epg_masterlib/logical/mstr_discrete/res/chips/chips.prt!RES!RES_0402-33.2,1%,1/16W,CHIP,G21796-074!RES!!!F727!!BMC!!
S!@baseboard_fab2_lib.baseboard_fab2(sch_1):page157_i358@mstr_discrete.res(chips)!RES_0402-33.2,1%,1/16W,CHIP,G2A!R2R10!//jf4cfls225.pdx.intel.com/apd_proj/ppg_lib/epg_masterlib/logical/mstr_discrete/res/chips/chips.prt!RES!RES_0402-33.2,1%,1/16W,CHIP,G21796-074!RES!!!F736!!MIO_CHASSIS!!
S!@baseboard_fab2_lib.baseboard_fab2(sch_1):page119_i172@mstr_discrete.res(chips)!RES_0402-33.2,1%,1/16W,CHIP,G2A!R2M3!//jf4cfls225.pdx.intel.com/apd_proj/ppg_lib/epg_masterlib/logical/mstr_discrete/res/chips/chips.prt!RES!RES_0402-33.2,1%,1/16W,CHIP,G21796-074!RES!!!F742!!CPLD!!
S!@baseboard_fab2_lib.baseboard_fab2(sch_1):page119_i173@mstr_discrete.res(chips)!RES_0402-33.2,1%,1/16W,CHIP,G2A!R2N1!//jf4cfls225.pdx.intel.com/apd_proj/ppg_lib/epg_masterlib/logical/mstr_discrete/res/chips/chips.prt!RES!RES_0402-33.2,1%,1/16W,CHIP,G21796-074!RES!!!F740!!CPLD!!
S!@baseboard_fab2_lib.baseboard_fab2(sch_1):page119_i174@mstr_discrete.res(chips)!RES_0402-33.2,1%,1/16W,CHIP,G2A!R2M7!//jf4cfls225.pdx.intel.com/apd_proj/ppg_lib/epg_masterlib/logical/mstr_discrete/res/chips/chips.prt!RES!RES_0402-33.2,1%,1/16W,CHIP,G21796-074!RES!!!F741!!CPLD!!
S!@baseboard_fab2_lib.baseboard_fab2(sch_1):page120_i218@mstr_discrete.res(chips)!RES_0402-33.2,1%,1/16W,CHIP,G2A!R2M1!//jf4cfls225.pdx.intel.com/apd_proj/ppg_lib/epg_masterlib/logical/mstr_discrete/res/chips/chips.prt!RES!RES_0402-33.2,1%,1/16W,CHIP,G21796-074!RES!!!F743!!CPLD!!
S!@baseboard_fab2_lib.baseboard_fab2(sch_1):page120_i219@mstr_discrete.res(chips)!RES_0402-33.2,1%,1/16W,CHIP,G2A!R2N26!//jf4cfls225.pdx.intel.com/apd_proj/ppg_lib/epg_masterlib/logical/mstr_discrete/res/chips/chips.prt!RES!RES_0402-33.2,1%,1/16W,CHIP,G21796-074!RES!!!F739!!CPLD!!
S!@baseboard_fab2_lib.baseboard_fab2(sch_1):page119_i189@mstr_discrete.res(chips)!RES_0402-33.2,1%,1/16W,CHIP,G2A!R2T14!//jf4cfls225.pdx.intel.com/apd_proj/ppg_lib/epg_masterlib/logical/mstr_discrete/res/chips/chips.prt!RES!RES_0402-33.2,1%,1/16W,CHIP,G21796-074!RES!!!F735!!SYS_CLOCK!!
S!@baseboard_fab2_lib.baseboard_fab2(sch_1):page92_i61@mstr_discrete.res(chips)!RES_0402-33.2,1%,1/16W,CHIP,G2A!R3R3!//jf4cfls225.pdx.intel.com/apd_proj/ppg_lib/epg_masterlib/logical/mstr_discrete/res/chips/chips.prt!RES!RES_0402-33.2,1%,1/16W,CHIP,G21796-074!RES!!!F720!!PROC_SIDEBAND!!
S!@baseboard_fab2_lib.baseboard_fab2(sch_1):page92_i70@mstr_discrete.res(chips)!RES_0402-33.2,1%,1/16W,CHIP,G2A!R7D25!//jf4cfls225.pdx.intel.com/apd_proj/ppg_lib/epg_masterlib/logical/mstr_discrete/res/chips/chips.prt!RES!RES_0402-33.2,1%,1/16W,CHIP,G21796-074!RES!!!F702!!PROC_SIDEBAND!!
S!@baseboard_fab2_lib.baseboard_fab2(sch_1):page93_i62@mstr_discrete.res(chips)!RES_0402-33.2,1%,1/16W,CHIP,G2A!R7D24!//jf4cfls225.pdx.intel.com/apd_proj/ppg_lib/epg_masterlib/logical/mstr_discrete/res/chips/chips.prt!RES!RES_0402-33.2,1%,1/16W,CHIP,G21796-074!RES!!!F703!!PROC_SIDEBAND!!
S!@baseboard_fab2_lib.baseboard_fab2(sch_1):page92_i14@mstr_discrete.res(chips)!RES_0402-33.2,1%,1/16W,CHIP,G2A!R3P42!//jf4cfls225.pdx.intel.com/apd_proj/ppg_lib/epg_masterlib/logical/mstr_discrete/res/chips/chips.prt!RES!RES_0402-33.2,1%,1/16W,CHIP,G21796-074!RES!!!F723!!PROC_SIDEBAND!!
S!@baseboard_fab2_lib.baseboard_fab2(sch_1):page92_i13@mstr_discrete.res(chips)!RES_0402-33.2,1%,1/16W,CHIP,G2A!R3P43!//jf4cfls225.pdx.intel.com/apd_proj/ppg_lib/epg_masterlib/logical/mstr_discrete/res/chips/chips.prt!RES!RES_0402-33.2,1%,1/16W,CHIP,G21796-074!RES!!!F722!!PROC_SIDEBAND!!
S!@baseboard_fab2_lib.baseboard_fab2(sch_1):page92_i12@mstr_discrete.res(chips)!RES_0402-33.2,1%,1/16W,CHIP,G2A!R3P46!//jf4cfls225.pdx.intel.com/apd_proj/ppg_lib/epg_masterlib/logical/mstr_discrete/res/chips/chips.prt!RES!RES_0402-33.2,1%,1/16W,CHIP,G21796-074!RES!!!F721!!PROC_SIDEBAND!!
S!@baseboard_fab2_lib.baseboard_fab2(sch_1):page92_i24@mstr_discrete.res(chips)!RES_0402-33.2,1%,1/16W,CHIP,G2A!R7D34!//jf4cfls225.pdx.intel.com/apd_proj/ppg_lib/epg_masterlib/logical/mstr_discrete/res/chips/chips.prt!RES!RES_0402-33.2,1%,1/16W,CHIP,G21796-074!RES!!!F699!!PROC_SIDEBAND!!
S!@baseboard_fab2_lib.baseboard_fab2(sch_1):page92_i29@mstr_discrete.res(chips)!RES_0402-33.2,1%,1/16W,CHIP,G2A!R7D31!//jf4cfls225.pdx.intel.com/apd_proj/ppg_lib/epg_masterlib/logical/mstr_discrete/res/chips/chips.prt!RES!RES_0402-33.2,1%,1/16W,CHIP,G21796-074!RES!!!F700!!PROC_SIDEBAND!!
S!@baseboard_fab2_lib.baseboard_fab2(sch_1):page92_i30@mstr_discrete.res(chips)!RES_0402-33.2,1%,1/16W,CHIP,G2A!R7D29!//jf4cfls225.pdx.intel.com/apd_proj/ppg_lib/epg_masterlib/logical/mstr_discrete/res/chips/chips.prt!RES!RES_0402-33.2,1%,1/16W,CHIP,G21796-074!RES!!!F701!!PROC_SIDEBAND!!
S!@baseboard_fab2_lib.baseboard_fab2(sch_1):page93_i42@mstr_discrete.res(chips)!RES_0402-33.2,1%,1/16W,CHIP,G2A!R2T30!//jf4cfls225.pdx.intel.com/apd_proj/ppg_lib/epg_masterlib/logical/mstr_discrete/res/chips/chips.prt!RES!RES_0402-33.2,1%,1/16W,CHIP,G21796-074!RES!!!F732!!PROC_SIDEBAND!!
S!@baseboard_fab2_lib.baseboard_fab2(sch_1):page93_i40@mstr_discrete.res(chips)!RES_0402-33.2,1%,1/16W,CHIP,G2A!R2T33!//jf4cfls225.pdx.intel.com/apd_proj/ppg_lib/epg_masterlib/logical/mstr_discrete/res/chips/chips.prt!RES!RES_0402-33.2,1%,1/16W,CHIP,G21796-074!RES!!!F731!!PROC_SIDEBAND!!
S!@baseboard_fab2_lib.baseboard_fab2(sch_1):page93_i39@mstr_discrete.res(chips)!RES_0402-33.2,1%,1/16W,CHIP,G2A!R2T38!//jf4cfls225.pdx.intel.com/apd_proj/ppg_lib/epg_masterlib/logical/mstr_discrete/res/chips/chips.prt!RES!RES_0402-33.2,1%,1/16W,CHIP,G21796-074!RES!!!F730!!PROC_SIDEBAND!!
S!@baseboard_fab2_lib.baseboard_fab2(sch_1):page146_i108@mstr_discrete.res(chips)!RES_0402-33.2,1%,1/16W,CHIP,G2A!R9F41!//jf4cfls225.pdx.intel.com/apd_proj/ppg_lib/epg_masterlib/logical/mstr_discrete/res/chips/chips.prt!RES!RES_0402-33.2,1%,1/16W,CHIP,G21796-074!RES!!!F671!!BMC!!
S!@baseboard_fab2_lib.baseboard_fab2(sch_1):page146_i109@mstr_discrete.res(chips)!RES_0402-33.2,1%,1/16W,CHIP,G2A!R9F21!//jf4cfls225.pdx.intel.com/apd_proj/ppg_lib/epg_masterlib/logical/mstr_discrete/res/chips/chips.prt!RES!RES_0402-33.2,1%,1/16W,CHIP,G21796-074!RES!!!F673!!BMC!!
S!@baseboard_fab2_lib.baseboard_fab2(sch_1):page144_i521@mstr_discrete.res(chips)!RES_0402-33.2,1%,1/16W,CHIP,G2A!R3N27!//jf4cfls225.pdx.intel.com/apd_proj/ppg_lib/epg_masterlib/logical/mstr_discrete/res/chips/chips.prt!RES!RES_0402-33.2,1%,1/16W,CHIP,G21796-074!RES!!!F725!!BMC!!
S!@baseboard_fab2_lib.baseboard_fab2(sch_1):page144_i520@mstr_discrete.res(chips)!RES_0402-33.2,1%,1/16W,CHIP,G2A!R2T24!//jf4cfls225.pdx.intel.com/apd_proj/ppg_lib/epg_masterlib/logical/mstr_discrete/res/chips/chips.prt!RES!RES_0402-33.2,1%,1/16W,CHIP,G21796-074!RES!!!F734!!BMC!!
S!@baseboard_fab2_lib.baseboard_fab2(sch_1):page152_i6@mstr_discrete.res(chips)!RES_0402-33.2,1%,1/16W,CHIP,G2A!R1U46!//jf4cfls225.pdx.intel.com/apd_proj/ppg_lib/epg_masterlib/logical/mstr_discrete/res/chips/chips.prt!RES!RES_0402-33.2,1%,1/16W,CHIP,G21796-074!RES!!!F744!!PROC_SIDEBAND!!
S!@baseboard_fab2_lib.baseboard_fab2(sch_1):page152_i14@mstr_discrete.res(chips)!RES_0402-33.2,1%,1/16W,CHIP,G2A!R9G31!//jf4cfls225.pdx.intel.com/apd_proj/ppg_lib/epg_masterlib/logical/mstr_discrete/res/chips/chips.prt!RES!RES_0402-33.2,1%,1/16W,CHIP,G21796-074!RES!!!F745!!PROC_SIDEBAND!!
S!@baseboard_fab2_lib.baseboard_fab2(sch_1):page152_i15@mstr_discrete.res(chips)!RES_0402-33.2,1%,1/16W,CHIP,G2A!R1U36!//jf4cfls225.pdx.intel.com/apd_proj/ppg_lib/epg_masterlib/logical/mstr_discrete/res/chips/chips.prt!RES!RES_0402-33.2,1%,1/16W,CHIP,G21796-074!RES!!!F747!!PROC_SIDEBAND!!
S!@baseboard_fab2_lib.baseboard_fab2(sch_1):page152_i16@mstr_discrete.res(chips)!RES_0402-33.2,1%,1/16W,CHIP,G2A!R1U34!//jf4cfls225.pdx.intel.com/apd_proj/ppg_lib/epg_masterlib/logical/mstr_discrete/res/chips/chips.prt!RES!RES_0402-33.2,1%,1/16W,CHIP,G21796-074!RES!!!F748!!PROC_TRANSLATORS!!
S!@baseboard_fab2_lib.baseboard_fab2(sch_1):page142_i2@mstr_discrete.res(chips)!RES_0402-33.2,1%,1/16W,CHIP,G2A!R8E17!//jf4cfls225.pdx.intel.com/apd_proj/ppg_lib/epg_masterlib/logical/mstr_discrete/res/chips/chips.prt!RES!RES_0402-33.2,1%,1/16W,CHIP,G21796-074!RES!!!F687!!PCIE_WAKE_BUFFER!!
S!@baseboard_fab2_lib.baseboard_fab2(sch_1):page175_i13@mstr_discrete.res(chips)!RES_0402-33.2,1%,1/16W,CHIP,G2A!R1L26!//jf4cfls225.pdx.intel.com/apd_proj/ppg_lib/epg_masterlib/logical/mstr_discrete/res/chips/chips.prt!RES!RES_0402-33.2,1%,1/16W,CHIP,G21796-074!RES!!!F751!!MIO_CHASSIS!!
S!@baseboard_fab2_lib.baseboard_fab2(sch_1):page153_i167@mstr_discrete.res(chips)!RES_0402-33.2,1%,1/16W,CHIP,G2A!R8F7!//jf4cfls225.pdx.intel.com/apd_proj/ppg_lib/epg_masterlib/logical/mstr_discrete/res/chips/chips.prt!RES!RES_0402-33.2,1%,1/16W,CHIP,G21796-074!RES!!!F684!!MIO_BIOS_MEM!!
S!@baseboard_fab2_lib.baseboard_fab2(sch_1):page181_i218@mstr_discrete.res(chips)!RES_0402-33.2,1%,1/16W,CHIP,G2A!R8E5!//jf4cfls225.pdx.intel.com/apd_proj/ppg_lib/epg_masterlib/logical/mstr_discrete/res/chips/chips.prt!RES!RES_0402-33.2,1%,1/16W,CHIP,G21796-074!RES!!!F691!!IO_SLOT!!
S!@baseboard_fab2_lib.baseboard_fab2(sch_1):page153_i155@mstr_discrete.res(chips)!RES_0402-33.2,1%,1/16W,CHIP,G2A!R3T2!//jf4cfls225.pdx.intel.com/apd_proj/ppg_lib/epg_masterlib/logical/mstr_discrete/res/chips/chips.prt!RES!RES_0402-33.2,1%,1/16W,CHIP,G21796-074!RES!!!F718!!SB_SPI!!
S!@baseboard_fab2_lib.baseboard_fab2(sch_1):page162_i13@mstr_discrete.res(chips)!RES_0402-33.2,1%,1/16W,CHIP,G2A!R8F12!//jf4cfls225.pdx.intel.com/apd_proj/ppg_lib/epg_masterlib/logical/mstr_discrete/res/chips/chips.prt!RES!RES_0402-33.2,1%,1/16W,CHIP,G21796-074!RES!!!F682!!BMC_BOOT_SPI!!
S!@baseboard_fab2_lib.baseboard_fab2(sch_1):page101_i20@mstr_discrete.res(chips)!RES_0402-33.2,1%,1/16W,CHIP,G2A!R8F29!//jf4cfls225.pdx.intel.com/apd_proj/ppg_lib/epg_masterlib/logical/mstr_discrete/res/chips/chips.prt!RES!RES_0402-33.2,1%,1/16W,CHIP,G21796-074!RES!!!F681!!SYS_CLOCK!!
S!@baseboard_fab2_lib.baseboard_fab2(sch_1):page140_i17@mstr_discrete.res(chips)!RES_0402-33.2,1%,1/16W,CHIP,G2A!R9E6!//jf4cfls225.pdx.intel.com/apd_proj/ppg_lib/epg_masterlib/logical/mstr_discrete/res/chips/chips.prt!RES!RES_0402-33.2,1%,1/16W,CHIP,G21796-074!RES!!!F677!!NIC_SPRV!!
S!@baseboard_fab2_lib.baseboard_fab2(sch_1):page139_i129@mstr_discrete.res(chips)!RES_0402-33.2,1%,1/16W,CHIP,G2A!R9E5!//jf4cfls225.pdx.intel.com/apd_proj/ppg_lib/epg_masterlib/logical/mstr_discrete/res/chips/chips.prt!RES!RES_0402-33.2,1%,1/16W,CHIP,G21796-074!RES!!!F678!!NIC_SPRV!!
S!@baseboard_fab2_lib.baseboard_fab2(sch_1):page139_i128@mstr_discrete.res(chips)!RES_0402-33.2,1%,1/16W,CHIP,G2A!R9E9!//jf4cfls225.pdx.intel.com/apd_proj/ppg_lib/epg_masterlib/logical/mstr_discrete/res/chips/chips.prt!RES!RES_0402-33.2,1%,1/16W,CHIP,G21796-074!RES!!!F675!!NIC_SPRV!!
S!@baseboard_fab2_lib.baseboard_fab2(sch_1):page139_i130@mstr_discrete.res(chips)!RES_0402-33.2,1%,1/16W,CHIP,G2A!R9E8!//jf4cfls225.pdx.intel.com/apd_proj/ppg_lib/epg_masterlib/logical/mstr_discrete/res/chips/chips.prt!RES!RES_0402-33.2,1%,1/16W,CHIP,G21796-074!RES!!!F676!!NIC_SPRV!!
S!@baseboard_fab2_lib.baseboard_fab2(sch_1):page153_i166@mstr_discrete.res(chips)!RES_0402-33.2,1%,1/16W,CHIP,G2A!R8F8!//jf4cfls225.pdx.intel.com/apd_proj/ppg_lib/epg_masterlib/logical/mstr_discrete/res/chips/chips.prt!RES!RES_0402-33.2,1%,1/16W,CHIP,G21796-074!RES!!!F683!!MIO_BIOS_MEM!!
S!@baseboard_fab2_lib.baseboard_fab2(sch_1):page121_i33@mstr_discrete.res(chips)!RES_0402-33.2,1%,1/16W,CHIP,G2A!R7C16!//jf4cfls225.pdx.intel.com/apd_proj/ppg_lib/epg_masterlib/logical/mstr_discrete/res/chips/chips.prt!RES!RES_0402-33.2,1%,1/16W,CHIP,G21796-074!RES!!!F705!!SB!!
S!@baseboard_fab2_lib.baseboard_fab2(sch_1):page134_i14@mstr_discrete.res(chips)!RES_0402-33.2,1%,1/16W,CHIP,G2A!R9A13!//jf4cfls225.pdx.intel.com/apd_proj/ppg_lib/epg_masterlib/logical/mstr_discrete/res/chips/chips.prt!RES!RES_0402-33.2,1%,1/16W,CHIP,G21796-074!RES!!!F679!!SB!!
S!@baseboard_fab2_lib.baseboard_fab2(sch_1):page153_i98@mstr_discrete.res(chips)!RES_0402-33.2,1%,1/16W,CHIP,G2A!R7F4!//jf4cfls225.pdx.intel.com/apd_proj/ppg_lib/epg_masterlib/logical/mstr_discrete/res/chips/chips.prt!RES!RES_0402-33.2,1%,1/16W,CHIP,G21796-074!RES!!!F697!!SB_SPI!!
S!@baseboard_fab2_lib.baseboard_fab2(sch_1):page191_i193@mstr_discrete.res(chips)!RES_0402-4.75K,1%,1/16W,CHIP,GA!R7D42!//jf4cfls225.pdx.intel.com/apd_proj/ppg_lib/epg_masterlib/logical/mstr_discrete/res/chips/chips.prt!RES!RES_0402-4.75K,1%,1/16W,CHIP,G21796-072!RES!!!F529!!CPLD!!
S!@baseboard_fab2_lib.baseboard_fab2(sch_1):page161_i70@mstr_discrete.res(chips)!RES_0402-4.75K,1%,1/16W,CHIP,GA!R1B21!//jf4cfls225.pdx.intel.com/apd_proj/ppg_lib/epg_masterlib/logical/mstr_discrete/res/chips/chips.prt!RES!RES_0402-4.75K,1%,1/16W,CHIP,G21796-072!RES!!!F650!!CPU_FANS!!
S!@baseboard_fab2_lib.baseboard_fab2(sch_1):page161_i45@mstr_discrete.res(chips)!RES_0402-4.75K,1%,1/16W,CHIP,GA!R1F1!//jf4cfls225.pdx.intel.com/apd_proj/ppg_lib/epg_masterlib/logical/mstr_discrete/res/chips/chips.prt!RES!RES_0402-4.75K,1%,1/16W,CHIP,G21796-072!RES!!!F645!!CPU_FANS!!
S!@baseboard_fab2_lib.baseboard_fab2(sch_1):page135_i104@mstr_discrete.res(chips)!RES_0402-4.75K,1%,1/16W,CHIP,GA!R2P17!//jf4cfls225.pdx.intel.com/apd_proj/ppg_lib/epg_masterlib/logical/mstr_discrete/res/chips/chips.prt!RES!RES_0402-4.75K,1%,1/16W,CHIP,G21796-072!RES!!!F557!!THERMTRIP_PCH!!
S!@baseboard_fab2_lib.baseboard_fab2(sch_1):page108_i343@mstr_discrete.res(chips)!RES_0402-4.75K,1%,1/16W,CHIP,GA!R7E21!//jf4cfls225.pdx.intel.com/apd_proj/ppg_lib/epg_masterlib/logical/mstr_discrete/res/chips/chips.prt!RES!RES_0402-4.75K,1%,1/16W,CHIP,G21796-072!RES!!!F531!!IO_SLOT!!
S!@baseboard_fab2_lib.baseboard_fab2(sch_1):page119_i213@mstr_discrete.res(chips)!RES_0402-4.75K,1%,1/16W,CHIP,GA!R2U48!//jf4cfls225.pdx.intel.com/apd_proj/ppg_lib/epg_masterlib/logical/mstr_discrete/res/chips/chips.prt!RES!RES_0402-4.75K,1%,1/16W,CHIP,G21796-072!RES!!!F530!!!!
S!@baseboard_fab2_lib.baseboard_fab2(sch_1):page166_i28@mstr_discrete.res(chips)!RES_0402-4.75K,1%,1/16W,CHIP,GA!R7C17!//jf4cfls225.pdx.intel.com/apd_proj/ppg_lib/epg_masterlib/logical/mstr_discrete/res/chips/chips.prt!RES!RES_0402-4.75K,1%,1/16W,CHIP,G21796-072!RES!!!F600!!PECI!!
S!@baseboard_fab2_lib.baseboard_fab2(sch_1):page133_i243@mstr_discrete.res(chips)!RES_0402-4.75K,1%,1/16W,CHIP,GA!R7D3!//jf4cfls225.pdx.intel.com/apd_proj/ppg_lib/epg_masterlib/logical/mstr_discrete/res/chips/chips.prt!RES!RES_0402-4.75K,1%,1/16W,CHIP,G21796-072!RES!!!F599!!SB!!
S!@baseboard_fab2_lib.baseboard_fab2(sch_1):page133_i341@mstr_discrete.res(chips)!RES_0402-4.75K,1%,1/16W,CHIP,GA!R2N32!//jf4cfls225.pdx.intel.com/apd_proj/ppg_lib/epg_masterlib/logical/mstr_discrete/res/chips/chips.prt!RES!RES_0402-4.75K,1%,1/16W,CHIP,G21796-072!RES!!!F590!!SB!!
S!@baseboard_fab2_lib.baseboard_fab2(sch_1):page133_i301@mstr_discrete.res(chips)!RES_0402-4.75K,1%,1/16W,CHIP,GA!R8D14!//jf4cfls225.pdx.intel.com/apd_proj/ppg_lib/epg_masterlib/logical/mstr_discrete/res/chips/chips.prt!RES!RES_0402-4.75K,1%,1/16W,CHIP,G21796-072!RES!!!F573!!SB!!
S!@baseboard_fab2_lib.baseboard_fab2(sch_1):page156_i340@mstr_discrete.res(chips)!RES_0402-4.75K,1%,1/16W,CHIP,GA!R3P52!//jf4cfls225.pdx.intel.com/apd_proj/ppg_lib/epg_masterlib/logical/mstr_discrete/res/chips/chips.prt!RES!RES_0402-4.75K,1%,1/16W,CHIP,G21796-072!RES!!!F532!!BMC!!
S!@baseboard_fab2_lib.baseboard_fab2(sch_1):page156_i294@mstr_discrete.res(chips)!RES_0402-4.75K,1%,1/16W,CHIP,GA!R4C14!//jf4cfls225.pdx.intel.com/apd_proj/ppg_lib/epg_masterlib/logical/mstr_discrete/res/chips/chips.prt!RES!RES_0402-4.75K,1%,1/16W,CHIP,G21796-072!RES!!!F535!!BMC_MISC!!
S!@baseboard_fab2_lib.baseboard_fab2(sch_1):page133_i356@mstr_discrete.res(chips)!RES_0402-4.75K,1%,1/16W,CHIP,GA!R3P55!//jf4cfls225.pdx.intel.com/apd_proj/ppg_lib/epg_masterlib/logical/mstr_discrete/res/chips/chips.prt!RES!RES_0402-4.75K,1%,1/16W,CHIP,G21796-072!RES!!!F534!!SB_PU_PD!!
S!@baseboard_fab2_lib.baseboard_fab2(sch_1):page133_i357@mstr_discrete.res(chips)!RES_0402-4.75K,1%,1/16W,CHIP,GA!R3P53!//jf4cfls225.pdx.intel.com/apd_proj/ppg_lib/epg_masterlib/logical/mstr_discrete/res/chips/chips.prt!RES!RES_0402-4.75K,1%,1/16W,CHIP,G21796-072!RES!!!F533!!SB_PU_PD!!
S!@baseboard_fab2_lib.baseboard_fab2(sch_1):page133_i349@mstr_discrete.res(chips)!RES_0402-4.75K,1%,1/16W,CHIP,GA!R2N30!//jf4cfls225.pdx.intel.com/apd_proj/ppg_lib/epg_masterlib/logical/mstr_discrete/res/chips/chips.prt!RES!RES_0402-4.75K,1%,1/16W,CHIP,G21796-072!RES!!!F537!!SB!!
S!@baseboard_fab2_lib.baseboard_fab2(sch_1):page133_i352@mstr_discrete.res(chips)!RES_0402-4.75K,1%,1/16W,CHIP,GA!R2N29!//jf4cfls225.pdx.intel.com/apd_proj/ppg_lib/epg_masterlib/logical/mstr_discrete/res/chips/chips.prt!RES!RES_0402-4.75K,1%,1/16W,CHIP,G21796-072!RES!!!F536!!SB!!
S!@baseboard_fab2_lib.baseboard_fab2(sch_1):page196_i115@mstr_discrete.res(chips)!RES_0402-4.75K,1%,1/16W,CHIP,GA!R8D37!//jf4cfls225.pdx.intel.com/apd_proj/ppg_lib/epg_masterlib/logical/mstr_discrete/res/chips/chips.prt!RES!RES_0402-4.75K,1%,1/16W,CHIP,G21796-072!RES!!!F538!!V_SUPER!!
S!@baseboard_fab2_lib.baseboard_fab2(sch_1):page192_i48@mstr_discrete.res(chips)!RES_0402-4.75K,1%,1/16W,CHIP,GA!R3R16!//jf4cfls225.pdx.intel.com/apd_proj/ppg_lib/epg_masterlib/logical/mstr_discrete/res/chips/chips.prt!RES!RES_0402-4.75K,1%,1/16W,CHIP,G21796-072!RES!!!F629!!CPLD!!
S!@baseboard_fab2_lib.baseboard_fab2(sch_1):page192_i49@mstr_discrete.res(chips)!RES_0402-4.75K,1%,1/16W,CHIP,GA!R6M9!//jf4cfls225.pdx.intel.com/apd_proj/ppg_lib/epg_masterlib/logical/mstr_discrete/res/chips/chips.prt!RES!RES_0402-4.75K,1%,1/16W,CHIP,G21796-072!RES!!!F614!!CPLD!!
S!@baseboard_fab2_lib.baseboard_fab2(sch_1):page102_i93@mstr_discrete.res(chips)!RES_0402-4.75K,1%,1/16W,CHIP,GA!R4D69!//jf4cfls225.pdx.intel.com/apd_proj/ppg_lib/epg_masterlib/logical/mstr_discrete/res/chips/chips.prt!RES!RES_0402-4.75K,1%,1/16W,CHIP,G21796-072!RES!!!F604!!DB1200ZL!!
S!@baseboard_fab2_lib.baseboard_fab2(sch_1):page102_i94@mstr_discrete.res(chips)!RES_0402-4.75K,1%,1/16W,CHIP,GA!R4D70!//jf4cfls225.pdx.intel.com/apd_proj/ppg_lib/epg_masterlib/logical/mstr_discrete/res/chips/chips.prt!RES!RES_0402-4.75K,1%,1/16W,CHIP,G21796-072!RES!!!F601!!DB1200ZL!!
S!@baseboard_fab2_lib.baseboard_fab2(sch_1):page154_i127@mstr_discrete.res(chips)!RES_0402-4.75K,1%,1/16W,CHIP,GA!R2T6!//jf4cfls225.pdx.intel.com/apd_proj/ppg_lib/epg_masterlib/logical/mstr_discrete/res/chips/chips.prt!RES!RES_0402-4.75K,1%,1/16W,CHIP,G21796-072!RES!!!F625!!SB_BMC_SPI_MUX!!
S!@baseboard_fab2_lib.baseboard_fab2(sch_1):page21_i258@mstr_discrete.res(chips)!RES_0402-4.75K,1%,1/16W,CHIP,GA!R4R5!//jf4cfls225.pdx.intel.com/apd_proj/ppg_lib/epg_masterlib/logical/mstr_discrete/res/chips/chips.prt!RES!RES_0402-4.75K,1%,1/16W,CHIP,G21796-072!RES!!!F607!!CPU0!!
S!@baseboard_fab2_lib.baseboard_fab2(sch_1):page55_i181@mstr_discrete.res(chips)!RES_0402-4.75K,1%,1/16W,CHIP,GA!R6P39!//jf4cfls225.pdx.intel.com/apd_proj/ppg_lib/epg_masterlib/logical/mstr_discrete/res/chips/chips.prt!RES!RES_0402-4.75K,1%,1/16W,CHIP,G21796-072!RES!!!F602!!CPU1!!
S!@baseboard_fab2_lib.baseboard_fab2(sch_1):page170_i71@mstr_discrete.res(chips)!RES_0402-4.75K,1%,1/16W,CHIP,GA!R8D26!//jf4cfls225.pdx.intel.com/apd_proj/ppg_lib/epg_masterlib/logical/mstr_discrete/res/chips/chips.prt!RES!RES_0402-4.75K,1%,1/16W,CHIP,G21796-072!RES!!!F571!!FAST_PROCHOT!!
S!@baseboard_fab2_lib.baseboard_fab2(sch_1):page170_i73@mstr_discrete.res(chips)!RES_0402-4.75K,1%,1/16W,CHIP,GA!R1R5!//jf4cfls225.pdx.intel.com/apd_proj/ppg_lib/epg_masterlib/logical/mstr_discrete/res/chips/chips.prt!RES!RES_0402-4.75K,1%,1/16W,CHIP,G21796-072!RES!!!F641!!FAST_PROCHOT!!
S!@baseboard_fab2_lib.baseboard_fab2(sch_1):page157_i385@mstr_discrete.res(chips)!RES_0402-4.75K,1%,1/16W,CHIP,GA!R8E32!//jf4cfls225.pdx.intel.com/apd_proj/ppg_lib/epg_masterlib/logical/mstr_discrete/res/chips/chips.prt!RES!RES_0402-4.75K,1%,1/16W,CHIP,G21796-072!RES!!!F564!!MIO_CHASSIS!!
S!@baseboard_fab2_lib.baseboard_fab2(sch_1):page161_i135@mstr_discrete.res(chips)!RES_0402-4.75K,1%,1/16W,CHIP,GA!R9T5!//jf4cfls225.pdx.intel.com/apd_proj/ppg_lib/epg_masterlib/logical/mstr_discrete/res/chips/chips.prt!RES!RES_0402-4.75K,1%,1/16W,CHIP,G21796-072!RES!!!F540!!CPU_FANS!!
S!@baseboard_fab2_lib.baseboard_fab2(sch_1):page161_i126@mstr_discrete.res(chips)!RES_0402-4.75K,1%,1/16W,CHIP,GA!R1B24!//jf4cfls225.pdx.intel.com/apd_proj/ppg_lib/epg_masterlib/logical/mstr_discrete/res/chips/chips.prt!RES!RES_0402-4.75K,1%,1/16W,CHIP,G21796-072!RES!!!F649!!CPU_FANS!!
S!@baseboard_fab2_lib.baseboard_fab2(sch_1):page133_i333@mstr_discrete.res(chips)!RES_0402-4.75K,1%,1/16W,CHIP,GA!R8C25!//jf4cfls225.pdx.intel.com/apd_proj/ppg_lib/epg_masterlib/logical/mstr_discrete/res/chips/chips.prt!RES!RES_0402-4.75K,1%,1/16W,CHIP,G21796-072!RES!!!F574!!SB_PU_PD!!
S!@baseboard_fab2_lib.baseboard_fab2(sch_1):page177_i82@mstr_discrete.res(chips)!RES_0402-4.75K,1%,1/16W,CHIP,GA!R9F52!//jf4cfls225.pdx.intel.com/apd_proj/ppg_lib/epg_masterlib/logical/mstr_discrete/res/chips/chips.prt!RES!RES_0402-4.75K,1%,1/16W,CHIP,G21796-072!RES!!!F543!!BMC!!
S!@baseboard_fab2_lib.baseboard_fab2(sch_1):page177_i76@mstr_discrete.res(chips)!RES_0402-4.75K,1%,1/16W,CHIP,GA!R9F30!//jf4cfls225.pdx.intel.com/apd_proj/ppg_lib/epg_masterlib/logical/mstr_discrete/res/chips/chips.prt!RES!RES_0402-4.75K,1%,1/16W,CHIP,G21796-072!RES!!!F547!!BMC!!
S!@baseboard_fab2_lib.baseboard_fab2(sch_1):page196_i59@mstr_discrete.res(chips)!RES_0402-4.75K,1%,1/16W,CHIP,GA!R3P44!//jf4cfls225.pdx.intel.com/apd_proj/ppg_lib/epg_masterlib/logical/mstr_discrete/res/chips/chips.prt!RES!RES_0402-4.75K,1%,1/16W,CHIP,G21796-072!RES!!!F613!!V_SUPER!!
S!@baseboard_fab2_lib.baseboard_fab2(sch_1):page157_i382@mstr_discrete.res(chips)!RES_0402-4.75K,1%,1/16W,CHIP,GA!R1L7!//jf4cfls225.pdx.intel.com/apd_proj/ppg_lib/epg_masterlib/logical/mstr_discrete/res/chips/chips.prt!RES!RES_0402-4.75K,1%,1/16W,CHIP,G21796-072!RES!!!F644!!BMC_MISC!!
S!@baseboard_fab2_lib.baseboard_fab2(sch_1):page200_i204@mstr_discrete.res(chips)!RES_0402-4.75K,1%,1/16W,CHIP,GA!R1D21!//jf4cfls225.pdx.intel.com/apd_proj/ppg_lib/epg_masterlib/logical/mstr_discrete/res/chips/chips.prt!RES!RES_0402-4.75K,1%,1/16W,CHIP,G21796-072!RES!!!F648!!HOT_SWAP!!
S!@baseboard_fab2_lib.baseboard_fab2(sch_1):page150_i66@mstr_discrete.res(chips)!RES_0402-4.75K,1%,1/16W,CHIP,GA!R1R11!//jf4cfls225.pdx.intel.com/apd_proj/ppg_lib/epg_masterlib/logical/mstr_discrete/res/chips/chips.prt!RES!RES_0402-4.75K,1%,1/16W,CHIP,G21796-072!RES!!!F640!!BMC!!
S!@baseboard_fab2_lib.baseboard_fab2(sch_1):page157_i335@mstr_discrete.res(chips)!RES_0402-4.75K,1%,1/16W,CHIP,GA!R8D25!//jf4cfls225.pdx.intel.com/apd_proj/ppg_lib/epg_masterlib/logical/mstr_discrete/res/chips/chips.prt!RES!RES_0402-4.75K,1%,1/16W,CHIP,G21796-072!RES!!!F572!!BMC_MISC!!
S!@baseboard_fab2_lib.baseboard_fab2(sch_1):page134_i27@mstr_discrete.res(chips)!RES_0402-4.75K,1%,1/16W,CHIP,GA!R7D30!//jf4cfls225.pdx.intel.com/apd_proj/ppg_lib/epg_masterlib/logical/mstr_discrete/res/chips/chips.prt!RES!RES_0402-4.75K,1%,1/16W,CHIP,G21796-072!RES!!!F597!!UART_MUX!!
S!@baseboard_fab2_lib.baseboard_fab2(sch_1):page189_i56@mstr_discrete.res(chips)!RES_0402-4.75K,1%,1/16W,CHIP,GA!R8G23!//jf4cfls225.pdx.intel.com/apd_proj/ppg_lib/epg_masterlib/logical/mstr_discrete/res/chips/chips.prt!RES!RES_0402-4.75K,1%,1/16W,CHIP,G21796-072!RES!!!F558!!BMC_DEBUG_HEADER!!
S!@baseboard_fab2_lib.baseboard_fab2(sch_1):page102_i91@mstr_discrete.res(chips)!RES_0402-4.75K,1%,1/16W,CHIP,GA!R6P48!//jf4cfls225.pdx.intel.com/apd_proj/ppg_lib/epg_masterlib/logical/mstr_discrete/res/chips/chips.prt!RES!RES_0402-4.75K,1%,1/16W,CHIP,G21796-072!RES!!!F615!!DB1200ZL!!
S!@baseboard_fab2_lib.baseboard_fab2(sch_1):page136_i133@mstr_discrete.res(chips)!RES_0402-4.75K,1%,1/16W,CHIP,GA!R8E14!//jf4cfls225.pdx.intel.com/apd_proj/ppg_lib/epg_masterlib/logical/mstr_discrete/res/chips/chips.prt!RES!RES_0402-4.75K,1%,1/16W,CHIP,G21796-072!RES!!!F568!!SB!!
S!@baseboard_fab2_lib.baseboard_fab2(sch_1):page156_i267@mstr_discrete.res(chips)!RES_0402-4.75K,1%,1/16W,CHIP,GA!R8G2!//jf4cfls225.pdx.intel.com/apd_proj/ppg_lib/epg_masterlib/logical/mstr_discrete/res/chips/chips.prt!RES!RES_0402-4.75K,1%,1/16W,CHIP,G21796-072!RES!!!F559!!BMC_MISC!!
S!@baseboard_fab2_lib.baseboard_fab2(sch_1):page156_i265@mstr_discrete.res(chips)!RES_0402-4.75K,1%,1/16W,CHIP,GA!R2U2!//jf4cfls225.pdx.intel.com/apd_proj/ppg_lib/epg_masterlib/logical/mstr_discrete/res/chips/chips.prt!RES!RES_0402-4.75K,1%,1/16W,CHIP,G21796-072!RES!!!F621!!BMC_MISC!!
S!@baseboard_fab2_lib.baseboard_fab2(sch_1):page157_i367@mstr_discrete.res(chips)!RES_0402-4.75K,1%,1/16W,CHIP,GA!R2U4!//jf4cfls225.pdx.intel.com/apd_proj/ppg_lib/epg_masterlib/logical/mstr_discrete/res/chips/chips.prt!RES!RES_0402-4.75K,1%,1/16W,CHIP,G21796-072!RES!!!F620!!BMC_MISC!!
S!@baseboard_fab2_lib.baseboard_fab2(sch_1):page157_i361@mstr_discrete.res(chips)!RES_0402-4.75K,1%,1/16W,CHIP,GA!R8E19!//jf4cfls225.pdx.intel.com/apd_proj/ppg_lib/epg_masterlib/logical/mstr_discrete/res/chips/chips.prt!RES!RES_0402-4.75K,1%,1/16W,CHIP,G21796-072!RES!!!F567!!BMC_MISC!!
S!@baseboard_fab2_lib.baseboard_fab2(sch_1):page126_i12@mstr_discrete.res(chips)!RES_0402-4.75K,1%,1/16W,CHIP,GA!R1D35!//jf4cfls225.pdx.intel.com/apd_proj/ppg_lib/epg_masterlib/logical/mstr_discrete/res/chips/chips.prt!RES!RES_0402-4.75K,1%,1/16W,CHIP,G21796-072!RES!!!F647!!BMC_MISC!!
S!@baseboard_fab2_lib.baseboard_fab2(sch_1):page170_i61@mstr_discrete.res(chips)!RES_0402-4.75K,1%,1/16W,CHIP,GA!R2P13!//jf4cfls225.pdx.intel.com/apd_proj/ppg_lib/epg_masterlib/logical/mstr_discrete/res/chips/chips.prt!RES!RES_0402-4.75K,1%,1/16W,CHIP,G21796-072!RES!!!F628!!PROC_SIDEBAND!!
S!@baseboard_fab2_lib.baseboard_fab2(sch_1):page170_i65@mstr_discrete.res(chips)!RES_0402-4.75K,1%,1/16W,CHIP,GA!R9F3!//jf4cfls225.pdx.intel.com/apd_proj/ppg_lib/epg_masterlib/logical/mstr_discrete/res/chips/chips.prt!RES!RES_0402-4.75K,1%,1/16W,CHIP,G21796-072!RES!!!F553!!PROC_SIDEBAND!!
S!@baseboard_fab2_lib.baseboard_fab2(sch_1):page119_i186@mstr_discrete.res(chips)!RES_0402-4.75K,1%,1/16W,CHIP,GA!R9A21!//jf4cfls225.pdx.intel.com/apd_proj/ppg_lib/epg_masterlib/logical/mstr_discrete/res/chips/chips.prt!RES!RES_0402-4.75K,1%,1/16W,CHIP,G21796-072!RES!!!F555!!SB!!
S!@baseboard_fab2_lib.baseboard_fab2(sch_1):page119_i183@mstr_discrete.res(chips)!RES_0402-4.75K,1%,1/16W,CHIP,GA!R9A18!//jf4cfls225.pdx.intel.com/apd_proj/ppg_lib/epg_masterlib/logical/mstr_discrete/res/chips/chips.prt!RES!RES_0402-4.75K,1%,1/16W,CHIP,G21796-072!RES!!!F556!!SB!!
S!@baseboard_fab2_lib.baseboard_fab2(sch_1):page147_i140@mstr_discrete.res(chips)!RES_0402-4.75K,1%,1/16W,CHIP,GA!R8B25!//jf4cfls225.pdx.intel.com/apd_proj/ppg_lib/epg_masterlib/logical/mstr_discrete/res/chips/chips.prt!RES!RES_0402-4.75K,1%,1/16W,CHIP,G21796-072!RES!!!F581!!BMC!!
S!@baseboard_fab2_lib.baseboard_fab2(sch_1):page157_i348@mstr_discrete.res(chips)!RES_0402-4.75K,1%,1/16W,CHIP,GA!R2M5!//jf4cfls225.pdx.intel.com/apd_proj/ppg_lib/epg_masterlib/logical/mstr_discrete/res/chips/chips.prt!RES!RES_0402-4.75K,1%,1/16W,CHIP,G21796-072!RES!!!F635!!BMC_MISC!!
S!@baseboard_fab2_lib.baseboard_fab2(sch_1):page170_i54@mstr_discrete.res(chips)!RES_0402-4.75K,1%,1/16W,CHIP,GA!R2T3!//jf4cfls225.pdx.intel.com/apd_proj/ppg_lib/epg_masterlib/logical/mstr_discrete/res/chips/chips.prt!RES!RES_0402-4.75K,1%,1/16W,CHIP,G21796-072!RES!!!F626!!FAST_PROCHOT!!
S!@baseboard_fab2_lib.baseboard_fab2(sch_1):page170_i56@mstr_discrete.res(chips)!RES_0402-4.75K,1%,1/16W,CHIP,GA!R2P5!//jf4cfls225.pdx.intel.com/apd_proj/ppg_lib/epg_masterlib/logical/mstr_discrete/res/chips/chips.prt!RES!RES_0402-4.75K,1%,1/16W,CHIP,G21796-072!RES!!!F631!!PROC_SIDEBAND!!
S!@baseboard_fab2_lib.baseboard_fab2(sch_1):page133_i326@mstr_discrete.res(chips)!RES_0402-4.75K,1%,1/16W,CHIP,GA!R8C1!//jf4cfls225.pdx.intel.com/apd_proj/ppg_lib/epg_masterlib/logical/mstr_discrete/res/chips/chips.prt!RES!RES_0402-4.75K,1%,1/16W,CHIP,G21796-072!RES!!!F579!!SB_PU_PD!!
S!@baseboard_fab2_lib.baseboard_fab2(sch_1):page133_i327@mstr_discrete.res(chips)!RES_0402-4.75K,1%,1/16W,CHIP,GA!R8C7!//jf4cfls225.pdx.intel.com/apd_proj/ppg_lib/epg_masterlib/logical/mstr_discrete/res/chips/chips.prt!RES!RES_0402-4.75K,1%,1/16W,CHIP,G21796-072!RES!!!F576!!SB_PU_PD!!
S!@baseboard_fab2_lib.baseboard_fab2(sch_1):page126_i20@mstr_discrete.res(chips)!RES_0402-4.75K,1%,1/16W,CHIP,GA!R8C9!//jf4cfls225.pdx.intel.com/apd_proj/ppg_lib/epg_masterlib/logical/mstr_discrete/res/chips/chips.prt!RES!RES_0402-4.75K,1%,1/16W,CHIP,G21796-072!RES!!!F575!!BMC_MISC!!
S!@baseboard_fab2_lib.baseboard_fab2(sch_1):page156_i206@mstr_discrete.res(chips)!RES_0402-4.75K,1%,1/16W,CHIP,GA!R2T34!//jf4cfls225.pdx.intel.com/apd_proj/ppg_lib/epg_masterlib/logical/mstr_discrete/res/chips/chips.prt!RES!RES_0402-4.75K,1%,1/16W,CHIP,G21796-072!RES!!!F623!!BMC_MISC!!
S!@baseboard_fab2_lib.baseboard_fab2(sch_1):page156_i207@mstr_discrete.res(chips)!RES_0402-4.75K,1%,1/16W,CHIP,GA!R2T35!//jf4cfls225.pdx.intel.com/apd_proj/ppg_lib/epg_masterlib/logical/mstr_discrete/res/chips/chips.prt!RES!RES_0402-4.75K,1%,1/16W,CHIP,G21796-072!RES!!!F622!!BMC_MISC!!
S!@baseboard_fab2_lib.baseboard_fab2(sch_1):page102_i53@mstr_discrete.res(chips)!RES_0402-4.75K,1%,1/16W,CHIP,GA!R4D41!//jf4cfls225.pdx.intel.com/apd_proj/ppg_lib/epg_masterlib/logical/mstr_discrete/res/chips/chips.prt!RES!RES_0402-4.75K,1%,1/16W,CHIP,G21796-072!RES!!!F608!!DB1200ZL!!
S!@baseboard_fab2_lib.baseboard_fab2(sch_1):page133_i309@mstr_discrete.res(chips)!RES_0402-4.75K,1%,1/16W,CHIP,GA!R2N7!//jf4cfls225.pdx.intel.com/apd_proj/ppg_lib/epg_masterlib/logical/mstr_discrete/res/chips/chips.prt!RES!RES_0402-4.75K,1%,1/16W,CHIP,G21796-072!RES!!!F634!!SB_PU_PD!!
S!@baseboard_fab2_lib.baseboard_fab2(sch_1):page161_i51@mstr_discrete.res(chips)!RES_0402-4.75K,1%,1/16W,CHIP,GA!R1E12!//jf4cfls225.pdx.intel.com/apd_proj/ppg_lib/epg_masterlib/logical/mstr_discrete/res/chips/chips.prt!RES!RES_0402-4.75K,1%,1/16W,CHIP,G21796-072!RES!!!F646!!CPU_FANS!!
S!@baseboard_fab2_lib.baseboard_fab2(sch_1):page161_i65@mstr_discrete.res(chips)!RES_0402-4.75K,1%,1/16W,CHIP,GA!R7F33!//jf4cfls225.pdx.intel.com/apd_proj/ppg_lib/epg_masterlib/logical/mstr_discrete/res/chips/chips.prt!RES!RES_0402-4.75K,1%,1/16W,CHIP,G21796-072!RES!!!F592!!CPU_FANS!!
S!@baseboard_fab2_lib.baseboard_fab2(sch_1):page133_i306@mstr_discrete.res(chips)!RES_0402-4.75K,1%,1/16W,CHIP,GA!R7D6!//jf4cfls225.pdx.intel.com/apd_proj/ppg_lib/epg_masterlib/logical/mstr_discrete/res/chips/chips.prt!RES!RES_0402-4.75K,1%,1/16W,CHIP,G21796-072!RES!!!F598!!SB_PU_PD!!
S!@baseboard_fab2_lib.baseboard_fab2(sch_1):page133_i303@mstr_discrete.res(chips)!RES_0402-4.75K,1%,1/16W,CHIP,GA!R8C6!//jf4cfls225.pdx.intel.com/apd_proj/ppg_lib/epg_masterlib/logical/mstr_discrete/res/chips/chips.prt!RES!RES_0402-4.75K,1%,1/16W,CHIP,G21796-072!RES!!!F577!!SB_PU_PD!!
S!@baseboard_fab2_lib.baseboard_fab2(sch_1):page133_i304@mstr_discrete.res(chips)!RES_0402-4.75K,1%,1/16W,CHIP,GA!R8C2!//jf4cfls225.pdx.intel.com/apd_proj/ppg_lib/epg_masterlib/logical/mstr_discrete/res/chips/chips.prt!RES!RES_0402-4.75K,1%,1/16W,CHIP,G21796-072!RES!!!F578!!SB_PU_PD!!
S!@baseboard_fab2_lib.baseboard_fab2(sch_1):page133_i307@mstr_discrete.res(chips)!RES_0402-4.75K,1%,1/16W,CHIP,GA!R8B31!//jf4cfls225.pdx.intel.com/apd_proj/ppg_lib/epg_masterlib/logical/mstr_discrete/res/chips/chips.prt!RES!RES_0402-4.75K,1%,1/16W,CHIP,G21796-072!RES!!!F580!!SB_PU_PD!!
S!@baseboard_fab2_lib.baseboard_fab2(sch_1):page170_i2@mstr_discrete.res(chips)!RES_0402-4.75K,1%,1/16W,CHIP,GA!R2P3!//jf4cfls225.pdx.intel.com/apd_proj/ppg_lib/epg_masterlib/logical/mstr_discrete/res/chips/chips.prt!RES!RES_0402-4.75K,1%,1/16W,CHIP,G21796-072!RES!!!F632!!FAST_PROCHOT!!
S!@baseboard_fab2_lib.baseboard_fab2(sch_1):page157_i346@mstr_discrete.res(chips)!RES_0402-4.75K,1%,1/16W,CHIP,GA!R2M2!//jf4cfls225.pdx.intel.com/apd_proj/ppg_lib/epg_masterlib/logical/mstr_discrete/res/chips/chips.prt!RES!RES_0402-4.75K,1%,1/16W,CHIP,G21796-072!RES!!!F636!!BMC_MISC!!
S!@baseboard_fab2_lib.baseboard_fab2(sch_1):page147_i137@mstr_discrete.res(chips)!RES_0402-4.75K,1%,1/16W,CHIP,GA!R9E21!//jf4cfls225.pdx.intel.com/apd_proj/ppg_lib/epg_masterlib/logical/mstr_discrete/res/chips/chips.prt!RES!RES_0402-4.75K,1%,1/16W,CHIP,G21796-072!RES!!!F554!!BMC!!
S!@baseboard_fab2_lib.baseboard_fab2(sch_1):page157_i342@mstr_discrete.res(chips)!RES_0402-4.75K,1%,1/16W,CHIP,GA!R3N12!//jf4cfls225.pdx.intel.com/apd_proj/ppg_lib/epg_masterlib/logical/mstr_discrete/res/chips/chips.prt!RES!RES_0402-4.75K,1%,1/16W,CHIP,G21796-072!RES!!!F617!!BMC_MISC!!
S!@baseboard_fab2_lib.baseboard_fab2(sch_1):page157_i344@mstr_discrete.res(chips)!RES_0402-4.75K,1%,1/16W,CHIP,GA!R3N11!//jf4cfls225.pdx.intel.com/apd_proj/ppg_lib/epg_masterlib/logical/mstr_discrete/res/chips/chips.prt!RES!RES_0402-4.75K,1%,1/16W,CHIP,G21796-072!RES!!!F618!!BMC_MISC!!
S!@baseboard_fab2_lib.baseboard_fab2(sch_1):page170_i52@mstr_discrete.res(chips)!RES_0402-4.75K,1%,1/16W,CHIP,GA!R2P8!//jf4cfls225.pdx.intel.com/apd_proj/ppg_lib/epg_masterlib/logical/mstr_discrete/res/chips/chips.prt!RES!RES_0402-4.75K,1%,1/16W,CHIP,G21796-072!RES!!!F630!!PROC_SIDEBAND!!
S!@baseboard_fab2_lib.baseboard_fab2(sch_1):page191_i172@mstr_discrete.res(chips)!RES_0402-4.75K,1%,1/16W,CHIP,GA!R2R7!//jf4cfls225.pdx.intel.com/apd_proj/ppg_lib/epg_masterlib/logical/mstr_discrete/res/chips/chips.prt!RES!RES_0402-4.75K,1%,1/16W,CHIP,G21796-072!RES!!!F627!!CPLD!!
S!@baseboard_fab2_lib.baseboard_fab2(sch_1):page181_i177@mstr_discrete.res(chips)!RES_0402-4.75K,1%,1/16W,CHIP,GA!R9T9!//jf4cfls225.pdx.intel.com/apd_proj/ppg_lib/epg_masterlib/logical/mstr_discrete/res/chips/chips.prt!RES!RES_0402-4.75K,1%,1/16W,CHIP,G21796-072!RES!!!F539!!IO_SLOT!!
S!@baseboard_fab2_lib.baseboard_fab2(sch_1):page95_i106@mstr_discrete.res(chips)!RES_0402-4.75K,1%,1/16W,CHIP,GA!R7E7!//jf4cfls225.pdx.intel.com/apd_proj/ppg_lib/epg_masterlib/logical/mstr_discrete/res/chips/chips.prt!RES!RES_0402-4.75K,1%,1/16W,CHIP,G21796-072!RES!!!F596!!PROC_SIDEBAND!!
S!@baseboard_fab2_lib.baseboard_fab2(sch_1):page150_i51@mstr_discrete.res(chips)!RES_0402-4.75K,1%,1/16W,CHIP,GA!R9F35!//jf4cfls225.pdx.intel.com/apd_proj/ppg_lib/epg_masterlib/logical/mstr_discrete/res/chips/chips.prt!RES!RES_0402-4.75K,1%,1/16W,CHIP,G21796-072!RES!!!F546!!BMC!!
S!@baseboard_fab2_lib.baseboard_fab2(sch_1):page125_i76@mstr_discrete.res(chips)!RES_0402-4.75K,1%,1/16W,CHIP,GA!R2U30!//jf4cfls225.pdx.intel.com/apd_proj/ppg_lib/epg_masterlib/logical/mstr_discrete/res/chips/chips.prt!RES!RES_0402-4.75K,1%,1/16W,CHIP,G21796-072!RES!!!F619!!ADR!!
S!@baseboard_fab2_lib.baseboard_fab2(sch_1):page183_i4@mstr_discrete.res(chips)!RES_0402-4.75K,1%,1/16W,CHIP,GA!R9F47!//jf4cfls225.pdx.intel.com/apd_proj/ppg_lib/epg_masterlib/logical/mstr_discrete/res/chips/chips.prt!RES!RES_0402-4.75K,1%,1/16W,CHIP,G21796-072!RES!!!F544!!LBG!!
S!@baseboard_fab2_lib.baseboard_fab2(sch_1):page183_i30@mstr_discrete.res(chips)!RES_0402-4.75K,1%,1/16W,CHIP,GA!R9F55!//jf4cfls225.pdx.intel.com/apd_proj/ppg_lib/epg_masterlib/logical/mstr_discrete/res/chips/chips.prt!RES!RES_0402-4.75K,1%,1/16W,CHIP,G21796-072!RES!!!F542!!LBG!!
S!@baseboard_fab2_lib.baseboard_fab2(sch_1):page89_i26@mstr_discrete.res(chips)!RES_0402-4.75K,1%,1/16W,CHIP,GA!R8D29!//jf4cfls225.pdx.intel.com/apd_proj/ppg_lib/epg_masterlib/logical/mstr_discrete/res/chips/chips.prt!RES!RES_0402-4.75K,1%,1/16W,CHIP,G21796-072!RES!!!F570!!NVDIMM!!
S!@baseboard_fab2_lib.baseboard_fab2(sch_1):page89_i27@mstr_discrete.res(chips)!RES_0402-4.75K,1%,1/16W,CHIP,GA!R8D31!//jf4cfls225.pdx.intel.com/apd_proj/ppg_lib/epg_masterlib/logical/mstr_discrete/res/chips/chips.prt!RES!RES_0402-4.75K,1%,1/16W,CHIP,G21796-072!RES!!!F569!!NVDIMM!!
S!@baseboard_fab2_lib.baseboard_fab2(sch_1):page91_i24@mstr_discrete.res(chips)!RES_0402-4.75K,1%,1/16W,CHIP,GA!R8B3!//jf4cfls225.pdx.intel.com/apd_proj/ppg_lib/epg_masterlib/logical/mstr_discrete/res/chips/chips.prt!RES!RES_0402-4.75K,1%,1/16W,CHIP,G21796-072!RES!!!F589!!HFI!!
S!@baseboard_fab2_lib.baseboard_fab2(sch_1):page91_i22@mstr_discrete.res(chips)!RES_0402-4.75K,1%,1/16W,CHIP,GA!R8B5!//jf4cfls225.pdx.intel.com/apd_proj/ppg_lib/epg_masterlib/logical/mstr_discrete/res/chips/chips.prt!RES!RES_0402-4.75K,1%,1/16W,CHIP,G21796-072!RES!!!F588!!HFI!!
S!@baseboard_fab2_lib.baseboard_fab2(sch_1):page91_i21@mstr_discrete.res(chips)!RES_0402-4.75K,1%,1/16W,CHIP,GA!R8B19!//jf4cfls225.pdx.intel.com/apd_proj/ppg_lib/epg_masterlib/logical/mstr_discrete/res/chips/chips.prt!RES!RES_0402-4.75K,1%,1/16W,CHIP,G21796-072!RES!!!F582!!HFI!!
S!@baseboard_fab2_lib.baseboard_fab2(sch_1):page91_i20@mstr_discrete.res(chips)!RES_0402-4.75K,1%,1/16W,CHIP,GA!R8B18!//jf4cfls225.pdx.intel.com/apd_proj/ppg_lib/epg_masterlib/logical/mstr_discrete/res/chips/chips.prt!RES!RES_0402-4.75K,1%,1/16W,CHIP,G21796-072!RES!!!F583!!HFI!!
S!@baseboard_fab2_lib.baseboard_fab2(sch_1):page91_i18@mstr_discrete.res(chips)!RES_0402-4.75K,1%,1/16W,CHIP,GA!R8B17!//jf4cfls225.pdx.intel.com/apd_proj/ppg_lib/epg_masterlib/logical/mstr_discrete/res/chips/chips.prt!RES!RES_0402-4.75K,1%,1/16W,CHIP,G21796-072!RES!!!F584!!HFI!!
S!@baseboard_fab2_lib.baseboard_fab2(sch_1):page91_i17@mstr_discrete.res(chips)!RES_0402-4.75K,1%,1/16W,CHIP,GA!R8B16!//jf4cfls225.pdx.intel.com/apd_proj/ppg_lib/epg_masterlib/logical/mstr_discrete/res/chips/chips.prt!RES!RES_0402-4.75K,1%,1/16W,CHIP,G21796-072!RES!!!F585!!HFI!!
S!@baseboard_fab2_lib.baseboard_fab2(sch_1):page91_i16@mstr_discrete.res(chips)!RES_0402-4.75K,1%,1/16W,CHIP,GA!R8B10!//jf4cfls225.pdx.intel.com/apd_proj/ppg_lib/epg_masterlib/logical/mstr_discrete/res/chips/chips.prt!RES!RES_0402-4.75K,1%,1/16W,CHIP,G21796-072!RES!!!F586!!HFI!!
S!@baseboard_fab2_lib.baseboard_fab2(sch_1):page91_i14@mstr_discrete.res(chips)!RES_0402-4.75K,1%,1/16W,CHIP,GA!R8B8!//jf4cfls225.pdx.intel.com/apd_proj/ppg_lib/epg_masterlib/logical/mstr_discrete/res/chips/chips.prt!RES!RES_0402-4.75K,1%,1/16W,CHIP,G21796-072!RES!!!F587!!HFI!!
S!@baseboard_fab2_lib.baseboard_fab2(sch_1):page150_i47@mstr_discrete.res(chips)!RES_0402-4.75K,1%,1/16W,CHIP,GA!R9F14!//jf4cfls225.pdx.intel.com/apd_proj/ppg_lib/epg_masterlib/logical/mstr_discrete/res/chips/chips.prt!RES!RES_0402-4.75K,1%,1/16W,CHIP,G21796-072!RES!!!F551!!BMC!!
S!@baseboard_fab2_lib.baseboard_fab2(sch_1):page150_i52@mstr_discrete.res(chips)!RES_0402-4.75K,1%,1/16W,CHIP,GA!R9F9!//jf4cfls225.pdx.intel.com/apd_proj/ppg_lib/epg_masterlib/logical/mstr_discrete/res/chips/chips.prt!RES!RES_0402-4.75K,1%,1/16W,CHIP,G21796-072!RES!!!F552!!BMC!!
S!@baseboard_fab2_lib.baseboard_fab2(sch_1):page150_i54@mstr_discrete.res(chips)!RES_0402-4.75K,1%,1/16W,CHIP,GA!R1T14!//jf4cfls225.pdx.intel.com/apd_proj/ppg_lib/epg_masterlib/logical/mstr_discrete/res/chips/chips.prt!RES!RES_0402-4.75K,1%,1/16W,CHIP,G21796-072!RES!!!F639!!BMC!!
S!@baseboard_fab2_lib.baseboard_fab2(sch_1):page150_i56@mstr_discrete.res(chips)!RES_0402-4.75K,1%,1/16W,CHIP,GA!R9F16!//jf4cfls225.pdx.intel.com/apd_proj/ppg_lib/epg_masterlib/logical/mstr_discrete/res/chips/chips.prt!RES!RES_0402-4.75K,1%,1/16W,CHIP,G21796-072!RES!!!F549!!BMC!!
S!@baseboard_fab2_lib.baseboard_fab2(sch_1):page150_i65@mstr_discrete.res(chips)!RES_0402-4.75K,1%,1/16W,CHIP,GA!R9F40!//jf4cfls225.pdx.intel.com/apd_proj/ppg_lib/epg_masterlib/logical/mstr_discrete/res/chips/chips.prt!RES!RES_0402-4.75K,1%,1/16W,CHIP,G21796-072!RES!!!F545!!BMC!!
S!@baseboard_fab2_lib.baseboard_fab2(sch_1):page95_i62@mstr_discrete.res(chips)!RES_0402-4.75K,1%,1/16W,CHIP,GA!R7E10!//jf4cfls225.pdx.intel.com/apd_proj/ppg_lib/epg_masterlib/logical/mstr_discrete/res/chips/chips.prt!RES!RES_0402-4.75K,1%,1/16W,CHIP,G21796-072!RES!!!F595!!HOT_EVENTS!!
S!@baseboard_fab2_lib.baseboard_fab2(sch_1):page95_i72@mstr_discrete.res(chips)!RES_0402-4.75K,1%,1/16W,CHIP,GA!R7E11!//jf4cfls225.pdx.intel.com/apd_proj/ppg_lib/epg_masterlib/logical/mstr_discrete/res/chips/chips.prt!RES!RES_0402-4.75K,1%,1/16W,CHIP,G21796-072!RES!!!F594!!HOT_EVENTS!!
S!@baseboard_fab2_lib.baseboard_fab2(sch_1):page118_i71@mstr_discrete.res(chips)!RES_0402-4.75K,1%,1/16W,CHIP,GA!R3N13!//jf4cfls225.pdx.intel.com/apd_proj/ppg_lib/epg_masterlib/logical/mstr_discrete/res/chips/chips.prt!RES!RES_0402-4.75K,1%,1/16W,CHIP,G21796-072!RES!!!F616!!SB!!
S!@baseboard_fab2_lib.baseboard_fab2(sch_1):page150_i111@mstr_discrete.res(chips)!RES_0402-4.75K,1%,1/16W,CHIP,GA!R9F15!//jf4cfls225.pdx.intel.com/apd_proj/ppg_lib/epg_masterlib/logical/mstr_discrete/res/chips/chips.prt!RES!RES_0402-4.75K,1%,1/16W,CHIP,G21796-072!RES!!!F550!!BMC!!
S!@baseboard_fab2_lib.baseboard_fab2(sch_1):page154_i105@mstr_discrete.res(chips)!RES_0402-4.75K,1%,1/16W,CHIP,GA!R2T11!//jf4cfls225.pdx.intel.com/apd_proj/ppg_lib/epg_masterlib/logical/mstr_discrete/res/chips/chips.prt!RES!RES_0402-4.75K,1%,1/16W,CHIP,G21796-072!RES!!!F624!!SB_BMC_SPI_MUX!!
S!@baseboard_fab2_lib.baseboard_fab2(sch_1):page142_i3@mstr_discrete.res(chips)!RES_0402-4.75K,1%,1/16W,CHIP,GA!R8E23!//jf4cfls225.pdx.intel.com/apd_proj/ppg_lib/epg_masterlib/logical/mstr_discrete/res/chips/chips.prt!RES!RES_0402-4.75K,1%,1/16W,CHIP,G21796-072!RES!!!F565!!PCIE_WAKE_BUFFER!!
S!@baseboard_fab2_lib.baseboard_fab2(sch_1):page156_i215@mstr_discrete.res(chips)!RES_0402-4.75K,1%,1/16W,CHIP,GA!R8E22!//jf4cfls225.pdx.intel.com/apd_proj/ppg_lib/epg_masterlib/logical/mstr_discrete/res/chips/chips.prt!RES!RES_0402-4.75K,1%,1/16W,CHIP,G21796-072!RES!!!F566!!BMC_MISC!!
S!@baseboard_fab2_lib.baseboard_fab2(sch_1):page102_i45@mstr_discrete.res(chips)!RES_0402-4.75K,1%,1/16W,CHIP,GA!R4D40!//jf4cfls225.pdx.intel.com/apd_proj/ppg_lib/epg_masterlib/logical/mstr_discrete/res/chips/chips.prt!RES!RES_0402-4.75K,1%,1/16W,CHIP,G21796-072!RES!!!F609!!DB1200ZL!!
S!@baseboard_fab2_lib.baseboard_fab2(sch_1):page175_i5@mstr_discrete.res(chips)!RES_0402-4.75K,1%,1/16W,CHIP,GA!R1L27!//jf4cfls225.pdx.intel.com/apd_proj/ppg_lib/epg_masterlib/logical/mstr_discrete/res/chips/chips.prt!RES!RES_0402-4.75K,1%,1/16W,CHIP,G21796-072!RES!!!F643!!MIO_CHASSIS!!
S!@baseboard_fab2_lib.baseboard_fab2(sch_1):page165_i56@mstr_discrete.res(chips)!RES_0402-4.75K,1%,1/16W,CHIP,GA!R1U48!//jf4cfls225.pdx.intel.com/apd_proj/ppg_lib/epg_masterlib/logical/mstr_discrete/res/chips/chips.prt!RES!RES_0402-4.75K,1%,1/16W,CHIP,G21796-072!RES!!!F637!!HEC_VOLT_MONITOR!!
S!@baseboard_fab2_lib.baseboard_fab2(sch_1):page165_i55@mstr_discrete.res(chips)!RES_0402-4.75K,1%,1/16W,CHIP,GA!R1U45!//jf4cfls225.pdx.intel.com/apd_proj/ppg_lib/epg_masterlib/logical/mstr_discrete/res/chips/chips.prt!RES!RES_0402-4.75K,1%,1/16W,CHIP,G21796-072!RES!!!F638!!HEC_VOLT_MONITOR!!
S!@baseboard_fab2_lib.baseboard_fab2(sch_1):page165_i69@mstr_discrete.res(chips)!RES_0402-4.75K,1%,1/16W,CHIP,GA!R9G21!//jf4cfls225.pdx.intel.com/apd_proj/ppg_lib/epg_masterlib/logical/mstr_discrete/res/chips/chips.prt!RES!RES_0402-4.75K,1%,1/16W,CHIP,G21796-072!RES!!!F541!!HEC_VOLT_MONITOR!!
S!@baseboard_fab2_lib.baseboard_fab2(sch_1):page94_i94@mstr_discrete.res(chips)!RES_0402-4.75K,1%,1/16W,CHIP,GA!R4U3!//jf4cfls225.pdx.intel.com/apd_proj/ppg_lib/epg_masterlib/logical/mstr_discrete/res/chips/chips.prt!RES!RES_0402-4.75K,1%,1/16W,CHIP,G21796-072!RES!!!F605!!PROC_SIDEBAND!!
S!@baseboard_fab2_lib.baseboard_fab2(sch_1):page94_i91@mstr_discrete.res(chips)!RES_0402-4.75K,1%,1/16W,CHIP,GA!R4U1!//jf4cfls225.pdx.intel.com/apd_proj/ppg_lib/epg_masterlib/logical/mstr_discrete/res/chips/chips.prt!RES!RES_0402-4.75K,1%,1/16W,CHIP,G21796-072!RES!!!F606!!PROC_SIDEBAND!!
S!@baseboard_fab2_lib.baseboard_fab2(sch_1):page157_i316@mstr_discrete.res(chips)!RES_0402-4.75K,1%,1/16W,CHIP,GA!R8F24!//jf4cfls225.pdx.intel.com/apd_proj/ppg_lib/epg_masterlib/logical/mstr_discrete/res/chips/chips.prt!RES!RES_0402-4.75K,1%,1/16W,CHIP,G21796-072!RES!!!F561!!BMC_MISC!!
S!@baseboard_fab2_lib.baseboard_fab2(sch_1):page153_i152@mstr_discrete.res(chips)!RES_0402-4.75K,1%,1/16W,CHIP,GA!R3T5!//jf4cfls225.pdx.intel.com/apd_proj/ppg_lib/epg_masterlib/logical/mstr_discrete/res/chips/chips.prt!RES!RES_0402-4.75K,1%,1/16W,CHIP,G21796-072!RES!!!F610!!SB_SPI!!
S!@baseboard_fab2_lib.baseboard_fab2(sch_1):page162_i9@mstr_discrete.res(chips)!RES_0402-4.75K,1%,1/16W,CHIP,GA!R8F14!//jf4cfls225.pdx.intel.com/apd_proj/ppg_lib/epg_masterlib/logical/mstr_discrete/res/chips/chips.prt!RES!RES_0402-4.75K,1%,1/16W,CHIP,G21796-072!RES!!!F562!!BMC_BOOT_SPI!!
S!@baseboard_fab2_lib.baseboard_fab2(sch_1):page162_i23@mstr_discrete.res(chips)!RES_0402-4.75K,1%,1/16W,CHIP,GA!R8F13!//jf4cfls225.pdx.intel.com/apd_proj/ppg_lib/epg_masterlib/logical/mstr_discrete/res/chips/chips.prt!RES!RES_0402-4.75K,1%,1/16W,CHIP,G21796-072!RES!!!F563!!BMC_BOOT_SPI!!
S!@baseboard_fab2_lib.baseboard_fab2(sch_1):page162_i22@mstr_discrete.res(chips)!RES_0402-4.75K,1%,1/16W,CHIP,GA!R8F34!//jf4cfls225.pdx.intel.com/apd_proj/ppg_lib/epg_masterlib/logical/mstr_discrete/res/chips/chips.prt!RES!RES_0402-4.75K,1%,1/16W,CHIP,G21796-072!RES!!!F560!!BMC_BOOT_SPI!!
S!@baseboard_fab2_lib.baseboard_fab2(sch_1):page153_i94@mstr_discrete.res(chips)!RES_0402-4.75K,1%,1/16W,CHIP,GA!R7F5!//jf4cfls225.pdx.intel.com/apd_proj/ppg_lib/epg_masterlib/logical/mstr_discrete/res/chips/chips.prt!RES!RES_0402-4.75K,1%,1/16W,CHIP,G21796-072!RES!!!F593!!SB_SPI!!
S!@baseboard_fab2_lib.baseboard_fab2(sch_1):page111_i66@mstr_discrete.res(chips)!RES_0402-4.75K,1%,1/16W,CHIP,GA!R1L28!//jf4cfls225.pdx.intel.com/apd_proj/ppg_lib/epg_masterlib/logical/mstr_discrete/res/chips/chips.prt!RES!RES_0402-4.75K,1%,1/16W,CHIP,G21796-072!RES!!!F642!!M-SATA!!
S!@baseboard_fab2_lib.baseboard_fab2(sch_1):page151_i71@mstr_discrete.res(chips)!RES_0402-4.75K,1%,1/16W,CHIP,GA!R9F29!//jf4cfls225.pdx.intel.com/apd_proj/ppg_lib/epg_masterlib/logical/mstr_discrete/res/chips/chips.prt!RES!RES_0402-4.75K,1%,1/16W,CHIP,G21796-072!RES!!!F548!!BMC_MEMORY!!
S!@baseboard_fab2_lib.baseboard_fab2(sch_1):page94_i51@mstr_discrete.res(chips)!RES_0402-4.75K,1%,1/16W,CHIP,GA!R7G7!//jf4cfls225.pdx.intel.com/apd_proj/ppg_lib/epg_masterlib/logical/mstr_discrete/res/chips/chips.prt!RES!RES_0402-4.75K,1%,1/16W,CHIP,G21796-072!RES!!!F591!!PROC_SIDEBAND!!
S!@baseboard_fab2_lib.baseboard_fab2(sch_1):page94_i66@mstr_discrete.res(chips)!RES_0402-4.75K,1%,1/16W,CHIP,GA!R3R4!//jf4cfls225.pdx.intel.com/apd_proj/ppg_lib/epg_masterlib/logical/mstr_discrete/res/chips/chips.prt!RES!RES_0402-4.75K,1%,1/16W,CHIP,G21796-072!RES!!!F612!!PROC_SIDEBAND!!
S!@baseboard_fab2_lib.baseboard_fab2(sch_1):page94_i79@mstr_discrete.res(chips)!RES_0402-4.75K,1%,1/16W,CHIP,GA!R3R10!//jf4cfls225.pdx.intel.com/apd_proj/ppg_lib/epg_masterlib/logical/mstr_discrete/res/chips/chips.prt!RES!RES_0402-4.75K,1%,1/16W,CHIP,G21796-072!RES!!!F611!!PROC_SIDEBAND!!
S!@baseboard_fab2_lib.baseboard_fab2(sch_1):page94_i82@mstr_discrete.res(chips)!RES_0402-4.75K,1%,1/16W,CHIP,GA!R6M4!//jf4cfls225.pdx.intel.com/apd_proj/ppg_lib/epg_masterlib/logical/mstr_discrete/res/chips/chips.prt!RES!RES_0402-4.75K,1%,1/16W,CHIP,G21796-072!RES!!!F603!!PROC_SIDEBAND!!
S!@baseboard_fab2_lib.baseboard_fab2(sch_1):page157_i97@mstr_discrete.res(chips)!RES_0402-4.75K,1%,1/16W,CHIP,GA!R2N27!//jf4cfls225.pdx.intel.com/apd_proj/ppg_lib/epg_masterlib/logical/mstr_discrete/res/chips/chips.prt!RES!RES_0402-4.75K,1%,1/16W,CHIP,G21796-072!RES!!!F633!!BMC_MISC!!
S!@baseboard_fab2_lib.baseboard_fab2(sch_1):page93_i67@mstr_discrete.res(chips)!RES_0402-75,1.0%,1/16W,CHIP,G2A!R2T16!//jf4cfls225.pdx.intel.com/apd_proj/ppg_lib/epg_masterlib/logical/mstr_discrete/res/chips/chips.prt!RES!RES_0402-75,1.0%,1/16W,CHIP,G21796-267!RES!!!F304!!PROC_SIDEBAND!!
S!@baseboard_fab2_lib.baseboard_fab2(sch_1):page93_i68@mstr_discrete.res(chips)!RES_0402-75,1.0%,1/16W,CHIP,G2A!R2T31!//jf4cfls225.pdx.intel.com/apd_proj/ppg_lib/epg_masterlib/logical/mstr_discrete/res/chips/chips.prt!RES!RES_0402-75,1.0%,1/16W,CHIP,G21796-267!RES!!!F303!!PROC_SIDEBAND!!
S!@baseboard_fab2_lib.baseboard_fab2(sch_1):page154_i62@mstr_discrete.res(chips)!RES_0402-75,1.0%,1/16W,CHIP,G2A!R2T9!//jf4cfls225.pdx.intel.com/apd_proj/ppg_lib/epg_masterlib/logical/mstr_discrete/res/chips/chips.prt!RES!RES_0402-75,1.0%,1/16W,CHIP,G21796-267!RES!!!F305!!SB_BMC_SPI_MUX!!
S!@baseboard_fab2_lib.baseboard_fab2(sch_1):page92_i9@mstr_discrete.res(chips)!RES_0402-75,1.0%,1/16W,CHIP,G2A!R3P41!//jf4cfls225.pdx.intel.com/apd_proj/ppg_lib/epg_masterlib/logical/mstr_discrete/res/chips/chips.prt!RES!RES_0402-75,1.0%,1/16W,CHIP,G21796-267!RES!!!F301!!PROC_SIDEBAND!!
S!@baseboard_fab2_lib.baseboard_fab2(sch_1):page92_i96@mstr_discrete.res(chips)!RES_0402-75,1.0%,1/16W,CHIP,G2A!R2T43!//jf4cfls225.pdx.intel.com/apd_proj/ppg_lib/epg_masterlib/logical/mstr_discrete/res/chips/chips.prt!RES!RES_0402-75,1.0%,1/16W,CHIP,G21796-267!RES!!!F302!!PROC_SIDEBAND!!
S!@baseboard_fab2_lib.baseboard_fab2(sch_1):page92_i19@mstr_discrete.res(chips)!RES_0402-75,1.0%,1/16W,CHIP,G2A!R7E2!//jf4cfls225.pdx.intel.com/apd_proj/ppg_lib/epg_masterlib/logical/mstr_discrete/res/chips/chips.prt!RES!RES_0402-75,1.0%,1/16W,CHIP,G21796-267!RES!!!F300!!PROC_SIDEBAND!!
S!@baseboard_fab2_lib.baseboard_fab2(sch_1):page151_i1@mstr_memory.k4b1g16(chips)!K4B1G16_BGA1-IC,G38649-001!U9F5!//jf4cfls225.pdx.intel.com/apd_proj/ppg_lib/epg_masterlib/logical/mstr_memory/k4b1g16/chips/chips.prt!K4B1G16!K4B1G16_BGA1-IC,G38649-001!K4B1G16_BGA1!!!F2056!!BMC_MEMORY!!
S!@baseboard_fab2_lib.baseboard_fab2(sch_1):page158_i86@mstr_discrete.res(chips)!RES_0402-100.0,1%,1/16W,CHIP,GA!R9F25!//jf4cfls225.pdx.intel.com/apd_proj/ppg_lib/epg_masterlib/logical/mstr_discrete/res/chips/chips.prt!RES!RES_0402-100.0,1%,1/16W,CHIP,G21796-017!RES!!!F1173!!UART_MUX!!
S!@baseboard_fab2_lib.baseboard_fab2(sch_1):page186_i222@mstr_discrete.res(chips)!RES_0402-100.0,1%,1/16W,CHIP,GA!R9B7!//jf4cfls225.pdx.intel.com/apd_proj/ppg_lib/epg_masterlib/logical/mstr_discrete/res/chips/chips.prt!RES!RES_0402-100.0,1%,1/16W,CHIP,G21796-017!RES!!!F1174!!IO_SLOT!!
S!@baseboard_fab2_lib.baseboard_fab2(sch_1):page187_i18@mstr_discrete.res(chips)!RES_0402-100.0,1%,1/16W,CHIP,GA!R2R8!//jf4cfls225.pdx.intel.com/apd_proj/ppg_lib/epg_masterlib/logical/mstr_discrete/res/chips/chips.prt!RES!RES_0402-100.0,1%,1/16W,CHIP,G21796-017!RES!!!F1208!!IO_SLOT!!
S!@baseboard_fab2_lib.baseboard_fab2(sch_1):page196_i106@mstr_discrete.res(chips)!RES_0402-100.0,1%,1/16W,CHIP,GA!R8D42!//jf4cfls225.pdx.intel.com/apd_proj/ppg_lib/epg_masterlib/logical/mstr_discrete/res/chips/chips.prt!RES!RES_0402-100.0,1%,1/16W,CHIP,G21796-017!RES!!!F1168!!V_SUPER!!
S!@baseboard_fab2_lib.baseboard_fab2(sch_1):page112_i76@mstr_discrete.res(chips)!RES_0402-100.0,1%,1/16W,CHIP,GA!R1L39!//jf4cfls225.pdx.intel.com/apd_proj/ppg_lib/epg_masterlib/logical/mstr_discrete/res/chips/chips.prt!RES!RES_0402-100.0,1%,1/16W,CHIP,G21796-017!RES!!!F1213!!DEBUG!!
S!@baseboard_fab2_lib.baseboard_fab2(sch_1):page112_i51@mstr_discrete.res(chips)!RES_0402-100.0,1%,1/16W,CHIP,GA!R1M3!//jf4cfls225.pdx.intel.com/apd_proj/ppg_lib/epg_masterlib/logical/mstr_discrete/res/chips/chips.prt!RES!RES_0402-100.0,1%,1/16W,CHIP,G21796-017!RES!!!F1211!!DEBUG!!
S!@baseboard_fab2_lib.baseboard_fab2(sch_1):page161_i134@mstr_discrete.res(chips)!RES_0402-100.0,1%,1/16W,CHIP,GA!R9T7!//jf4cfls225.pdx.intel.com/apd_proj/ppg_lib/epg_masterlib/logical/mstr_discrete/res/chips/chips.prt!RES!RES_0402-100.0,1%,1/16W,CHIP,G21796-017!RES!!!F1170!!CPU_FANS!!
S!@baseboard_fab2_lib.baseboard_fab2(sch_1):page161_i124@mstr_discrete.res(chips)!RES_0402-100.0,1%,1/16W,CHIP,GA!R1B23!//jf4cfls225.pdx.intel.com/apd_proj/ppg_lib/epg_masterlib/logical/mstr_discrete/res/chips/chips.prt!RES!RES_0402-100.0,1%,1/16W,CHIP,G21796-017!RES!!!F1219!!CPU_FANS!!
S!@baseboard_fab2_lib.baseboard_fab2(sch_1):page236_i90@mstr_discrete.res(chips)!RES_0402-100.0,1%,1/16W,CHIP,GA!R7A13!//jf4cfls225.pdx.intel.com/apd_proj/ppg_lib/epg_masterlib/logical/mstr_discrete/res/chips/chips.prt!RES!RES_0402-100.0,1%,1/16W,CHIP,G21796-017!RES!!!F1182!!P1V05_PCH_STBY!!
S!@baseboard_fab2_lib.baseboard_fab2(sch_1):page112_i54@mstr_discrete.res(chips)!RES_0402-100.0,1%,1/16W,CHIP,GA!R1M4!//jf4cfls225.pdx.intel.com/apd_proj/ppg_lib/epg_masterlib/logical/mstr_discrete/res/chips/chips.prt!RES!RES_0402-100.0,1%,1/16W,CHIP,G21796-017!RES!!!F1210!!DEBUG!!
S!@baseboard_fab2_lib.baseboard_fab2(sch_1):page215_i295@mstr_discrete.res(chips)!RES_0402-100.0,1%,1/16W,CHIP,GA!R3U2!//jf4cfls225.pdx.intel.com/apd_proj/ppg_lib/epg_masterlib/logical/mstr_discrete/res/chips/chips.prt!RES!RES_0402-100.0,1%,1/16W,CHIP,G21796-017!RES!!!F1197!!VDDQ_ABC_PWR_VR!!
S!@baseboard_fab2_lib.baseboard_fab2(sch_1):page112_i57@mstr_discrete.res(chips)!RES_0402-100.0,1%,1/16W,CHIP,GA!R4P12!//jf4cfls225.pdx.intel.com/apd_proj/ppg_lib/epg_masterlib/logical/mstr_discrete/res/chips/chips.prt!RES!RES_0402-100.0,1%,1/16W,CHIP,G21796-017!RES!!!F1190!!DEBUG!!
S!@baseboard_fab2_lib.baseboard_fab2(sch_1):page112_i53@mstr_discrete.res(chips)!RES_0402-100.0,1%,1/16W,CHIP,GA!R4P15!//jf4cfls225.pdx.intel.com/apd_proj/ppg_lib/epg_masterlib/logical/mstr_discrete/res/chips/chips.prt!RES!RES_0402-100.0,1%,1/16W,CHIP,G21796-017!RES!!!F1189!!DEBUG!!
S!@baseboard_fab2_lib.baseboard_fab2(sch_1):page223_i8@mstr_discrete.res(chips)!RES_0402-100.0,1%,1/16W,CHIP,GA!R9U3!//jf4cfls225.pdx.intel.com/apd_proj/ppg_lib/epg_masterlib/logical/mstr_discrete/res/chips/chips.prt!RES!RES_0402-100.0,1%,1/16W,CHIP,G21796-017!RES!!!F1169!!VDDQ_GHJ_PWR_VR!!
S!@baseboard_fab2_lib.baseboard_fab2(sch_1):page196_i65@mstr_discrete.res(chips)!RES_0402-100.0,1%,1/16W,CHIP,GA!R2P20!//jf4cfls225.pdx.intel.com/apd_proj/ppg_lib/epg_masterlib/logical/mstr_discrete/res/chips/chips.prt!RES!RES_0402-100.0,1%,1/16W,CHIP,G21796-017!RES!!!F1176!!V_SUPER!!
S!@baseboard_fab2_lib.baseboard_fab2(sch_1):page112_i77@mstr_discrete.res(chips)!RES_0402-100.0,1%,1/16W,CHIP,GA!R1L41!//jf4cfls225.pdx.intel.com/apd_proj/ppg_lib/epg_masterlib/logical/mstr_discrete/res/chips/chips.prt!RES!RES_0402-100.0,1%,1/16W,CHIP,G21796-017!RES!!!F1212!!DEBUG!!
S!@baseboard_fab2_lib.baseboard_fab2(sch_1):page175_i35@mstr_discrete.res(chips)!RES_0402-100.0,1%,1/16W,CHIP,GA!R9A9!//jf4cfls225.pdx.intel.com/apd_proj/ppg_lib/epg_masterlib/logical/mstr_discrete/res/chips/chips.prt!RES!RES_0402-100.0,1%,1/16W,CHIP,G21796-017!RES!!!F1175!!MIO_CHASSIS!!
S!@baseboard_fab2_lib.baseboard_fab2(sch_1):page152_i26@mstr_discrete.res(chips)!RES_0402-100.0,1%,1/16W,CHIP,GA!R1U37!//jf4cfls225.pdx.intel.com/apd_proj/ppg_lib/epg_masterlib/logical/mstr_discrete/res/chips/chips.prt!RES!RES_0402-100.0,1%,1/16W,CHIP,G21796-017!RES!!!F1209!!PROC_SIDEBAND!!
S!@baseboard_fab2_lib.baseboard_fab2(sch_1):page161_i43@mstr_discrete.res(chips)!RES_0402-100.0,1%,1/16W,CHIP,GA!R1F2!//jf4cfls225.pdx.intel.com/apd_proj/ppg_lib/epg_masterlib/logical/mstr_discrete/res/chips/chips.prt!RES!RES_0402-100.0,1%,1/16W,CHIP,G21796-017!RES!!!F1214!!CPU_FANS!!
S!@baseboard_fab2_lib.baseboard_fab2(sch_1):page161_i67@mstr_discrete.res(chips)!RES_0402-100.0,1%,1/16W,CHIP,GA!R1B22!//jf4cfls225.pdx.intel.com/apd_proj/ppg_lib/epg_masterlib/logical/mstr_discrete/res/chips/chips.prt!RES!RES_0402-100.0,1%,1/16W,CHIP,G21796-017!RES!!!F1220!!CPU_FANS!!
S!@baseboard_fab2_lib.baseboard_fab2(sch_1):page214_i101@mstr_discrete.res(chips)!RES_0402-100.0,1%,1/16W,CHIP,GA!R3D28!//jf4cfls225.pdx.intel.com/apd_proj/ppg_lib/epg_masterlib/logical/mstr_discrete/res/chips/chips.prt!RES!RES_0402-100.0,1%,1/16W,CHIP,G21796-017!RES!!!F1204!!PVCCIO_CPU1!!
S!@baseboard_fab2_lib.baseboard_fab2(sch_1):page212_i74@mstr_discrete.res(chips)!RES_0402-100.0,1%,1/16W,CHIP,GA!R3N21!//jf4cfls225.pdx.intel.com/apd_proj/ppg_lib/epg_masterlib/logical/mstr_discrete/res/chips/chips.prt!RES!RES_0402-100.0,1%,1/16W,CHIP,G21796-017!RES!!!F1199!!PVCCIO_CPU0!!
S!@baseboard_fab2_lib.baseboard_fab2(sch_1):page214_i105@mstr_discrete.res(chips)!RES_0402-100.0,1%,1/16W,CHIP,GA!R3E1!//jf4cfls225.pdx.intel.com/apd_proj/ppg_lib/epg_masterlib/logical/mstr_discrete/res/chips/chips.prt!RES!RES_0402-100.0,1%,1/16W,CHIP,G21796-017!RES!!!F1203!!PVCCIO_CPU1!!
S!@baseboard_fab2_lib.baseboard_fab2(sch_1):page212_i68@mstr_discrete.res(chips)!RES_0402-100.0,1%,1/16W,CHIP,GA!R3N20!//jf4cfls225.pdx.intel.com/apd_proj/ppg_lib/epg_masterlib/logical/mstr_discrete/res/chips/chips.prt!RES!RES_0402-100.0,1%,1/16W,CHIP,G21796-017!RES!!!F1200!!PVCCIO_CPU0!!
S!@baseboard_fab2_lib.baseboard_fab2(sch_1):page209_i15@mstr_discrete.res(chips)!RES_0402-100.0,1%,1/16W,CHIP,GA!R1E4!//jf4cfls225.pdx.intel.com/apd_proj/ppg_lib/epg_masterlib/logical/mstr_discrete/res/chips/chips.prt!RES!RES_0402-100.0,1%,1/16W,CHIP,G21796-017!RES!!!F1216!!PVCCIN_CPU1_VSENSE_VR!!
S!@baseboard_fab2_lib.baseboard_fab2(sch_1):page209_i9@mstr_discrete.res(chips)!RES_0402-100.0,1%,1/16W,CHIP,GA!R1E8!//jf4cfls225.pdx.intel.com/apd_proj/ppg_lib/epg_masterlib/logical/mstr_discrete/res/chips/chips.prt!RES!RES_0402-100.0,1%,1/16W,CHIP,G21796-017!RES!!!F1215!!PVCCIN_CPU1_VSENSE_VR!!
S!@baseboard_fab2_lib.baseboard_fab2(sch_1):page93_i98@mstr_discrete.res(chips)!RES_0402-100.0,1%,1/16W,CHIP,GA!R2T39!//jf4cfls225.pdx.intel.com/apd_proj/ppg_lib/epg_masterlib/logical/mstr_discrete/res/chips/chips.prt!RES!RES_0402-100.0,1%,1/16W,CHIP,G21796-017!RES!!!F1207!!PROC_SIDEBAND!!
S!@baseboard_fab2_lib.baseboard_fab2(sch_1):page116_i181@mstr_discrete.res(chips)!RES_0402-100.0,1%,1/16W,CHIP,GA!R3M12!//jf4cfls225.pdx.intel.com/apd_proj/ppg_lib/epg_masterlib/logical/mstr_discrete/res/chips/chips.prt!RES!RES_0402-100.0,1%,1/16W,CHIP,G21796-017!RES!!!F1201!!SB!!
S!@baseboard_fab2_lib.baseboard_fab2(sch_1):page121_i35@mstr_discrete.res(chips)!RES_0402-100.0,1%,1/16W,CHIP,GA!R8D10!//jf4cfls225.pdx.intel.com/apd_proj/ppg_lib/epg_masterlib/logical/mstr_discrete/res/chips/chips.prt!RES!RES_0402-100.0,1%,1/16W,CHIP,G21796-017!RES!!!F1177!!SB!!
S!@baseboard_fab2_lib.baseboard_fab2(sch_1):page120_i148@mstr_discrete.res(chips)!RES_0402-100.0,1%,1/16W,CHIP,GA!R8C21!//jf4cfls225.pdx.intel.com/apd_proj/ppg_lib/epg_masterlib/logical/mstr_discrete/res/chips/chips.prt!RES!RES_0402-100.0,1%,1/16W,CHIP,G21796-017!RES!!!F1178!!SB!!
S!@baseboard_fab2_lib.baseboard_fab2(sch_1):page112_i50@mstr_discrete.res(chips)!RES_0402-100.0,1%,1/16W,CHIP,GA!R7P30!//jf4cfls225.pdx.intel.com/apd_proj/ppg_lib/epg_masterlib/logical/mstr_discrete/res/chips/chips.prt!RES!RES_0402-100.0,1%,1/16W,CHIP,G21796-017!RES!!!F1179!!DEBUG!!
S!@baseboard_fab2_lib.baseboard_fab2(sch_1):page112_i49@mstr_discrete.res(chips)!RES_0402-100.0,1%,1/16W,CHIP,GA!R6P46!//jf4cfls225.pdx.intel.com/apd_proj/ppg_lib/epg_masterlib/logical/mstr_discrete/res/chips/chips.prt!RES!RES_0402-100.0,1%,1/16W,CHIP,G21796-017!RES!!!F1185!!DEBUG!!
S!@baseboard_fab2_lib.baseboard_fab2(sch_1):page112_i121@mstr_discrete.res(chips)!RES_0402-100.0,1%,1/16W,CHIP,GA!R6T8!//jf4cfls225.pdx.intel.com/apd_proj/ppg_lib/epg_masterlib/logical/mstr_discrete/res/chips/chips.prt!RES!RES_0402-100.0,1%,1/16W,CHIP,G21796-017!RES!!!F1184!!DEBUG!!
S!@baseboard_fab2_lib.baseboard_fab2(sch_1):page112_i120@mstr_discrete.res(chips)!RES_0402-100.0,1%,1/16W,CHIP,GA!R6T9!//jf4cfls225.pdx.intel.com/apd_proj/ppg_lib/epg_masterlib/logical/mstr_discrete/res/chips/chips.prt!RES!RES_0402-100.0,1%,1/16W,CHIP,G21796-017!RES!!!F1183!!DEBUG!!
S!@baseboard_fab2_lib.baseboard_fab2(sch_1):page205_i24@mstr_discrete.res(chips)!RES_0402-100.0,1%,1/16W,CHIP,GA!R4C5!//jf4cfls225.pdx.intel.com/apd_proj/ppg_lib/epg_masterlib/logical/mstr_discrete/res/chips/chips.prt!RES!RES_0402-100.0,1%,1/16W,CHIP,G21796-017!RES!!!F1195!!PVSA_CPU0_VSENSE_VR!!
S!@baseboard_fab2_lib.baseboard_fab2(sch_1):page204_i60@mstr_discrete.res(chips)!RES_0402-100.0,1%,1/16W,CHIP,GA!R4E14!//jf4cfls225.pdx.intel.com/apd_proj/ppg_lib/epg_masterlib/logical/mstr_discrete/res/chips/chips.prt!RES!RES_0402-100.0,1%,1/16W,CHIP,G21796-017!RES!!!F1193!!PVCCIN_CPU0_VSENSE_VR!!
S!@baseboard_fab2_lib.baseboard_fab2(sch_1):page204_i64@mstr_discrete.res(chips)!RES_0402-100.0,1%,1/16W,CHIP,GA!R4E18!//jf4cfls225.pdx.intel.com/apd_proj/ppg_lib/epg_masterlib/logical/mstr_discrete/res/chips/chips.prt!RES!RES_0402-100.0,1%,1/16W,CHIP,G21796-017!RES!!!F1192!!PVCCIN_CPU0_VSENSE_VR!!
S!@baseboard_fab2_lib.baseboard_fab2(sch_1):page21_i159@mstr_discrete.res(chips)!RES_0402-100.0,1%,1/16W,CHIP,GA!R6B2!//jf4cfls225.pdx.intel.com/apd_proj/ppg_lib/epg_masterlib/logical/mstr_discrete/res/chips/chips.prt!RES!RES_0402-100.0,1%,1/16W,CHIP,G21796-017!RES!!!F1188!!CPU0!!
S!@baseboard_fab2_lib.baseboard_fab2(sch_1):page21_i163@mstr_discrete.res(chips)!RES_0402-100.0,1%,1/16W,CHIP,GA!R6N2!//jf4cfls225.pdx.intel.com/apd_proj/ppg_lib/epg_masterlib/logical/mstr_discrete/res/chips/chips.prt!RES!RES_0402-100.0,1%,1/16W,CHIP,G21796-017!RES!!!F1186!!CPU0!!
S!@baseboard_fab2_lib.baseboard_fab2(sch_1):page55_i7@mstr_discrete.res(chips)!RES_0402-100.0,1%,1/16W,CHIP,GA!R9N2!//jf4cfls225.pdx.intel.com/apd_proj/ppg_lib/epg_masterlib/logical/mstr_discrete/res/chips/chips.prt!RES!RES_0402-100.0,1%,1/16W,CHIP,G21796-017!RES!!!F1172!!CPU1!!
S!@baseboard_fab2_lib.baseboard_fab2(sch_1):page55_i21@mstr_discrete.res(chips)!RES_0402-100.0,1%,1/16W,CHIP,GA!R3B4!//jf4cfls225.pdx.intel.com/apd_proj/ppg_lib/epg_masterlib/logical/mstr_discrete/res/chips/chips.prt!RES!RES_0402-100.0,1%,1/16W,CHIP,G21796-017!RES!!!F1206!!CPU1!!
S!@baseboard_fab2_lib.baseboard_fab2(sch_1):page201_i20@mstr_discrete.res(chips)!RES_0402-100.0,1%,1/16W,CHIP,GA!R4E10!//jf4cfls225.pdx.intel.com/apd_proj/ppg_lib/epg_masterlib/logical/mstr_discrete/res/chips/chips.prt!RES!RES_0402-100.0,1%,1/16W,CHIP,G21796-017!RES!!!F1194!!PVCCIN_CPU0_VR!!
S!@baseboard_fab2_lib.baseboard_fab2(sch_1):page206_i4@mstr_discrete.res(chips)!RES_0402-100.0,1%,1/16W,CHIP,GA!R9P1!//jf4cfls225.pdx.intel.com/apd_proj/ppg_lib/epg_masterlib/logical/mstr_discrete/res/chips/chips.prt!RES!RES_0402-100.0,1%,1/16W,CHIP,G21796-017!RES!!!F1171!!PVCCIN_CPU1_VR!!
S!@baseboard_fab2_lib.baseboard_fab2(sch_1):page210_i29@mstr_discrete.res(chips)!RES_0402-100.0,1%,1/16W,CHIP,GA!R1C12!//jf4cfls225.pdx.intel.com/apd_proj/ppg_lib/epg_masterlib/logical/mstr_discrete/res/chips/chips.prt!RES!RES_0402-100.0,1%,1/16W,CHIP,G21796-017!RES!!!F1217!!PVSA_CPU1_VSENSE_VR!!
S!@baseboard_fab2_lib.baseboard_fab2(sch_1):page210_i33@mstr_discrete.res(chips)!RES_0402-100.0,1%,1/16W,CHIP,GA!R1C4!//jf4cfls225.pdx.intel.com/apd_proj/ppg_lib/epg_masterlib/logical/mstr_discrete/res/chips/chips.prt!RES!RES_0402-100.0,1%,1/16W,CHIP,G21796-017!RES!!!F1218!!PVSA_CPU1_VSENSE_VR!!
S!@baseboard_fab2_lib.baseboard_fab2(sch_1):page205_i29@mstr_discrete.res(chips)!RES_0402-100.0,1%,1/16W,CHIP,GA!R4C1!//jf4cfls225.pdx.intel.com/apd_proj/ppg_lib/epg_masterlib/logical/mstr_discrete/res/chips/chips.prt!RES!RES_0402-100.0,1%,1/16W,CHIP,G21796-017!RES!!!F1196!!PVSA_CPU0_VSENSE_VR!!
S!@baseboard_fab2_lib.baseboard_fab2(sch_1):page116_i108@mstr_discrete.res(chips)!RES_0402-100.0,1%,1/16W,CHIP,GA!R3M11!//jf4cfls225.pdx.intel.com/apd_proj/ppg_lib/epg_masterlib/logical/mstr_discrete/res/chips/chips.prt!RES!RES_0402-100.0,1%,1/16W,CHIP,G21796-017!RES!!!F1202!!SB!!
S!@baseboard_fab2_lib.baseboard_fab2(sch_1):page92_i38@mstr_discrete.res(chips)!RES_0402-100.0,1%,1/16W,CHIP,GA!R3P49!//jf4cfls225.pdx.intel.com/apd_proj/ppg_lib/epg_masterlib/logical/mstr_discrete/res/chips/chips.prt!RES!RES_0402-100.0,1%,1/16W,CHIP,G21796-017!RES!!!F1198!!PROC_SIDEBAND!!
S!@baseboard_fab2_lib.baseboard_fab2(sch_1):page92_i48@mstr_discrete.res(chips)!RES_0402-100.0,1%,1/16W,CHIP,GA!R7D32!//jf4cfls225.pdx.intel.com/apd_proj/ppg_lib/epg_masterlib/logical/mstr_discrete/res/chips/chips.prt!RES!RES_0402-100.0,1%,1/16W,CHIP,G21796-017!RES!!!F1181!!PROC_SIDEBAND!!
S!@baseboard_fab2_lib.baseboard_fab2(sch_1):page21_i182@mstr_discrete.res(chips)!RES_0402-100.0,1%,1/16W,CHIP,GA!R4P11!//jf4cfls225.pdx.intel.com/apd_proj/ppg_lib/epg_masterlib/logical/mstr_discrete/res/chips/chips.prt!RES!RES_0402-100.0,1%,1/16W,CHIP,G21796-017!RES!!!F1191!!CPU0!!
S!@baseboard_fab2_lib.baseboard_fab2(sch_1):page21_i179@mstr_discrete.res(chips)!RES_0402-100.0,1%,1/16W,CHIP,GA!R6D1!//jf4cfls225.pdx.intel.com/apd_proj/ppg_lib/epg_masterlib/logical/mstr_discrete/res/chips/chips.prt!RES!RES_0402-100.0,1%,1/16W,CHIP,G21796-017!RES!!!F1187!!CPU0!!
S!@baseboard_fab2_lib.baseboard_fab2(sch_1):page55_i115@mstr_discrete.res(chips)!RES_0402-100.0,1%,1/16W,CHIP,GA!R7P19!//jf4cfls225.pdx.intel.com/apd_proj/ppg_lib/epg_masterlib/logical/mstr_discrete/res/chips/chips.prt!RES!RES_0402-100.0,1%,1/16W,CHIP,G21796-017!RES!!!F1180!!CPU1!!
S!@baseboard_fab2_lib.baseboard_fab2(sch_1):page55_i118@mstr_discrete.res(chips)!RES_0402-100.0,1%,1/16W,CHIP,GA!R3D3!//jf4cfls225.pdx.intel.com/apd_proj/ppg_lib/epg_masterlib/logical/mstr_discrete/res/chips/chips.prt!RES!RES_0402-100.0,1%,1/16W,CHIP,G21796-017!RES!!!F1205!!CPU1!!
S!@baseboard_fab2_lib.baseboard_fab2(sch_1):page90_i72@mstr_discrete.res(chips)!RES_0402-49.9,1%,1/16W,CHIP,G2A!R4P7!//jf4cfls225.pdx.intel.com/apd_proj/ppg_lib/epg_masterlib/logical/mstr_discrete/res/chips/chips.prt!RES!RES_0402-49.9,1%,1/16W,CHIP,G21796-047!RES!!!F446!!PROC_SIDEBAND!!
S!@baseboard_fab2_lib.baseboard_fab2(sch_1):page90_i74@mstr_discrete.res(chips)!RES_0402-49.9,1%,1/16W,CHIP,G2A!R7P15!//jf4cfls225.pdx.intel.com/apd_proj/ppg_lib/epg_masterlib/logical/mstr_discrete/res/chips/chips.prt!RES!RES_0402-49.9,1%,1/16W,CHIP,G21796-047!RES!!!F420!!PROC_SIDEBAND!!
S!@baseboard_fab2_lib.baseboard_fab2(sch_1):page113_i134@mstr_discrete.res(chips)!RES_0402-49.9,1%,1/16W,CHIP,G2A!R4R6!//jf4cfls225.pdx.intel.com/apd_proj/ppg_lib/epg_masterlib/logical/mstr_discrete/res/chips/chips.prt!RES!RES_0402-49.9,1%,1/16W,CHIP,G21796-047!RES!!!F445!!DEBUG!!
S!@baseboard_fab2_lib.baseboard_fab2(sch_1):page113_i180@mstr_discrete.res(chips)!RES_0402-49.9,1%,1/16W,CHIP,G2A!R9B10!//jf4cfls225.pdx.intel.com/apd_proj/ppg_lib/epg_masterlib/logical/mstr_discrete/res/chips/chips.prt!RES!RES_0402-49.9,1%,1/16W,CHIP,G21796-047!RES!!!F428!!DEBUG!!
S!@baseboard_fab2_lib.baseboard_fab2(sch_1):page113_i195@mstr_discrete.res(chips)!RES_0402-49.9,1%,1/16W,CHIP,G2A!R1M22!//jf4cfls225.pdx.intel.com/apd_proj/ppg_lib/epg_masterlib/logical/mstr_discrete/res/chips/chips.prt!RES!RES_0402-49.9,1%,1/16W,CHIP,G21796-047!RES!!!F427!!DEBUG!!
S!@baseboard_fab2_lib.baseboard_fab2(sch_1):page113_i188@mstr_discrete.res(chips)!RES_0402-49.9,1%,1/16W,CHIP,G2A!R6M8!//jf4cfls225.pdx.intel.com/apd_proj/ppg_lib/epg_masterlib/logical/mstr_discrete/res/chips/chips.prt!RES!RES_0402-49.9,1%,1/16W,CHIP,G21796-047!RES!!!F426!!DEBUG!!
S!@baseboard_fab2_lib.baseboard_fab2(sch_1):page156_i288@mstr_discrete.res(chips)!RES_0402-49.9,1%,1/16W,CHIP,G2A!R2T18!//jf4cfls225.pdx.intel.com/apd_proj/ppg_lib/epg_masterlib/logical/mstr_discrete/res/chips/chips.prt!RES!RES_0402-49.9,1%,1/16W,CHIP,G21796-047!RES!!!F461!!BMC_MISC!!
S!@baseboard_fab2_lib.baseboard_fab2(sch_1):page196_i68@mstr_discrete.res(chips)!RES_0402-49.9,1%,1/16W,CHIP,G2A!R1L16!//jf4cfls225.pdx.intel.com/apd_proj/ppg_lib/epg_masterlib/logical/mstr_discrete/res/chips/chips.prt!RES!RES_0402-49.9,1%,1/16W,CHIP,G21796-047!RES!!!F465!!V_SUPER!!
S!@baseboard_fab2_lib.baseboard_fab2(sch_1):page90_i79@mstr_discrete.res(chips)!RES_0402-49.9,1%,1/16W,CHIP,G2A!R5P2!//jf4cfls225.pdx.intel.com/apd_proj/ppg_lib/epg_masterlib/logical/mstr_discrete/res/chips/chips.prt!RES!RES_0402-49.9,1%,1/16W,CHIP,G21796-047!RES!!!F442!!CPU0!!
S!@baseboard_fab2_lib.baseboard_fab2(sch_1):page90_i80@mstr_discrete.res(chips)!RES_0402-49.9,1%,1/16W,CHIP,G2A!R5P3!//jf4cfls225.pdx.intel.com/apd_proj/ppg_lib/epg_masterlib/logical/mstr_discrete/res/chips/chips.prt!RES!RES_0402-49.9,1%,1/16W,CHIP,G21796-047!RES!!!F441!!CPU0!!
S!@baseboard_fab2_lib.baseboard_fab2(sch_1):page90_i81@mstr_discrete.res(chips)!RES_0402-49.9,1%,1/16W,CHIP,G2A!R6D5!//jf4cfls225.pdx.intel.com/apd_proj/ppg_lib/epg_masterlib/logical/mstr_discrete/res/chips/chips.prt!RES!RES_0402-49.9,1%,1/16W,CHIP,G21796-047!RES!!!F436!!CPU0!!
S!@baseboard_fab2_lib.baseboard_fab2(sch_1):page90_i85@mstr_discrete.res(chips)!RES_0402-49.9,1%,1/16W,CHIP,G2A!R8P1!//jf4cfls225.pdx.intel.com/apd_proj/ppg_lib/epg_masterlib/logical/mstr_discrete/res/chips/chips.prt!RES!RES_0402-49.9,1%,1/16W,CHIP,G21796-047!RES!!!F414!!CPU1!!
S!@baseboard_fab2_lib.baseboard_fab2(sch_1):page90_i86@mstr_discrete.res(chips)!RES_0402-49.9,1%,1/16W,CHIP,G2A!R8P2!//jf4cfls225.pdx.intel.com/apd_proj/ppg_lib/epg_masterlib/logical/mstr_discrete/res/chips/chips.prt!RES!RES_0402-49.9,1%,1/16W,CHIP,G21796-047!RES!!!F413!!CPU1!!
S!@baseboard_fab2_lib.baseboard_fab2(sch_1):page90_i88@mstr_discrete.res(chips)!RES_0402-49.9,1%,1/16W,CHIP,G2A!R3D9!//jf4cfls225.pdx.intel.com/apd_proj/ppg_lib/epg_masterlib/logical/mstr_discrete/res/chips/chips.prt!RES!RES_0402-49.9,1%,1/16W,CHIP,G21796-047!RES!!!F457!!CPU1!!
S!@baseboard_fab2_lib.baseboard_fab2(sch_1):page22_i190@mstr_discrete.res(chips)!RES_0402-49.9,1%,1/16W,CHIP,G2A!R5P4!//jf4cfls225.pdx.intel.com/apd_proj/ppg_lib/epg_masterlib/logical/mstr_discrete/res/chips/chips.prt!RES!RES_0402-49.9,1%,1/16W,CHIP,G21796-047!RES!!!F440!!CPU0!!
S!@baseboard_fab2_lib.baseboard_fab2(sch_1):page22_i188@mstr_discrete.res(chips)!RES_0402-49.9,1%,1/16W,CHIP,G2A!R5R1!//jf4cfls225.pdx.intel.com/apd_proj/ppg_lib/epg_masterlib/logical/mstr_discrete/res/chips/chips.prt!RES!RES_0402-49.9,1%,1/16W,CHIP,G21796-047!RES!!!F439!!CPU0!!
S!@baseboard_fab2_lib.baseboard_fab2(sch_1):page56_i173@mstr_discrete.res(chips)!RES_0402-49.9,1%,1/16W,CHIP,G2A!R8P3!//jf4cfls225.pdx.intel.com/apd_proj/ppg_lib/epg_masterlib/logical/mstr_discrete/res/chips/chips.prt!RES!RES_0402-49.9,1%,1/16W,CHIP,G21796-047!RES!!!F412!!CPU1!!
S!@baseboard_fab2_lib.baseboard_fab2(sch_1):page56_i174@mstr_discrete.res(chips)!RES_0402-49.9,1%,1/16W,CHIP,G2A!R8R1!//jf4cfls225.pdx.intel.com/apd_proj/ppg_lib/epg_masterlib/logical/mstr_discrete/res/chips/chips.prt!RES!RES_0402-49.9,1%,1/16W,CHIP,G21796-047!RES!!!F411!!CPU1!!
S!@baseboard_fab2_lib.baseboard_fab2(sch_1):page178_i1@mstr_discrete.res(chips)!RES_0402-49.9,1%,1/16W,CHIP,G2A!R8D20!//jf4cfls225.pdx.intel.com/apd_proj/ppg_lib/epg_masterlib/logical/mstr_discrete/res/chips/chips.prt!RES!RES_0402-49.9,1%,1/16W,CHIP,G21796-047!RES!!!F415!!ST_SATA!!
S!@baseboard_fab2_lib.baseboard_fab2(sch_1):page178_i8@mstr_discrete.res(chips)!RES_0402-49.9,1%,1/16W,CHIP,G2A!R8D19!//jf4cfls225.pdx.intel.com/apd_proj/ppg_lib/epg_masterlib/logical/mstr_discrete/res/chips/chips.prt!RES!RES_0402-49.9,1%,1/16W,CHIP,G21796-047!RES!!!F416!!ST_SATA!!
S!@baseboard_fab2_lib.baseboard_fab2(sch_1):page178_i11@mstr_discrete.res(chips)!RES_0402-49.9,1%,1/16W,CHIP,G2A!R2N31!//jf4cfls225.pdx.intel.com/apd_proj/ppg_lib/epg_masterlib/logical/mstr_discrete/res/chips/chips.prt!RES!RES_0402-49.9,1%,1/16W,CHIP,G21796-047!RES!!!F452!!ST_SATA!!
S!@baseboard_fab2_lib.baseboard_fab2(sch_1):page178_i22@mstr_discrete.res(chips)!RES_0402-49.9,1%,1/16W,CHIP,G2A!R2N19!//jf4cfls225.pdx.intel.com/apd_proj/ppg_lib/epg_masterlib/logical/mstr_discrete/res/chips/chips.prt!RES!RES_0402-49.9,1%,1/16W,CHIP,G21796-047!RES!!!F463!!ST_SATA!!
S!@baseboard_fab2_lib.baseboard_fab2(sch_1):page178_i21@mstr_discrete.res(chips)!RES_0402-49.9,1%,1/16W,CHIP,G2A!R8B29!//jf4cfls225.pdx.intel.com/apd_proj/ppg_lib/epg_masterlib/logical/mstr_discrete/res/chips/chips.prt!RES!RES_0402-49.9,1%,1/16W,CHIP,G21796-047!RES!!!F417!!ST_SATA!!
S!@baseboard_fab2_lib.baseboard_fab2(sch_1):page178_i23@mstr_discrete.res(chips)!RES_0402-49.9,1%,1/16W,CHIP,G2A!R2N22!//jf4cfls225.pdx.intel.com/apd_proj/ppg_lib/epg_masterlib/logical/mstr_discrete/res/chips/chips.prt!RES!RES_0402-49.9,1%,1/16W,CHIP,G21796-047!RES!!!F462!!ST_SATA!!
S!@baseboard_fab2_lib.baseboard_fab2(sch_1):page218_i47@mstr_discrete.res(chips)!RES_0402-49.9,1%,1/16W,CHIP,G2A!R3L13!//jf4cfls225.pdx.intel.com/apd_proj/ppg_lib/epg_masterlib/logical/mstr_discrete/res/chips/chips.prt!RES!RES_0402-49.9,1%,1/16W,CHIP,G21796-047!RES!!!F453!!VDDQ_DEF_PWR_VR!!
S!@baseboard_fab2_lib.baseboard_fab2(sch_1):page226_i50@mstr_discrete.res(chips)!RES_0402-49.9,1%,1/16W,CHIP,G2A!R9M6!//jf4cfls225.pdx.intel.com/apd_proj/ppg_lib/epg_masterlib/logical/mstr_discrete/res/chips/chips.prt!RES!RES_0402-49.9,1%,1/16W,CHIP,G21796-047!RES!!!F408!!VDDQ_KLM_PWR_VR!!
S!@baseboard_fab2_lib.baseboard_fab2(sch_1):page201_i52@mstr_discrete.res(chips)!RES_0402-49.9,1%,1/16W,CHIP,G2A!R4E9!//jf4cfls225.pdx.intel.com/apd_proj/ppg_lib/epg_masterlib/logical/mstr_discrete/res/chips/chips.prt!RES!RES_0402-49.9,1%,1/16W,CHIP,G21796-047!RES!!!F450!!PVCCIN_CPU0_VR!!
S!@baseboard_fab2_lib.baseboard_fab2(sch_1):page206_i53@mstr_discrete.res(chips)!RES_0402-49.9,1%,1/16W,CHIP,G2A!R9P2!//jf4cfls225.pdx.intel.com/apd_proj/ppg_lib/epg_masterlib/logical/mstr_discrete/res/chips/chips.prt!RES!RES_0402-49.9,1%,1/16W,CHIP,G21796-047!RES!!!F406!!PVCCIN_CPU1_VR!!
S!@baseboard_fab2_lib.baseboard_fab2(sch_1):page21_i244@mstr_discrete.res(chips)!RES_0402-49.9,1%,1/16W,CHIP,G2A!R4P18!//jf4cfls225.pdx.intel.com/apd_proj/ppg_lib/epg_masterlib/logical/mstr_discrete/res/chips/chips.prt!RES!RES_0402-49.9,1%,1/16W,CHIP,G21796-047!RES!!!F444!!CPU0!!
S!@baseboard_fab2_lib.baseboard_fab2(sch_1):page55_i170@mstr_discrete.res(chips)!RES_0402-49.9,1%,1/16W,CHIP,G2A!R7P25!//jf4cfls225.pdx.intel.com/apd_proj/ppg_lib/epg_masterlib/logical/mstr_discrete/res/chips/chips.prt!RES!RES_0402-49.9,1%,1/16W,CHIP,G21796-047!RES!!!F419!!CPU1!!
S!@baseboard_fab2_lib.baseboard_fab2(sch_1):page21_i219@mstr_discrete.res(chips)!RES_0402-49.9,1%,1/16W,CHIP,G2A!R4P19!//jf4cfls225.pdx.intel.com/apd_proj/ppg_lib/epg_masterlib/logical/mstr_discrete/res/chips/chips.prt!RES!RES_0402-49.9,1%,1/16W,CHIP,G21796-047!RES!!!F443!!CPU0!!
S!@baseboard_fab2_lib.baseboard_fab2(sch_1):page55_i156@mstr_discrete.res(chips)!RES_0402-49.9,1%,1/16W,CHIP,G2A!R7P26!//jf4cfls225.pdx.intel.com/apd_proj/ppg_lib/epg_masterlib/logical/mstr_discrete/res/chips/chips.prt!RES!RES_0402-49.9,1%,1/16W,CHIP,G21796-047!RES!!!F418!!CPU1!!
S!@baseboard_fab2_lib.baseboard_fab2(sch_1):page55_i155@mstr_discrete.res(chips)!RES_0402-49.9,1%,1/16W,CHIP,G2A!R3D4!//jf4cfls225.pdx.intel.com/apd_proj/ppg_lib/epg_masterlib/logical/mstr_discrete/res/chips/chips.prt!RES!RES_0402-49.9,1%,1/16W,CHIP,G21796-047!RES!!!F458!!CPU1!!
S!@baseboard_fab2_lib.baseboard_fab2(sch_1):page152_i25@mstr_discrete.res(chips)!RES_0402-49.9,1%,1/16W,CHIP,G2A!R1U43!//jf4cfls225.pdx.intel.com/apd_proj/ppg_lib/epg_masterlib/logical/mstr_discrete/res/chips/chips.prt!RES!RES_0402-49.9,1%,1/16W,CHIP,G21796-047!RES!!!F464!!PROC_SIDEBAND!!
S!@baseboard_fab2_lib.baseboard_fab2(sch_1):page89_i3@mstr_discrete.res(chips)!RES_0402-49.9,1%,1/16W,CHIP,G2A!R6F4!//jf4cfls225.pdx.intel.com/apd_proj/ppg_lib/epg_masterlib/logical/mstr_discrete/res/chips/chips.prt!RES!RES_0402-49.9,1%,1/16W,CHIP,G21796-047!RES!!!F430!!NV_DIMM!!
S!@baseboard_fab2_lib.baseboard_fab2(sch_1):page89_i4@mstr_discrete.res(chips)!RES_0402-49.9,1%,1/16W,CHIP,G2A!R6F1!//jf4cfls225.pdx.intel.com/apd_proj/ppg_lib/epg_masterlib/logical/mstr_discrete/res/chips/chips.prt!RES!RES_0402-49.9,1%,1/16W,CHIP,G21796-047!RES!!!F432!!NV_DIMM!!
S!@baseboard_fab2_lib.baseboard_fab2(sch_1):page89_i5@mstr_discrete.res(chips)!RES_0402-49.9,1%,1/16W,CHIP,G2A!R6F5!//jf4cfls225.pdx.intel.com/apd_proj/ppg_lib/epg_masterlib/logical/mstr_discrete/res/chips/chips.prt!RES!RES_0402-49.9,1%,1/16W,CHIP,G21796-047!RES!!!F429!!NV_DIMM!!
S!@baseboard_fab2_lib.baseboard_fab2(sch_1):page89_i6@mstr_discrete.res(chips)!RES_0402-49.9,1%,1/16W,CHIP,G2A!R6F2!//jf4cfls225.pdx.intel.com/apd_proj/ppg_lib/epg_masterlib/logical/mstr_discrete/res/chips/chips.prt!RES!RES_0402-49.9,1%,1/16W,CHIP,G21796-047!RES!!!F431!!NV_DIMM!!
S!@baseboard_fab2_lib.baseboard_fab2(sch_1):page167_i6@mstr_discrete.res(chips)!RES_0402-49.9,1%,1/16W,CHIP,G2A!R9B4!//jf4cfls225.pdx.intel.com/apd_proj/ppg_lib/epg_masterlib/logical/mstr_discrete/res/chips/chips.prt!RES!RES_0402-49.9,1%,1/16W,CHIP,G21796-047!RES!!!F410!!TEMP_SENSORS!!
S!@baseboard_fab2_lib.baseboard_fab2(sch_1):page167_i5@mstr_discrete.res(chips)!RES_0402-49.9,1%,1/16W,CHIP,G2A!R9B5!//jf4cfls225.pdx.intel.com/apd_proj/ppg_lib/epg_masterlib/logical/mstr_discrete/res/chips/chips.prt!RES!RES_0402-49.9,1%,1/16W,CHIP,G21796-047!RES!!!F409!!TEMP_SENSORS!!
S!@baseboard_fab2_lib.baseboard_fab2(sch_1):page167_i25@mstr_discrete.res(chips)!RES_0402-49.9,1%,1/16W,CHIP,G2A!R9R5!//jf4cfls225.pdx.intel.com/apd_proj/ppg_lib/epg_masterlib/logical/mstr_discrete/res/chips/chips.prt!RES!RES_0402-49.9,1%,1/16W,CHIP,G21796-047!RES!!!F405!!TEMP_SENSORS!!
S!@baseboard_fab2_lib.baseboard_fab2(sch_1):page167_i26@mstr_discrete.res(chips)!RES_0402-49.9,1%,1/16W,CHIP,G2A!R9R6!//jf4cfls225.pdx.intel.com/apd_proj/ppg_lib/epg_masterlib/logical/mstr_discrete/res/chips/chips.prt!RES!RES_0402-49.9,1%,1/16W,CHIP,G21796-047!RES!!!F404!!TEMP_SENSORS!!
S!@baseboard_fab2_lib.baseboard_fab2(sch_1):page93_i97@mstr_discrete.res(chips)!RES_0402-49.9,1%,1/16W,CHIP,G2A!R2T36!//jf4cfls225.pdx.intel.com/apd_proj/ppg_lib/epg_masterlib/logical/mstr_discrete/res/chips/chips.prt!RES!RES_0402-49.9,1%,1/16W,CHIP,G21796-047!RES!!!F460!!PROC_SIDEBAND!!
S!@baseboard_fab2_lib.baseboard_fab2(sch_1):page96_i25@mstr_discrete.res(chips)!RES_0402-49.9,1%,1/16W,CHIP,G2A!R3D20!//jf4cfls225.pdx.intel.com/apd_proj/ppg_lib/epg_masterlib/logical/mstr_discrete/res/chips/chips.prt!RES!RES_0402-49.9,1%,1/16W,CHIP,G21796-047!RES!!!F454!!PROC_RSTS_PGOODS!!
S!@baseboard_fab2_lib.baseboard_fab2(sch_1):page96_i26@mstr_discrete.res(chips)!RES_0402-49.9,1%,1/16W,CHIP,G2A!R3D15!//jf4cfls225.pdx.intel.com/apd_proj/ppg_lib/epg_masterlib/logical/mstr_discrete/res/chips/chips.prt!RES!RES_0402-49.9,1%,1/16W,CHIP,G21796-047!RES!!!F456!!PROC_RSTS_PGOODS!!
S!@baseboard_fab2_lib.baseboard_fab2(sch_1):page96_i2@mstr_discrete.res(chips)!RES_0402-49.9,1%,1/16W,CHIP,G2A!R6D12!//jf4cfls225.pdx.intel.com/apd_proj/ppg_lib/epg_masterlib/logical/mstr_discrete/res/chips/chips.prt!RES!RES_0402-49.9,1%,1/16W,CHIP,G21796-047!RES!!!F433!!PROC_RSTS_PGOODS!!
S!@baseboard_fab2_lib.baseboard_fab2(sch_1):page96_i3@mstr_discrete.res(chips)!RES_0402-49.9,1%,1/16W,CHIP,G2A!R6D8!//jf4cfls225.pdx.intel.com/apd_proj/ppg_lib/epg_masterlib/logical/mstr_discrete/res/chips/chips.prt!RES!RES_0402-49.9,1%,1/16W,CHIP,G21796-047!RES!!!F435!!PROC_RSTS_PGOODS!!
S!@baseboard_fab2_lib.baseboard_fab2(sch_1):page21_i161@mstr_discrete.res(chips)!RES_0402-49.9,1%,1/16W,CHIP,G2A!R6B1!//jf4cfls225.pdx.intel.com/apd_proj/ppg_lib/epg_masterlib/logical/mstr_discrete/res/chips/chips.prt!RES!RES_0402-49.9,1%,1/16W,CHIP,G21796-047!RES!!!F438!!CPU0!!
S!@baseboard_fab2_lib.baseboard_fab2(sch_1):page21_i164@mstr_discrete.res(chips)!RES_0402-49.9,1%,1/16W,CHIP,G2A!R6N1!//jf4cfls225.pdx.intel.com/apd_proj/ppg_lib/epg_masterlib/logical/mstr_discrete/res/chips/chips.prt!RES!RES_0402-49.9,1%,1/16W,CHIP,G21796-047!RES!!!F425!!CPU0!!
S!@baseboard_fab2_lib.baseboard_fab2(sch_1):page55_i4@mstr_discrete.res(chips)!RES_0402-49.9,1%,1/16W,CHIP,G2A!R9N1!//jf4cfls225.pdx.intel.com/apd_proj/ppg_lib/epg_masterlib/logical/mstr_discrete/res/chips/chips.prt!RES!RES_0402-49.9,1%,1/16W,CHIP,G21796-047!RES!!!F407!!CPU1!!
S!@baseboard_fab2_lib.baseboard_fab2(sch_1):page55_i19@mstr_discrete.res(chips)!RES_0402-49.9,1%,1/16W,CHIP,G2A!R3B2!//jf4cfls225.pdx.intel.com/apd_proj/ppg_lib/epg_masterlib/logical/mstr_discrete/res/chips/chips.prt!RES!RES_0402-49.9,1%,1/16W,CHIP,G21796-047!RES!!!F459!!CPU1!!
S!@baseboard_fab2_lib.baseboard_fab2(sch_1):page92_i39@mstr_discrete.res(chips)!RES_0402-49.9,1%,1/16W,CHIP,G2A!R3P45!//jf4cfls225.pdx.intel.com/apd_proj/ppg_lib/epg_masterlib/logical/mstr_discrete/res/chips/chips.prt!RES!RES_0402-49.9,1%,1/16W,CHIP,G21796-047!RES!!!F451!!PROC_SIDEBAND!!
S!@baseboard_fab2_lib.baseboard_fab2(sch_1):page92_i51@mstr_discrete.res(chips)!RES_0402-49.9,1%,1/16W,CHIP,G2A!R7D33!//jf4cfls225.pdx.intel.com/apd_proj/ppg_lib/epg_masterlib/logical/mstr_discrete/res/chips/chips.prt!RES!RES_0402-49.9,1%,1/16W,CHIP,G21796-047!RES!!!F424!!PROC_SIDEBAND!!
S!@baseboard_fab2_lib.baseboard_fab2(sch_1):page21_i204@mstr_discrete.res(chips)!RES_0402-49.9,1%,1/16W,CHIP,G2A!R6D2!//jf4cfls225.pdx.intel.com/apd_proj/ppg_lib/epg_masterlib/logical/mstr_discrete/res/chips/chips.prt!RES!RES_0402-49.9,1%,1/16W,CHIP,G21796-047!RES!!!F437!!CPU0!!
S!@baseboard_fab2_lib.baseboard_fab2(sch_1):page21_i188@mstr_discrete.res(chips)!RES_0402-49.9,1%,1/16W,CHIP,G2A!R4P2!//jf4cfls225.pdx.intel.com/apd_proj/ppg_lib/epg_masterlib/logical/mstr_discrete/res/chips/chips.prt!RES!RES_0402-49.9,1%,1/16W,CHIP,G21796-047!RES!!!F449!!CPU0!!
S!@baseboard_fab2_lib.baseboard_fab2(sch_1):page21_i186@mstr_discrete.res(chips)!RES_0402-49.9,1%,1/16W,CHIP,G2A!R4P3!//jf4cfls225.pdx.intel.com/apd_proj/ppg_lib/epg_masterlib/logical/mstr_discrete/res/chips/chips.prt!RES!RES_0402-49.9,1%,1/16W,CHIP,G21796-047!RES!!!F448!!CPU0!!
S!@baseboard_fab2_lib.baseboard_fab2(sch_1):page21_i184@mstr_discrete.res(chips)!RES_0402-49.9,1%,1/16W,CHIP,G2A!R6D11!//jf4cfls225.pdx.intel.com/apd_proj/ppg_lib/epg_masterlib/logical/mstr_discrete/res/chips/chips.prt!RES!RES_0402-49.9,1%,1/16W,CHIP,G21796-047!RES!!!F434!!CPU0!!
S!@baseboard_fab2_lib.baseboard_fab2(sch_1):page21_i189@mstr_discrete.res(chips)!RES_0402-49.9,1%,1/16W,CHIP,G2A!R4P4!//jf4cfls225.pdx.intel.com/apd_proj/ppg_lib/epg_masterlib/logical/mstr_discrete/res/chips/chips.prt!RES!RES_0402-49.9,1%,1/16W,CHIP,G21796-047!RES!!!F447!!CPU0!!
S!@baseboard_fab2_lib.baseboard_fab2(sch_1):page55_i123@mstr_discrete.res(chips)!RES_0402-49.9,1%,1/16W,CHIP,G2A!R7P8!//jf4cfls225.pdx.intel.com/apd_proj/ppg_lib/epg_masterlib/logical/mstr_discrete/res/chips/chips.prt!RES!RES_0402-49.9,1%,1/16W,CHIP,G21796-047!RES!!!F423!!CPU1!!
S!@baseboard_fab2_lib.baseboard_fab2(sch_1):page55_i124@mstr_discrete.res(chips)!RES_0402-49.9,1%,1/16W,CHIP,G2A!R7P10!//jf4cfls225.pdx.intel.com/apd_proj/ppg_lib/epg_masterlib/logical/mstr_discrete/res/chips/chips.prt!RES!RES_0402-49.9,1%,1/16W,CHIP,G21796-047!RES!!!F422!!CPU1!!
S!@baseboard_fab2_lib.baseboard_fab2(sch_1):page55_i125@mstr_discrete.res(chips)!RES_0402-49.9,1%,1/16W,CHIP,G2A!R3D19!//jf4cfls225.pdx.intel.com/apd_proj/ppg_lib/epg_masterlib/logical/mstr_discrete/res/chips/chips.prt!RES!RES_0402-49.9,1%,1/16W,CHIP,G21796-047!RES!!!F455!!CPU1!!
S!@baseboard_fab2_lib.baseboard_fab2(sch_1):page55_i126@mstr_discrete.res(chips)!RES_0402-49.9,1%,1/16W,CHIP,G2A!R7P11!//jf4cfls225.pdx.intel.com/apd_proj/ppg_lib/epg_masterlib/logical/mstr_discrete/res/chips/chips.prt!RES!RES_0402-49.9,1%,1/16W,CHIP,G21796-047!RES!!!F421!!CPU1!!
S!@baseboard_fab2_lib.baseboard_fab2(sch_1):page199_i10@mstr_controller.adm1278(chips)!ADM1278_SM-IC,G99251-001!EU1D2!//jf4cfls225.pdx.intel.com/apd_proj/ppg_lib/epg_masterlib/logical/mstr_controller/adm1278/chips/chips.prt!ADM1278!ADM1278_SM-IC,G99251-001!ADM1278_SM!!!F4197!!HOT_SWAP!!
S!@baseboard_fab2_lib.baseboard_fab2(sch_1):page143_i281@mstr_controller.ast1250(chips)!AST1250_BGA-IC,G85138-002!U9F4!//jf4cfls225.pdx.intel.com/apd_proj/ppg_lib/epg_masterlib/logical/mstr_controller/ast1250/chips/chips.prt!AST1250!AST1250_BGA-IC,G85138-002!AST1250_BGA!!!F4192!!BMC!!
S!@baseboard_fab2_lib.baseboard_fab2(sch_1):page144_i347@mstr_controller.ast1250(chips)!AST1250_BGA-IC,G85138-002!U9F4!//jf4cfls225.pdx.intel.com/apd_proj/ppg_lib/epg_masterlib/logical/mstr_controller/ast1250/chips/chips.prt!AST1250!AST1250_BGA-IC,G85138-002!AST1250_BGA!!!F4191!!BMC!!
S!@baseboard_fab2_lib.baseboard_fab2(sch_1):page145_i100@mstr_controller.ast1250(chips)!AST1250_BGA-IC,G85138-002!U9F4!//jf4cfls225.pdx.intel.com/apd_proj/ppg_lib/epg_masterlib/logical/mstr_controller/ast1250/chips/chips.prt!AST1250!AST1250_BGA-IC,G85138-002!AST1250_BGA!!!F4190!!BMC!!
S!@baseboard_fab2_lib.baseboard_fab2(sch_1):page146_i1@mstr_controller.ast1250(chips)!AST1250_BGA-IC,G85138-002!U9F4!//jf4cfls225.pdx.intel.com/apd_proj/ppg_lib/epg_masterlib/logical/mstr_controller/ast1250/chips/chips.prt!AST1250!AST1250_BGA-IC,G85138-002!AST1250_BGA!!!F4189!!BMC!!
S!@baseboard_fab2_lib.baseboard_fab2(sch_1):page147_i1@mstr_controller.ast1250(chips)!AST1250_BGA-IC,G85138-002!U9F4!//jf4cfls225.pdx.intel.com/apd_proj/ppg_lib/epg_masterlib/logical/mstr_controller/ast1250/chips/chips.prt!AST1250!AST1250_BGA-IC,G85138-002!AST1250_BGA!!!F4188!!BMC!!
S!@baseboard_fab2_lib.baseboard_fab2(sch_1):page148_i11@mstr_controller.ast1250(chips)!AST1250_BGA-IC,G85138-002!U9F4!//jf4cfls225.pdx.intel.com/apd_proj/ppg_lib/epg_masterlib/logical/mstr_controller/ast1250/chips/chips.prt!AST1250!AST1250_BGA-IC,G85138-002!AST1250_BGA!!!F4187!!BMC!!
S!@baseboard_fab2_lib.baseboard_fab2(sch_1):page196_i47@mstr_misc.battery(chips)!BATTERY_PLCLF-202168-001!BT8G1!//jf4cfls225.pdx.intel.com/apd_proj/ppg_lib/epg_masterlib/logical/mstr_misc/battery/chips/chips.prt!BATTERY!BATTERY_PLCLF-202168-001!BATTERY!!!TF-4025!!SB_VRD!!
S!@baseboard_fab2_lib.baseboard_fab2(sch_1):page209_i35@mstr_discrete.capp(chips)!CAPP_2626-270UF,16V,20%,OSCON,A!C1C1!//jf4cfls225.pdx.intel.com/apd_proj/ppg_lib/epg_masterlib/logical/mstr_discrete/capp/chips/chips.prt!CAPP!CAPP_2626-270UF,16V,20%,OSCON,A31228-047!CAPP!!!F4184!!PVCCIN_CPU1_FILTER_VR!!
S!@baseboard_fab2_lib.baseboard_fab2(sch_1):page209_i37@mstr_discrete.capp(chips)!CAPP_2626-270UF,16V,20%,OSCON,A!C1E18!//jf4cfls225.pdx.intel.com/apd_proj/ppg_lib/epg_masterlib/logical/mstr_discrete/capp/chips/chips.prt!CAPP!CAPP_2626-270UF,16V,20%,OSCON,A31228-047!CAPP!!!F4182!!PVCCIN_CPU1_FILTER_VR!!
S!@baseboard_fab2_lib.baseboard_fab2(sch_1):page209_i38@mstr_discrete.capp(chips)!CAPP_2626-270UF,16V,20%,OSCON,A!C1C2!//jf4cfls225.pdx.intel.com/apd_proj/ppg_lib/epg_masterlib/logical/mstr_discrete/capp/chips/chips.prt!CAPP!CAPP_2626-270UF,16V,20%,OSCON,A31228-047!CAPP!!!F4183!!PVCCIN_CPU1_FILTER_VR!!
S!@baseboard_fab2_lib.baseboard_fab2(sch_1):page204_i50@mstr_discrete.capp(chips)!CAPP_2626-270UF,16V,20%,OSCON,A!C4E16!//jf4cfls225.pdx.intel.com/apd_proj/ppg_lib/epg_masterlib/logical/mstr_discrete/capp/chips/chips.prt!CAPP!CAPP_2626-270UF,16V,20%,OSCON,A31228-047!CAPP!!!F4179!!PVCCIN_CPU0_FILTER_VR!!
S!@baseboard_fab2_lib.baseboard_fab2(sch_1):page204_i48@mstr_discrete.capp(chips)!CAPP_2626-270UF,16V,20%,OSCON,A!C4D2!//jf4cfls225.pdx.intel.com/apd_proj/ppg_lib/epg_masterlib/logical/mstr_discrete/capp/chips/chips.prt!CAPP!CAPP_2626-270UF,16V,20%,OSCON,A31228-047!CAPP!!!F4180!!PVCCIN_CPU0_FILTER_VR!!
S!@baseboard_fab2_lib.baseboard_fab2(sch_1):page204_i67@mstr_discrete.capp(chips)!CAPP_2626-270UF,16V,20%,OSCON,A!C4C12!//jf4cfls225.pdx.intel.com/apd_proj/ppg_lib/epg_masterlib/logical/mstr_discrete/capp/chips/chips.prt!CAPP!CAPP_2626-270UF,16V,20%,OSCON,A31228-047!CAPP!!!F4181!!PVCCIN_CPU0_FILTER_VR!!
S!@baseboard_fab2_lib.baseboard_fab2(sch_1):page217_i175@mstr_discrete.capp(chips)!CAPP_2626-270UF,16V,20%,OSCON,A!C7G2!//jf4cfls225.pdx.intel.com/apd_proj/ppg_lib/epg_masterlib/logical/mstr_discrete/capp/chips/chips.prt!CAPP!CAPP_2626-270UF,16V,20%,OSCON,A31228-047!CAPP!!!F4177!!VDDQ_ABC_PWR_VR!!
S!@baseboard_fab2_lib.baseboard_fab2(sch_1):page220_i175@mstr_discrete.capp(chips)!CAPP_2626-270UF,16V,20%,OSCON,A!C7A19!//jf4cfls225.pdx.intel.com/apd_proj/ppg_lib/epg_masterlib/logical/mstr_discrete/capp/chips/chips.prt!CAPP!CAPP_2626-270UF,16V,20%,OSCON,A31228-047!CAPP!!!F4178!!VDDQ_DEF_PWR_VR!!
S!@baseboard_fab2_lib.baseboard_fab2(sch_1):page228_i175@mstr_discrete.capp(chips)!CAPP_2626-270UF,16V,20%,OSCON,A!C1B10!//jf4cfls225.pdx.intel.com/apd_proj/ppg_lib/epg_masterlib/logical/mstr_discrete/capp/chips/chips.prt!CAPP!CAPP_2626-270UF,16V,20%,OSCON,A31228-047!CAPP!!!F4185!!VDDQ_KLM_PWR_VR!!
S!@baseboard_fab2_lib.baseboard_fab2(sch_1):page194_i29@mstr_discrete.capp(chips)!CAPP_3018-470UF,2.5V,20%,ALUM,A!C4R1!//jf4cfls225.pdx.intel.com/apd_proj/ppg_lib/epg_masterlib/logical/mstr_discrete/capp/chips/chips.prt!CAPP!CAPP_3018-470UF,2.5V,20%,ALUM,699013-049!CAPP!!!F4162!!PVMCP_MCP_CPU0_VR!!
S!@baseboard_fab2_lib.baseboard_fab2(sch_1):page193_i62@mstr_discrete.capp(chips)!CAPP_3018-470UF,2.5V,20%,ALUM,A!C6R16!//jf4cfls225.pdx.intel.com/apd_proj/ppg_lib/epg_masterlib/logical/mstr_discrete/capp/chips/chips.prt!CAPP!CAPP_3018-470UF,2.5V,20%,ALUM,699013-049!CAPP!!!F4149!!PVMCP_MCP_CPU1_VR!!
S!@baseboard_fab2_lib.baseboard_fab2(sch_1):page194_i31@mstr_discrete.capp(chips)!CAPP_3018-470UF,2.5V,20%,ALUM,A!C3R4!//jf4cfls225.pdx.intel.com/apd_proj/ppg_lib/epg_masterlib/logical/mstr_discrete/capp/chips/chips.prt!CAPP!CAPP_3018-470UF,2.5V,20%,ALUM,699013-049!CAPP!!!F4170!!PVMCP_MCP_CPU0_VR!!
S!@baseboard_fab2_lib.baseboard_fab2(sch_1):page193_i61@mstr_discrete.capp(chips)!CAPP_3018-470UF,2.5V,20%,ALUM,A!C4E24!//jf4cfls225.pdx.intel.com/apd_proj/ppg_lib/epg_masterlib/logical/mstr_discrete/capp/chips/chips.prt!CAPP!CAPP_3018-470UF,2.5V,20%,ALUM,699013-049!CAPP!!!F4164!!PVMCP_MCP_CPU1_VR!!
S!@baseboard_fab2_lib.baseboard_fab2(sch_1):page194_i101@mstr_discrete.capp(chips)!CAPP_3018-470UF,2.5V,20%,ALUM,A!C3N14!//jf4cfls225.pdx.intel.com/apd_proj/ppg_lib/epg_masterlib/logical/mstr_discrete/capp/chips/chips.prt!CAPP!CAPP_3018-470UF,2.5V,20%,ALUM,699013-049!CAPP!!!F4174!!P0V95_MCP_CPU0_DECAP_VR!!
S!@baseboard_fab2_lib.baseboard_fab2(sch_1):page193_i29@mstr_discrete.capp(chips)!CAPP_3018-470UF,2.5V,20%,ALUM,A!C4C1!//jf4cfls225.pdx.intel.com/apd_proj/ppg_lib/epg_masterlib/logical/mstr_discrete/capp/chips/chips.prt!CAPP!CAPP_3018-470UF,2.5V,20%,ALUM,699013-049!CAPP!!!F4166!!P0V95_MCP_CPU1_DECAP_VR!!
S!@baseboard_fab2_lib.baseboard_fab2(sch_1):page203_i34@mstr_discrete.capp(chips)!CAPP_3018-470UF,2.5V,20%,ALUM,A!C6N9!//jf4cfls225.pdx.intel.com/apd_proj/ppg_lib/epg_masterlib/logical/mstr_discrete/capp/chips/chips.prt!CAPP!CAPP_3018-470UF,2.5V,20%,ALUM,699013-049!CAPP!!!F4158!!PVCCIN_CPU0_DECAP_VR!!
S!@baseboard_fab2_lib.baseboard_fab2(sch_1):page203_i32@mstr_discrete.capp(chips)!CAPP_3018-470UF,2.5V,20%,ALUM,A!C6P8!//jf4cfls225.pdx.intel.com/apd_proj/ppg_lib/epg_masterlib/logical/mstr_discrete/capp/chips/chips.prt!CAPP!CAPP_3018-470UF,2.5V,20%,ALUM,699013-049!CAPP!!!F4157!!PVCCIN_CPU0_DECAP_VR!!
S!@baseboard_fab2_lib.baseboard_fab2(sch_1):page203_i30@mstr_discrete.capp(chips)!CAPP_3018-470UF,2.5V,20%,ALUM,A!C6P18!//jf4cfls225.pdx.intel.com/apd_proj/ppg_lib/epg_masterlib/logical/mstr_discrete/capp/chips/chips.prt!CAPP!CAPP_3018-470UF,2.5V,20%,ALUM,699013-049!CAPP!!!F4155!!PVCCIN_CPU0_DECAP_VR!!
S!@baseboard_fab2_lib.baseboard_fab2(sch_1):page203_i29@mstr_discrete.capp(chips)!CAPP_3018-470UF,2.5V,20%,ALUM,A!C6P14!//jf4cfls225.pdx.intel.com/apd_proj/ppg_lib/epg_masterlib/logical/mstr_discrete/capp/chips/chips.prt!CAPP!CAPP_3018-470UF,2.5V,20%,ALUM,699013-049!CAPP!!!F4156!!PVCCIN_CPU0_DECAP_VR!!
S!@baseboard_fab2_lib.baseboard_fab2(sch_1):page203_i28@mstr_discrete.capp(chips)!CAPP_3018-470UF,2.5V,20%,ALUM,A!C6P23!//jf4cfls225.pdx.intel.com/apd_proj/ppg_lib/epg_masterlib/logical/mstr_discrete/capp/chips/chips.prt!CAPP!CAPP_3018-470UF,2.5V,20%,ALUM,699013-049!CAPP!!!F4154!!PVCCIN_CPU0_DECAP_VR!!
S!@baseboard_fab2_lib.baseboard_fab2(sch_1):page203_i18@mstr_discrete.capp(chips)!CAPP_3018-470UF,2.5V,20%,ALUM,A!C6R9!//jf4cfls225.pdx.intel.com/apd_proj/ppg_lib/epg_masterlib/logical/mstr_discrete/capp/chips/chips.prt!CAPP!CAPP_3018-470UF,2.5V,20%,ALUM,699013-049!CAPP!!!F4151!!PVCCIN_CPU0_DECAP_VR!!
S!@baseboard_fab2_lib.baseboard_fab2(sch_1):page203_i16@mstr_discrete.capp(chips)!CAPP_3018-470UF,2.5V,20%,ALUM,A!C6R3!//jf4cfls225.pdx.intel.com/apd_proj/ppg_lib/epg_masterlib/logical/mstr_discrete/capp/chips/chips.prt!CAPP!CAPP_3018-470UF,2.5V,20%,ALUM,699013-049!CAPP!!!F4153!!PVCCIN_CPU0_DECAP_VR!!
S!@baseboard_fab2_lib.baseboard_fab2(sch_1):page212_i18@mstr_discrete.capp(chips)!CAPP_3018-470UF,2.5V,20%,ALUM,A!C3N35!//jf4cfls225.pdx.intel.com/apd_proj/ppg_lib/epg_masterlib/logical/mstr_discrete/capp/chips/chips.prt!CAPP!CAPP_3018-470UF,2.5V,20%,ALUM,699013-049!CAPP!!!F4172!!PVCCIO_CPU0!!
S!@baseboard_fab2_lib.baseboard_fab2(sch_1):page212_i17@mstr_discrete.capp(chips)!CAPP_3018-470UF,2.5V,20%,ALUM,A!C3N26!//jf4cfls225.pdx.intel.com/apd_proj/ppg_lib/epg_masterlib/logical/mstr_discrete/capp/chips/chips.prt!CAPP!CAPP_3018-470UF,2.5V,20%,ALUM,699013-049!CAPP!!!F4173!!PVCCIO_CPU0!!
S!@baseboard_fab2_lib.baseboard_fab2(sch_1):page212_i16@mstr_discrete.capp(chips)!CAPP_3018-470UF,2.5V,20%,ALUM,A!C3N38!//jf4cfls225.pdx.intel.com/apd_proj/ppg_lib/epg_masterlib/logical/mstr_discrete/capp/chips/chips.prt!CAPP!CAPP_3018-470UF,2.5V,20%,ALUM,699013-049!CAPP!!!F4171!!PVCCIO_CPU0!!
S!@baseboard_fab2_lib.baseboard_fab2(sch_1):page214_i24@mstr_discrete.capp(chips)!CAPP_3018-470UF,2.5V,20%,ALUM,A!C6R5!//jf4cfls225.pdx.intel.com/apd_proj/ppg_lib/epg_masterlib/logical/mstr_discrete/capp/chips/chips.prt!CAPP!CAPP_3018-470UF,2.5V,20%,ALUM,699013-049!CAPP!!!F4152!!PVCCIO_CPU1!!
S!@baseboard_fab2_lib.baseboard_fab2(sch_1):page214_i21@mstr_discrete.capp(chips)!CAPP_3018-470UF,2.5V,20%,ALUM,A!C6R12!//jf4cfls225.pdx.intel.com/apd_proj/ppg_lib/epg_masterlib/logical/mstr_discrete/capp/chips/chips.prt!CAPP!CAPP_3018-470UF,2.5V,20%,ALUM,699013-049!CAPP!!!F4150!!PVCCIO_CPU1!!
S!@baseboard_fab2_lib.baseboard_fab2(sch_1):page214_i20@mstr_discrete.capp(chips)!CAPP_3018-470UF,2.5V,20%,ALUM,A!C4E7!//jf4cfls225.pdx.intel.com/apd_proj/ppg_lib/epg_masterlib/logical/mstr_discrete/capp/chips/chips.prt!CAPP!CAPP_3018-470UF,2.5V,20%,ALUM,699013-049!CAPP!!!F4165!!PVCCIO_CPU1!!
S!@baseboard_fab2_lib.baseboard_fab2(sch_1):page205_i14@mstr_discrete.capp(chips)!CAPP_3018-470UF,2.5V,20%,ALUM,A!C6N4!//jf4cfls225.pdx.intel.com/apd_proj/ppg_lib/epg_masterlib/logical/mstr_discrete/capp/chips/chips.prt!CAPP!CAPP_3018-470UF,2.5V,20%,ALUM,699013-049!CAPP!!!F4159!!PVSA_CPU0_DECAP_VR!!
S!@baseboard_fab2_lib.baseboard_fab2(sch_1):page205_i12@mstr_discrete.capp(chips)!CAPP_3018-470UF,2.5V,20%,ALUM,A!C6N1!//jf4cfls225.pdx.intel.com/apd_proj/ppg_lib/epg_masterlib/logical/mstr_discrete/capp/chips/chips.prt!CAPP!CAPP_3018-470UF,2.5V,20%,ALUM,699013-049!CAPP!!!F4160!!PVSA_CPU0_DECAP_VR!!
S!@baseboard_fab2_lib.baseboard_fab2(sch_1):page217_i75@mstr_discrete.capp(chips)!CAPP_3018-470UF,2.5V,20%,ALUM,A!C7G28!//jf4cfls225.pdx.intel.com/apd_proj/ppg_lib/epg_masterlib/logical/mstr_discrete/capp/chips/chips.prt!CAPP!CAPP_3018-470UF,2.5V,20%,ALUM,699013-049!CAPP!!!F4148!!VDDQ_ABC_PWR_VR!!
S!@baseboard_fab2_lib.baseboard_fab2(sch_1):page217_i76@mstr_discrete.capp(chips)!CAPP_3018-470UF,2.5V,20%,ALUM,A!C3U1!//jf4cfls225.pdx.intel.com/apd_proj/ppg_lib/epg_masterlib/logical/mstr_discrete/capp/chips/chips.prt!CAPP!CAPP_3018-470UF,2.5V,20%,ALUM,699013-049!CAPP!!!F4169!!VDDQ_ABC_PWR_VR!!
S!@baseboard_fab2_lib.baseboard_fab2(sch_1):page217_i77@mstr_discrete.capp(chips)!CAPP_3018-470UF,2.5V,20%,ALUM,A!C3U5!//jf4cfls225.pdx.intel.com/apd_proj/ppg_lib/epg_masterlib/logical/mstr_discrete/capp/chips/chips.prt!CAPP!CAPP_3018-470UF,2.5V,20%,ALUM,699013-049!CAPP!!!F4168!!VDDQ_ABC_PWR_VR!!
S!@baseboard_fab2_lib.baseboard_fab2(sch_1):page217_i78@mstr_discrete.capp(chips)!CAPP_3018-470UF,2.5V,20%,ALUM,A!C3U8!//jf4cfls225.pdx.intel.com/apd_proj/ppg_lib/epg_masterlib/logical/mstr_discrete/capp/chips/chips.prt!CAPP!CAPP_3018-470UF,2.5V,20%,ALUM,699013-049!CAPP!!!F4167!!VDDQ_ABC_PWR_VR!!
S!@baseboard_fab2_lib.baseboard_fab2(sch_1):page220_i75@mstr_discrete.capp(chips)!CAPP_3018-470UF,2.5V,20%,ALUM,A!C3L6!//jf4cfls225.pdx.intel.com/apd_proj/ppg_lib/epg_masterlib/logical/mstr_discrete/capp/chips/chips.prt!CAPP!CAPP_3018-470UF,2.5V,20%,ALUM,699013-049!CAPP!!!F4176!!VDDQ_DEF_PWR_VR!!
S!@baseboard_fab2_lib.baseboard_fab2(sch_1):page220_i76@mstr_discrete.capp(chips)!CAPP_3018-470UF,2.5V,20%,ALUM,A!C3L14!//jf4cfls225.pdx.intel.com/apd_proj/ppg_lib/epg_masterlib/logical/mstr_discrete/capp/chips/chips.prt!CAPP!CAPP_3018-470UF,2.5V,20%,ALUM,699013-049!CAPP!!!F4175!!VDDQ_DEF_PWR_VR!!
S!@baseboard_fab2_lib.baseboard_fab2(sch_1):page220_i77@mstr_discrete.capp(chips)!CAPP_3018-470UF,2.5V,20%,ALUM,A!C6A5!//jf4cfls225.pdx.intel.com/apd_proj/ppg_lib/epg_masterlib/logical/mstr_discrete/capp/chips/chips.prt!CAPP!CAPP_3018-470UF,2.5V,20%,ALUM,699013-049!CAPP!!!F4161!!VDDQ_DEF_PWR_VR!!
S!@baseboard_fab2_lib.baseboard_fab2(sch_1):page220_i78@mstr_discrete.capp(chips)!CAPP_3018-470UF,2.5V,20%,ALUM,A!C4L5!//jf4cfls225.pdx.intel.com/apd_proj/ppg_lib/epg_masterlib/logical/mstr_discrete/capp/chips/chips.prt!CAPP!CAPP_3018-470UF,2.5V,20%,ALUM,699013-049!CAPP!!!F4163!!VDDQ_DEF_PWR_VR!!
S!@baseboard_fab2_lib.baseboard_fab2(sch_1):page225_i75@mstr_discrete.capp(chips)!CAPP_3018-470UF,2.5V,20%,ALUM,A!C9T5!//jf4cfls225.pdx.intel.com/apd_proj/ppg_lib/epg_masterlib/logical/mstr_discrete/capp/chips/chips.prt!CAPP!CAPP_3018-470UF,2.5V,20%,ALUM,699013-049!CAPP!!!F4134!!VDDQ_GHJ_PWR_VR!!
S!@baseboard_fab2_lib.baseboard_fab2(sch_1):page225_i76@mstr_discrete.capp(chips)!CAPP_3018-470UF,2.5V,20%,ALUM,A!C9U2!//jf4cfls225.pdx.intel.com/apd_proj/ppg_lib/epg_masterlib/logical/mstr_discrete/capp/chips/chips.prt!CAPP!CAPP_3018-470UF,2.5V,20%,ALUM,699013-049!CAPP!!!F4133!!VDDQ_GHJ_PWR_VR!!
S!@baseboard_fab2_lib.baseboard_fab2(sch_1):page225_i77@mstr_discrete.capp(chips)!CAPP_3018-470UF,2.5V,20%,ALUM,A!C9U9!//jf4cfls225.pdx.intel.com/apd_proj/ppg_lib/epg_masterlib/logical/mstr_discrete/capp/chips/chips.prt!CAPP!CAPP_3018-470UF,2.5V,20%,ALUM,699013-049!CAPP!!!F4131!!VDDQ_GHJ_PWR_VR!!
S!@baseboard_fab2_lib.baseboard_fab2(sch_1):page225_i78@mstr_discrete.capp(chips)!CAPP_3018-470UF,2.5V,20%,ALUM,A!C9U5!//jf4cfls225.pdx.intel.com/apd_proj/ppg_lib/epg_masterlib/logical/mstr_discrete/capp/chips/chips.prt!CAPP!CAPP_3018-470UF,2.5V,20%,ALUM,699013-049!CAPP!!!F4132!!VDDQ_GHJ_PWR_VR!!
S!@baseboard_fab2_lib.baseboard_fab2(sch_1):page228_i75@mstr_discrete.capp(chips)!CAPP_3018-470UF,2.5V,20%,ALUM,A!C9L9!//jf4cfls225.pdx.intel.com/apd_proj/ppg_lib/epg_masterlib/logical/mstr_discrete/capp/chips/chips.prt!CAPP!CAPP_3018-470UF,2.5V,20%,ALUM,699013-049!CAPP!!!F4145!!VDDQ_KLM_PWR_VR!!
S!@baseboard_fab2_lib.baseboard_fab2(sch_1):page228_i76@mstr_discrete.capp(chips)!CAPP_3018-470UF,2.5V,20%,ALUM,A!C9L12!//jf4cfls225.pdx.intel.com/apd_proj/ppg_lib/epg_masterlib/logical/mstr_discrete/capp/chips/chips.prt!CAPP!CAPP_3018-470UF,2.5V,20%,ALUM,699013-049!CAPP!!!F4144!!VDDQ_KLM_PWR_VR!!
S!@baseboard_fab2_lib.baseboard_fab2(sch_1):page228_i77@mstr_discrete.capp(chips)!CAPP_3018-470UF,2.5V,20%,ALUM,A!C9L4!//jf4cfls225.pdx.intel.com/apd_proj/ppg_lib/epg_masterlib/logical/mstr_discrete/capp/chips/chips.prt!CAPP!CAPP_3018-470UF,2.5V,20%,ALUM,699013-049!CAPP!!!F4146!!VDDQ_KLM_PWR_VR!!
S!@baseboard_fab2_lib.baseboard_fab2(sch_1):page228_i78@mstr_discrete.capp(chips)!CAPP_3018-470UF,2.5V,20%,ALUM,A!C9L2!//jf4cfls225.pdx.intel.com/apd_proj/ppg_lib/epg_masterlib/logical/mstr_discrete/capp/chips/chips.prt!CAPP!CAPP_3018-470UF,2.5V,20%,ALUM,699013-049!CAPP!!!F4147!!VDDQ_KLM_PWR_VR!!
S!@baseboard_fab2_lib.baseboard_fab2(sch_1):page208_i30@mstr_discrete.capp(chips)!CAPP_3018-470UF,2.5V,20%,ALUM,A!C9P18!//jf4cfls225.pdx.intel.com/apd_proj/ppg_lib/epg_masterlib/logical/mstr_discrete/capp/chips/chips.prt!CAPP!CAPP_3018-470UF,2.5V,20%,ALUM,699013-049!CAPP!!!F4138!!PVCCIN_CPU1_DECAP_VR!!
S!@baseboard_fab2_lib.baseboard_fab2(sch_1):page208_i28@mstr_discrete.capp(chips)!CAPP_3018-470UF,2.5V,20%,ALUM,A!C9P23!//jf4cfls225.pdx.intel.com/apd_proj/ppg_lib/epg_masterlib/logical/mstr_discrete/capp/chips/chips.prt!CAPP!CAPP_3018-470UF,2.5V,20%,ALUM,699013-049!CAPP!!!F4137!!PVCCIN_CPU1_DECAP_VR!!
S!@baseboard_fab2_lib.baseboard_fab2(sch_1):page208_i26@mstr_discrete.capp(chips)!CAPP_3018-470UF,2.5V,20%,ALUM,A!C9R3!//jf4cfls225.pdx.intel.com/apd_proj/ppg_lib/epg_masterlib/logical/mstr_discrete/capp/chips/chips.prt!CAPP!CAPP_3018-470UF,2.5V,20%,ALUM,699013-049!CAPP!!!F4136!!PVCCIN_CPU1_DECAP_VR!!
S!@baseboard_fab2_lib.baseboard_fab2(sch_1):page208_i25@mstr_discrete.capp(chips)!CAPP_3018-470UF,2.5V,20%,ALUM,A!C9R9!//jf4cfls225.pdx.intel.com/apd_proj/ppg_lib/epg_masterlib/logical/mstr_discrete/capp/chips/chips.prt!CAPP!CAPP_3018-470UF,2.5V,20%,ALUM,699013-049!CAPP!!!F4135!!PVCCIN_CPU1_DECAP_VR!!
S!@baseboard_fab2_lib.baseboard_fab2(sch_1):page208_i24@mstr_discrete.capp(chips)!CAPP_3018-470UF,2.5V,20%,ALUM,A!C9N24!//jf4cfls225.pdx.intel.com/apd_proj/ppg_lib/epg_masterlib/logical/mstr_discrete/capp/chips/chips.prt!CAPP!CAPP_3018-470UF,2.5V,20%,ALUM,699013-049!CAPP!!!F4141!!PVCCIN_CPU1_DECAP_VR!!
S!@baseboard_fab2_lib.baseboard_fab2(sch_1):page208_i14@mstr_discrete.capp(chips)!CAPP_3018-470UF,2.5V,20%,ALUM,A!C9P5!//jf4cfls225.pdx.intel.com/apd_proj/ppg_lib/epg_masterlib/logical/mstr_discrete/capp/chips/chips.prt!CAPP!CAPP_3018-470UF,2.5V,20%,ALUM,699013-049!CAPP!!!F4140!!PVCCIN_CPU1_DECAP_VR!!
S!@baseboard_fab2_lib.baseboard_fab2(sch_1):page208_i12@mstr_discrete.capp(chips)!CAPP_3018-470UF,2.5V,20%,ALUM,A!C9P8!//jf4cfls225.pdx.intel.com/apd_proj/ppg_lib/epg_masterlib/logical/mstr_discrete/capp/chips/chips.prt!CAPP!CAPP_3018-470UF,2.5V,20%,ALUM,699013-049!CAPP!!!F4139!!PVCCIN_CPU1_DECAP_VR!!
S!@baseboard_fab2_lib.baseboard_fab2(sch_1):page210_i14@mstr_discrete.capp(chips)!CAPP_3018-470UF,2.5V,20%,ALUM,A!C9N20!//jf4cfls225.pdx.intel.com/apd_proj/ppg_lib/epg_masterlib/logical/mstr_discrete/capp/chips/chips.prt!CAPP!CAPP_3018-470UF,2.5V,20%,ALUM,699013-049!CAPP!!!F4142!!PVSA_CPU1_DECAP_VR!!
S!@baseboard_fab2_lib.baseboard_fab2(sch_1):page210_i12@mstr_discrete.capp(chips)!CAPP_3018-470UF,2.5V,20%,ALUM,A!C9N11!//jf4cfls225.pdx.intel.com/apd_proj/ppg_lib/epg_masterlib/logical/mstr_discrete/capp/chips/chips.prt!CAPP!CAPP_3018-470UF,2.5V,20%,ALUM,699013-049!CAPP!!!F4143!!PVSA_CPU1_DECAP_VR!!
S!@baseboard_fab2_lib.baseboard_fab2(sch_1):page236_i76@mstr_discrete.capp(chips)!CAPP_SM-470UF,2V,20%,ALUM,6990A!C3L19!//jf4cfls225.pdx.intel.com/apd_proj/ppg_lib/epg_masterlib/logical/mstr_discrete/capp/chips/chips.prt!CAPP!CAPP_SM-470UF,2V,20%,ALUM,699013-031!CAPP!!!F4095!!P1V05_PCH_STBY!!
S!@baseboard_fab2_lib.baseboard_fab2(sch_1):page236_i71@mstr_discrete.capp(chips)!CAPP_SM-470UF,2V,20%,ALUM,6990A!C3L18!//jf4cfls225.pdx.intel.com/apd_proj/ppg_lib/epg_masterlib/logical/mstr_discrete/capp/chips/chips.prt!CAPP!CAPP_SM-470UF,2V,20%,ALUM,699013-031!CAPP!!!F4096!!PVNN_PCH_STBY!!
S!@baseboard_fab2_lib.baseboard_fab2(sch_1):page236_i73@mstr_discrete.capp(chips)!CAPP_SM-470UF,2V,20%,ALUM,6990A!C3L20!//jf4cfls225.pdx.intel.com/apd_proj/ppg_lib/epg_masterlib/logical/mstr_discrete/capp/chips/chips.prt!CAPP!CAPP_SM-470UF,2V,20%,ALUM,699013-031!CAPP!!!F4094!!PVNN_PCH_STBY!!
S!@baseboard_fab2_lib.baseboard_fab2(sch_1):page236_i74@mstr_discrete.capp(chips)!CAPP_SM-470UF,2V,20%,ALUM,6990A!C3L21!//jf4cfls225.pdx.intel.com/apd_proj/ppg_lib/epg_masterlib/logical/mstr_discrete/capp/chips/chips.prt!CAPP!CAPP_SM-470UF,2V,20%,ALUM,699013-031!CAPP!!!F4093!!PVNN_PCH_STBY!!
S!@baseboard_fab2_lib.baseboard_fab2(sch_1):page236_i75@mstr_discrete.capp(chips)!CAPP_SM-470UF,2V,20%,ALUM,6990A!C7A27!//jf4cfls225.pdx.intel.com/apd_proj/ppg_lib/epg_masterlib/logical/mstr_discrete/capp/chips/chips.prt!CAPP!CAPP_SM-470UF,2V,20%,ALUM,699013-031!CAPP!!!F4092!!PVNN_PCH_STBY!!
S!@baseboard_fab2_lib.baseboard_fab2(sch_1):page236_i77@mstr_discrete.capp(chips)!CAPP_SM-470UF,2V,20%,ALUM,6990A!C2L46!//jf4cfls225.pdx.intel.com/apd_proj/ppg_lib/epg_masterlib/logical/mstr_discrete/capp/chips/chips.prt!CAPP!CAPP_SM-470UF,2V,20%,ALUM,699013-031!CAPP!!!F4097!!P1V05_PCH_STBY!!
S!@baseboard_fab2_lib.baseboard_fab2(sch_1):page236_i78@mstr_discrete.capp(chips)!CAPP_SM-470UF,2V,20%,ALUM,6990A!C8A15!//jf4cfls225.pdx.intel.com/apd_proj/ppg_lib/epg_masterlib/logical/mstr_discrete/capp/chips/chips.prt!CAPP!CAPP_SM-470UF,2V,20%,ALUM,699013-031!CAPP!!!F4091!!P1V05_PCH_STBY!!
S!@baseboard_fab2_lib.baseboard_fab2(sch_1):page236_i79@mstr_discrete.capp(chips)!CAPP_SM-470UF,2V,20%,ALUM,6990A!C2L25!//jf4cfls225.pdx.intel.com/apd_proj/ppg_lib/epg_masterlib/logical/mstr_discrete/capp/chips/chips.prt!CAPP!CAPP_SM-470UF,2V,20%,ALUM,699013-031!CAPP!!!F4098!!P1V05_PCH_STBY!!
S!@baseboard_fab2_lib.baseboard_fab2(sch_1):page196_i102@mstr_discrete.cap(chips)!CAP_0402-1.0UF,6.3V,10%,X6S,D9A!C2U26!//jf4cfls225.pdx.intel.com/apd_proj/ppg_lib/epg_masterlib/logical/mstr_discrete/cap/chips/chips.prt!CAP!CAP_0402-1.0UF,6.3V,10%,X6S,D97712-004!CAP_0402!!!F3682!!SB_VRD!!
S!@baseboard_fab2_lib.baseboard_fab2(sch_1):page177_i20@mstr_discrete.cap(chips)!CAP_0402-1.0UF,6.3V,10%,X6S,D9A!C1M3!//jf4cfls225.pdx.intel.com/apd_proj/ppg_lib/epg_masterlib/logical/mstr_discrete/cap/chips/chips.prt!CAP!CAP_0402-1.0UF,6.3V,10%,X6S,D97712-004!CAP_0402!!!F3736!!MIO_CHASSIS!!
S!@baseboard_fab2_lib.baseboard_fab2(sch_1):page157_i353@mstr_discrete.cap(chips)!CAP_0402-1.0UF,6.3V,10%,X6S,D9A!C2R12!//jf4cfls225.pdx.intel.com/apd_proj/ppg_lib/epg_masterlib/logical/mstr_discrete/cap/chips/chips.prt!CAP!CAP_0402-1.0UF,6.3V,10%,X6S,D97712-004!CAP_0402!!!F3688!!MIO_CHASSIS!!
S!@baseboard_fab2_lib.baseboard_fab2(sch_1):page113_i117@mstr_discrete.cap(chips)!CAP_0402-1.0UF,6.3V,10%,X6S,D9A!C1M32!//jf4cfls225.pdx.intel.com/apd_proj/ppg_lib/epg_masterlib/logical/mstr_discrete/cap/chips/chips.prt!CAP!CAP_0402-1.0UF,6.3V,10%,X6S,D97712-004!CAP_0402!!!F3689!!DEBUG!!
S!@baseboard_fab2_lib.baseboard_fab2(sch_1):page186_i335@mstr_discrete.cap(chips)!CAP_0402-1.0UF,6.3V,10%,X6S,D9A!C1M25!//jf4cfls225.pdx.intel.com/apd_proj/ppg_lib/epg_masterlib/logical/mstr_discrete/cap/chips/chips.prt!CAP!CAP_0402-1.0UF,6.3V,10%,X6S,D97712-004!CAP_0402!!!F3734!!IO_SLOT!!
S!@baseboard_fab2_lib.baseboard_fab2(sch_1):page215_i309@mstr_discrete.cap(chips)!CAP_0402-1.0UF,6.3V,10%,X6S,D9A!C7F18!//jf4cfls225.pdx.intel.com/apd_proj/ppg_lib/epg_masterlib/logical/mstr_discrete/cap/chips/chips.prt!CAP!CAP_0402-1.0UF,6.3V,10%,X6S,D97712-004!CAP_0402!!!F3616!!VDDQ_ABC_PWR_VR!!
S!@baseboard_fab2_lib.baseboard_fab2(sch_1):page215_i325@mstr_discrete.cap(chips)!CAP_0402-1.0UF,6.3V,10%,X6S,D9A!C7F16!//jf4cfls225.pdx.intel.com/apd_proj/ppg_lib/epg_masterlib/logical/mstr_discrete/cap/chips/chips.prt!CAP!CAP_0402-1.0UF,6.3V,10%,X6S,D97712-004!CAP_0402!!!F3617!!VDDQ_ABC_PWR_VR!!
S!@baseboard_fab2_lib.baseboard_fab2(sch_1):page201_i37@mstr_discrete.cap(chips)!CAP_0402-1.0UF,6.3V,10%,X6S,D9A!C4D15!//jf4cfls225.pdx.intel.com/apd_proj/ppg_lib/epg_masterlib/logical/mstr_discrete/cap/chips/chips.prt!CAP!CAP_0402-1.0UF,6.3V,10%,X6S,D97712-004!CAP_0402!!!F3636!!PVCCIN_CPU0_VR!!
S!@baseboard_fab2_lib.baseboard_fab2(sch_1):page201_i30@mstr_discrete.cap(chips)!CAP_0402-1.0UF,6.3V,10%,X6S,D9A!C4D25!//jf4cfls225.pdx.intel.com/apd_proj/ppg_lib/epg_masterlib/logical/mstr_discrete/cap/chips/chips.prt!CAP!CAP_0402-1.0UF,6.3V,10%,X6S,D97712-004!CAP_0402!!!F3634!!PVCCIN_CPU0_VR!!
S!@baseboard_fab2_lib.baseboard_fab2(sch_1):page206_i41@mstr_discrete.cap(chips)!CAP_0402-1.0UF,6.3V,10%,X6S,D9A!C1C7!//jf4cfls225.pdx.intel.com/apd_proj/ppg_lib/epg_masterlib/logical/mstr_discrete/cap/chips/chips.prt!CAP!CAP_0402-1.0UF,6.3V,10%,X6S,D97712-004!CAP_0402!!!F3750!!PVCCIN_CPU1_VR!!
S!@baseboard_fab2_lib.baseboard_fab2(sch_1):page218_i29@mstr_discrete.cap(chips)!CAP_0402-1.0UF,6.3V,10%,X6S,D9A!C7A37!//jf4cfls225.pdx.intel.com/apd_proj/ppg_lib/epg_masterlib/logical/mstr_discrete/cap/chips/chips.prt!CAP!CAP_0402-1.0UF,6.3V,10%,X6S,D97712-004!CAP_0402!!!F3621!!VDDQ_DEF_PWR_VR!!
S!@baseboard_fab2_lib.baseboard_fab2(sch_1):page218_i22@mstr_discrete.cap(chips)!CAP_0402-1.0UF,6.3V,10%,X6S,D9A!C7B1!//jf4cfls225.pdx.intel.com/apd_proj/ppg_lib/epg_masterlib/logical/mstr_discrete/cap/chips/chips.prt!CAP!CAP_0402-1.0UF,6.3V,10%,X6S,D97712-004!CAP_0402!!!F3620!!VDDQ_DEF_PWR_VR!!
S!@baseboard_fab2_lib.baseboard_fab2(sch_1):page223_i25@mstr_discrete.cap(chips)!CAP_0402-1.0UF,6.3V,10%,X6S,D9A!C1G27!//jf4cfls225.pdx.intel.com/apd_proj/ppg_lib/epg_masterlib/logical/mstr_discrete/cap/chips/chips.prt!CAP!CAP_0402-1.0UF,6.3V,10%,X6S,D97712-004!CAP_0402!!!F3740!!VDDQ_GHJ_PWR_VR!!
S!@baseboard_fab2_lib.baseboard_fab2(sch_1):page223_i41@mstr_discrete.cap(chips)!CAP_0402-1.0UF,6.3V,10%,X6S,D9A!C1G23!//jf4cfls225.pdx.intel.com/apd_proj/ppg_lib/epg_masterlib/logical/mstr_discrete/cap/chips/chips.prt!CAP!CAP_0402-1.0UF,6.3V,10%,X6S,D97712-004!CAP_0402!!!F3741!!VDDQ_GHJ_PWR_VR!!
S!@baseboard_fab2_lib.baseboard_fab2(sch_1):page226_i25@mstr_discrete.cap(chips)!CAP_0402-1.0UF,6.3V,10%,X6S,D9A!C1B6!//jf4cfls225.pdx.intel.com/apd_proj/ppg_lib/epg_masterlib/logical/mstr_discrete/cap/chips/chips.prt!CAP!CAP_0402-1.0UF,6.3V,10%,X6S,D97712-004!CAP_0402!!!F3752!!VDDQ_KLM_PWR_VR!!
S!@baseboard_fab2_lib.baseboard_fab2(sch_1):page226_i41@mstr_discrete.cap(chips)!CAP_0402-1.0UF,6.3V,10%,X6S,D9A!C1B3!//jf4cfls225.pdx.intel.com/apd_proj/ppg_lib/epg_masterlib/logical/mstr_discrete/cap/chips/chips.prt!CAP!CAP_0402-1.0UF,6.3V,10%,X6S,D97712-004!CAP_0402!!!F3753!!VDDQ_KLM_PWR_VR!!
S!@baseboard_fab2_lib.baseboard_fab2(sch_1):page206_i29@mstr_discrete.cap(chips)!CAP_0402-1.0UF,6.3V,10%,X6S,D9A!C1C13!//jf4cfls225.pdx.intel.com/apd_proj/ppg_lib/epg_masterlib/logical/mstr_discrete/cap/chips/chips.prt!CAP!CAP_0402-1.0UF,6.3V,10%,X6S,D97712-004!CAP_0402!!!F3749!!PVCCIN_CPU1_VR!!
S!@baseboard_fab2_lib.baseboard_fab2(sch_1):page186_i334@mstr_discrete.cap(chips)!CAP_0402-1.0UF,6.3V,10%,X6S,D9A!C1M21!//jf4cfls225.pdx.intel.com/apd_proj/ppg_lib/epg_masterlib/logical/mstr_discrete/cap/chips/chips.prt!CAP!CAP_0402-1.0UF,6.3V,10%,X6S,D97712-004!CAP_0402!!!F3735!!IO_SLOT!!
S!@baseboard_fab2_lib.baseboard_fab2(sch_1):page211_i11@mstr_discrete.cap(chips)!CAP_0402-1.0UF,6.3V,10%,X6S,D9A!C3P4!//jf4cfls225.pdx.intel.com/apd_proj/ppg_lib/epg_masterlib/logical/mstr_discrete/cap/chips/chips.prt!CAP!CAP_0402-1.0UF,6.3V,10%,X6S,D97712-004!CAP_0402!!!F3646!!PVCCIO_CPU0!!
S!@baseboard_fab2_lib.baseboard_fab2(sch_1):page213_i9@mstr_discrete.cap(chips)!CAP_0402-1.0UF,6.3V,10%,X6S,D9A!C4D31!//jf4cfls225.pdx.intel.com/apd_proj/ppg_lib/epg_masterlib/logical/mstr_discrete/cap/chips/chips.prt!CAP!CAP_0402-1.0UF,6.3V,10%,X6S,D97712-004!CAP_0402!!!F3632!!PVCCIO_CPU1!!
S!@baseboard_fab2_lib.baseboard_fab2(sch_1):page211_i20@mstr_discrete.cap(chips)!CAP_0402-1.0UF,6.3V,10%,X6S,D9A!C3P3!//jf4cfls225.pdx.intel.com/apd_proj/ppg_lib/epg_masterlib/logical/mstr_discrete/cap/chips/chips.prt!CAP!CAP_0402-1.0UF,6.3V,10%,X6S,D97712-004!CAP_0402!!!F3647!!PVCCIO_CPU0!!
S!@baseboard_fab2_lib.baseboard_fab2(sch_1):page213_i17@mstr_discrete.cap(chips)!CAP_0402-1.0UF,6.3V,10%,X6S,D9A!C4D36!//jf4cfls225.pdx.intel.com/apd_proj/ppg_lib/epg_masterlib/logical/mstr_discrete/cap/chips/chips.prt!CAP!CAP_0402-1.0UF,6.3V,10%,X6S,D97712-004!CAP_0402!!!F3631!!PVCCIO_CPU1!!
S!@baseboard_fab2_lib.baseboard_fab2(sch_1):page235_i143@mstr_discrete.cap(chips)!CAP_0402-1.0UF,6.3V,10%,X6S,D9A!C8A7!//jf4cfls225.pdx.intel.com/apd_proj/ppg_lib/epg_masterlib/logical/mstr_discrete/cap/chips/chips.prt!CAP!CAP_0402-1.0UF,6.3V,10%,X6S,D97712-004!CAP_0402!!!F3612!!PVNN_PCH_STBY!!
S!@baseboard_fab2_lib.baseboard_fab2(sch_1):page102_i30@mstr_discrete.cap(chips)!CAP_0402-1.0UF,6.3V,10%,X6S,D9A!C4D27!//jf4cfls225.pdx.intel.com/apd_proj/ppg_lib/epg_masterlib/logical/mstr_discrete/cap/chips/chips.prt!CAP!CAP_0402-1.0UF,6.3V,10%,X6S,D97712-004!CAP_0402!!!F3633!!DB1200ZL!!
S!@baseboard_fab2_lib.baseboard_fab2(sch_1):page102_i19@mstr_discrete.cap(chips)!CAP_0402-1.0UF,6.3V,10%,X6S,D9A!C4D23!//jf4cfls225.pdx.intel.com/apd_proj/ppg_lib/epg_masterlib/logical/mstr_discrete/cap/chips/chips.prt!CAP!CAP_0402-1.0UF,6.3V,10%,X6S,D97712-004!CAP_0402!!!F3635!!DB1200ZL!!
S!@baseboard_fab2_lib.baseboard_fab2(sch_1):page235_i151@mstr_discrete.cap(chips)!CAP_0402-1.0UF,6.3V,10%,X6S,D9A!C2L8!//jf4cfls225.pdx.intel.com/apd_proj/ppg_lib/epg_masterlib/logical/mstr_discrete/cap/chips/chips.prt!CAP!CAP_0402-1.0UF,6.3V,10%,X6S,D97712-004!CAP_0402!!!F3718!!PVNN_PCH_STBY!!
S!@baseboard_fab2_lib.baseboard_fab2(sch_1):page127_i63@mstr_discrete.cap(chips)!CAP_0402-1.0UF,6.3V,10%,X6S,D9A!C2N1!//jf4cfls225.pdx.intel.com/apd_proj/ppg_lib/epg_masterlib/logical/mstr_discrete/cap/chips/chips.prt!CAP!CAP_0402-1.0UF,6.3V,10%,X6S,D97712-004!CAP_0402!!!F3707!!SB_FILTER_KR_PLL!!
S!@baseboard_fab2_lib.baseboard_fab2(sch_1):page127_i31@mstr_discrete.cap(chips)!CAP_0402-1.0UF,6.3V,10%,X6S,D9A!C3M19!//jf4cfls225.pdx.intel.com/apd_proj/ppg_lib/epg_masterlib/logical/mstr_discrete/cap/chips/chips.prt!CAP!CAP_0402-1.0UF,6.3V,10%,X6S,D97712-004!CAP_0402!!!F3678!!SB_FILTER_PLL0!!
S!@baseboard_fab2_lib.baseboard_fab2(sch_1):page127_i33@mstr_discrete.cap(chips)!CAP_0402-1.0UF,6.3V,10%,X6S,D9A!C3M20!//jf4cfls225.pdx.intel.com/apd_proj/ppg_lib/epg_masterlib/logical/mstr_discrete/cap/chips/chips.prt!CAP!CAP_0402-1.0UF,6.3V,10%,X6S,D97712-004!CAP_0402!!!F3677!!SB_FILTER_PLL1!!
S!@baseboard_fab2_lib.baseboard_fab2(sch_1):page127_i42@mstr_discrete.cap(chips)!CAP_0402-1.0UF,6.3V,10%,X6S,D9A!C2M6!//jf4cfls225.pdx.intel.com/apd_proj/ppg_lib/epg_masterlib/logical/mstr_discrete/cap/chips/chips.prt!CAP!CAP_0402-1.0UF,6.3V,10%,X6S,D97712-004!CAP_0402!!!F3717!!SB_FILTER_VM20!!
S!@baseboard_fab2_lib.baseboard_fab2(sch_1):page127_i35@mstr_discrete.cap(chips)!CAP_0402-1.0UF,6.3V,10%,X6S,D9A!C3M27!//jf4cfls225.pdx.intel.com/apd_proj/ppg_lib/epg_masterlib/logical/mstr_discrete/cap/chips/chips.prt!CAP!CAP_0402-1.0UF,6.3V,10%,X6S,D97712-004!CAP_0402!!!F3674!!SB_FILTER_XTAL!!
S!@baseboard_fab2_lib.baseboard_fab2(sch_1):page127_i53@mstr_discrete.cap(chips)!CAP_0402-1.0UF,6.3V,10%,X6S,D9A!C3M29!//jf4cfls225.pdx.intel.com/apd_proj/ppg_lib/epg_masterlib/logical/mstr_discrete/cap/chips/chips.prt!CAP!CAP_0402-1.0UF,6.3V,10%,X6S,D97712-004!CAP_0402!!!F3673!!SB_FILTER_ISCLK!!
S!@baseboard_fab2_lib.baseboard_fab2(sch_1):page127_i48@mstr_discrete.cap(chips)!CAP_0402-1.0UF,6.3V,10%,X6S,D9A!C2M8!//jf4cfls225.pdx.intel.com/apd_proj/ppg_lib/epg_masterlib/logical/mstr_discrete/cap/chips/chips.prt!CAP!CAP_0402-1.0UF,6.3V,10%,X6S,D97712-004!CAP_0402!!!F3715!!SB_FILTER_VM26!!
S!@baseboard_fab2_lib.baseboard_fab2(sch_1):page175_i11@mstr_discrete.cap(chips)!CAP_0402-1.0UF,6.3V,10%,X6S,D9A!C1L18!//jf4cfls225.pdx.intel.com/apd_proj/ppg_lib/epg_masterlib/logical/mstr_discrete/cap/chips/chips.prt!CAP!CAP_0402-1.0UF,6.3V,10%,X6S,D97712-004!CAP_0402!!!F3737!!MIO_CHASSIS!!
S!@baseboard_fab2_lib.baseboard_fab2(sch_1):page175_i19@mstr_discrete.cap(chips)!CAP_0402-1.0UF,6.3V,10%,X6S,D9A!C1L10!//jf4cfls225.pdx.intel.com/apd_proj/ppg_lib/epg_masterlib/logical/mstr_discrete/cap/chips/chips.prt!CAP!CAP_0402-1.0UF,6.3V,10%,X6S,D97712-004!CAP_0402!!!F3738!!MIO_CHASSIS!!
S!@baseboard_fab2_lib.baseboard_fab2(sch_1):page162_i30@mstr_discrete.cap(chips)!CAP_0402-1.0UF,6.3V,10%,X6S,D9A!C8F4!//jf4cfls225.pdx.intel.com/apd_proj/ppg_lib/epg_masterlib/logical/mstr_discrete/cap/chips/chips.prt!CAP!CAP_0402-1.0UF,6.3V,10%,X6S,D97712-004!CAP_0402!!!F3611!!BMC_BOOT_SPI!!
S!@baseboard_fab2_lib.baseboard_fab2(sch_1):page205_i18@mstr_discrete.cap(chips)!CAP_0402-1.0UF,6.3V,10%,X6S,D9A!C4C4!//jf4cfls225.pdx.intel.com/apd_proj/ppg_lib/epg_masterlib/logical/mstr_discrete/cap/chips/chips.prt!CAP!CAP_0402-1.0UF,6.3V,10%,X6S,D97712-004!CAP_0402!!!F3640!!PVSA_CPU0_PWR_VR!!
S!@baseboard_fab2_lib.baseboard_fab2(sch_1):page236_i38@mstr_discrete.cap(chips)!CAP_0402-1.0UF,6.3V,10%,X6S,D9A!C3L29!//jf4cfls225.pdx.intel.com/apd_proj/ppg_lib/epg_masterlib/logical/mstr_discrete/cap/chips/chips.prt!CAP!CAP_0402-1.0UF,6.3V,10%,X6S,D97712-004!CAP_0402!!!F3613!!P1V05_PCH_STBY_VR!!
S!@baseboard_fab2_lib.baseboard_fab2(sch_1):page236_i17@mstr_discrete.cap(chips)!CAP_0402-1.0UF,6.3V,10%,X6S,D9A!C3L1!//jf4cfls225.pdx.intel.com/apd_proj/ppg_lib/epg_masterlib/logical/mstr_discrete/cap/chips/chips.prt!CAP!CAP_0402-1.0UF,6.3V,10%,X6S,D97712-004!CAP_0402!!!F3679!!PVNN_PCH_STBY!!
S!@baseboard_fab2_lib.baseboard_fab2(sch_1):page194_i86@mstr_discrete.cap(chips)!CAP_0402-1.0UF,6.3V,10%,X6S,D9A!C3N40!//jf4cfls225.pdx.intel.com/apd_proj/ppg_lib/epg_masterlib/logical/mstr_discrete/cap/chips/chips.prt!CAP!CAP_0402-1.0UF,6.3V,10%,X6S,D97712-004!CAP_0402!!!F3644!!P0V95_MCP_CPU0!!
S!@baseboard_fab2_lib.baseboard_fab2(sch_1):page194_i99@mstr_discrete.cap(chips)!CAP_0402-1.0UF,6.3V,10%,X6S,D9A!C3M46!//jf4cfls225.pdx.intel.com/apd_proj/ppg_lib/epg_masterlib/logical/mstr_discrete/cap/chips/chips.prt!CAP!CAP_0402-1.0UF,6.3V,10%,X6S,D97712-004!CAP_0402!!!F3645!!P0V95_MCP_CPU0!!
S!@baseboard_fab2_lib.baseboard_fab2(sch_1):page193_i31@mstr_discrete.cap(chips)!CAP_0402-1.0UF,6.3V,10%,X6S,D9A!C3C2!//jf4cfls225.pdx.intel.com/apd_proj/ppg_lib/epg_masterlib/logical/mstr_discrete/cap/chips/chips.prt!CAP!CAP_0402-1.0UF,6.3V,10%,X6S,D97712-004!CAP_0402!!!F3680!!P0V95_FPGA_CPU1!!
S!@baseboard_fab2_lib.baseboard_fab2(sch_1):page193_i38@mstr_discrete.cap(chips)!CAP_0402-1.0UF,6.3V,10%,X6S,D9A!C3C1!//jf4cfls225.pdx.intel.com/apd_proj/ppg_lib/epg_masterlib/logical/mstr_discrete/cap/chips/chips.prt!CAP!CAP_0402-1.0UF,6.3V,10%,X6S,D97712-004!CAP_0402!!!F3681!!P0V95_FPGA_CPU1!!
S!@baseboard_fab2_lib.baseboard_fab2(sch_1):page194_i9@mstr_discrete.cap(chips)!CAP_0402-1.0UF,6.3V,10%,X6S,D9A!C4T2!//jf4cfls225.pdx.intel.com/apd_proj/ppg_lib/epg_masterlib/logical/mstr_discrete/cap/chips/chips.prt!CAP!CAP_0402-1.0UF,6.3V,10%,X6S,D97712-004!CAP_0402!!!F3625!!P1V8_MCP_CPU0!!
S!@baseboard_fab2_lib.baseboard_fab2(sch_1):page194_i16@mstr_discrete.cap(chips)!CAP_0402-1.0UF,6.3V,10%,X6S,D9A!C4T1!//jf4cfls225.pdx.intel.com/apd_proj/ppg_lib/epg_masterlib/logical/mstr_discrete/cap/chips/chips.prt!CAP!CAP_0402-1.0UF,6.3V,10%,X6S,D97712-004!CAP_0402!!!F3626!!P1V8_MCP_CPU0!!
S!@baseboard_fab2_lib.baseboard_fab2(sch_1):page193_i68@mstr_discrete.cap(chips)!CAP_0402-1.0UF,6.3V,10%,X6S,D9A!C4F1!//jf4cfls225.pdx.intel.com/apd_proj/ppg_lib/epg_masterlib/logical/mstr_discrete/cap/chips/chips.prt!CAP!CAP_0402-1.0UF,6.3V,10%,X6S,D97712-004!CAP_0402!!!F3628!!P1V8_MCP_CPU1!!
S!@baseboard_fab2_lib.baseboard_fab2(sch_1):page193_i70@mstr_discrete.cap(chips)!CAP_0402-1.0UF,6.3V,10%,X6S,D9A!C4F3!//jf4cfls225.pdx.intel.com/apd_proj/ppg_lib/epg_masterlib/logical/mstr_discrete/cap/chips/chips.prt!CAP!CAP_0402-1.0UF,6.3V,10%,X6S,D97712-004!CAP_0402!!!F3627!!P1V8_MCP_CPU1!!
S!@baseboard_fab2_lib.baseboard_fab2(sch_1):page153_i130@mstr_discrete.cap(chips)!CAP_0402-1.0UF,6.3V,10%,X6S,D9A!C7F2!//jf4cfls225.pdx.intel.com/apd_proj/ppg_lib/epg_masterlib/logical/mstr_discrete/cap/chips/chips.prt!CAP!CAP_0402-1.0UF,6.3V,10%,X6S,D97712-004!CAP_0402!!!F3618!!SB_SPI!!
S!@baseboard_fab2_lib.baseboard_fab2(sch_1):page153_i138@mstr_discrete.cap(chips)!CAP_0402-1.0UF,6.3V,10%,X6S,D9A!C3T4!//jf4cfls225.pdx.intel.com/apd_proj/ppg_lib/epg_masterlib/logical/mstr_discrete/cap/chips/chips.prt!CAP!CAP_0402-1.0UF,6.3V,10%,X6S,D97712-004!CAP_0402!!!F3642!!SB_SPI!!
S!@baseboard_fab2_lib.baseboard_fab2(sch_1):page212_i34@mstr_discrete.cap(chips)!CAP_0402-1.0UF,6.3V,10%,X6S,D9A!C7C20!//jf4cfls225.pdx.intel.com/apd_proj/ppg_lib/epg_masterlib/logical/mstr_discrete/cap/chips/chips.prt!CAP!CAP_0402-1.0UF,6.3V,10%,X6S,D97712-004!CAP_0402!!!F3648!!PVCCIO_CPU0!!
S!@baseboard_fab2_lib.baseboard_fab2(sch_1):page214_i74@mstr_discrete.cap(chips)!CAP_0402-1.0UF,6.3V,10%,X6S,D9A!C4E28!//jf4cfls225.pdx.intel.com/apd_proj/ppg_lib/epg_masterlib/logical/mstr_discrete/cap/chips/chips.prt!CAP!CAP_0402-1.0UF,6.3V,10%,X6S,D97712-004!CAP_0402!!!F3624!!PVCCIO_CPU1!!
S!@baseboard_fab2_lib.baseboard_fab2(sch_1):page203_i41@mstr_discrete.cap(chips)!CAP_0402-1.0UF,6.3V,10%,X6S,D9A!C4D14!//jf4cfls225.pdx.intel.com/apd_proj/ppg_lib/epg_masterlib/logical/mstr_discrete/cap/chips/chips.prt!CAP!CAP_0402-1.0UF,6.3V,10%,X6S,D97712-004!CAP_0402!!!F3637!!PVCCIN_CPU0_PWR_VR!!
S!@baseboard_fab2_lib.baseboard_fab2(sch_1):page203_i49@mstr_discrete.cap(chips)!CAP_0402-1.0UF,6.3V,10%,X6S,D9A!C4D6!//jf4cfls225.pdx.intel.com/apd_proj/ppg_lib/epg_masterlib/logical/mstr_discrete/cap/chips/chips.prt!CAP!CAP_0402-1.0UF,6.3V,10%,X6S,D97712-004!CAP_0402!!!F3638!!PVCCIN_CPU0_PWR_VR!!
S!@baseboard_fab2_lib.baseboard_fab2(sch_1):page151_i62@mstr_discrete.cap(chips)!CAP_0402-1.0UF,6.3V,10%,X6S,D9A!C1T51!//jf4cfls225.pdx.intel.com/apd_proj/ppg_lib/epg_masterlib/logical/mstr_discrete/cap/chips/chips.prt!CAP!CAP_0402-1.0UF,6.3V,10%,X6S,D97712-004!CAP_0402!!!F3724!!BMC_MEMORY!!
S!@baseboard_fab2_lib.baseboard_fab2(sch_1):page132_i48@mstr_discrete.cap(chips)!CAP_0402-1.0UF,6.3V,10%,X6S,D9A!C3N5!//jf4cfls225.pdx.intel.com/apd_proj/ppg_lib/epg_masterlib/logical/mstr_discrete/cap/chips/chips.prt!CAP!CAP_0402-1.0UF,6.3V,10%,X6S,D97712-004!CAP_0402!!!F3662!!SB_DECOUPLING!!
S!@baseboard_fab2_lib.baseboard_fab2(sch_1):page132_i51@mstr_discrete.cap(chips)!CAP_0402-1.0UF,6.3V,10%,X6S,D9A!C3N20!//jf4cfls225.pdx.intel.com/apd_proj/ppg_lib/epg_masterlib/logical/mstr_discrete/cap/chips/chips.prt!CAP!CAP_0402-1.0UF,6.3V,10%,X6S,D97712-004!CAP_0402!!!F3654!!SB_DECOUPLING!!
S!@baseboard_fab2_lib.baseboard_fab2(sch_1):page132_i46@mstr_discrete.cap(chips)!CAP_0402-1.0UF,6.3V,10%,X6S,D9A!C3N4!//jf4cfls225.pdx.intel.com/apd_proj/ppg_lib/epg_masterlib/logical/mstr_discrete/cap/chips/chips.prt!CAP!CAP_0402-1.0UF,6.3V,10%,X6S,D97712-004!CAP_0402!!!F3663!!SB_DECOUPLING!!
S!@baseboard_fab2_lib.baseboard_fab2(sch_1):page132_i49@mstr_discrete.cap(chips)!CAP_0402-1.0UF,6.3V,10%,X6S,D9A!C3N15!//jf4cfls225.pdx.intel.com/apd_proj/ppg_lib/epg_masterlib/logical/mstr_discrete/cap/chips/chips.prt!CAP!CAP_0402-1.0UF,6.3V,10%,X6S,D97712-004!CAP_0402!!!F3659!!SB_DECOUPLING!!
S!@baseboard_fab2_lib.baseboard_fab2(sch_1):page132_i43@mstr_discrete.cap(chips)!CAP_0402-1.0UF,6.3V,10%,X6S,D9A!C3N2!//jf4cfls225.pdx.intel.com/apd_proj/ppg_lib/epg_masterlib/logical/mstr_discrete/cap/chips/chips.prt!CAP!CAP_0402-1.0UF,6.3V,10%,X6S,D97712-004!CAP_0402!!!F3665!!SB_DECOUPLING!!
S!@baseboard_fab2_lib.baseboard_fab2(sch_1):page132_i45@mstr_discrete.cap(chips)!CAP_0402-1.0UF,6.3V,10%,X6S,D9A!C3N17!//jf4cfls225.pdx.intel.com/apd_proj/ppg_lib/epg_masterlib/logical/mstr_discrete/cap/chips/chips.prt!CAP!CAP_0402-1.0UF,6.3V,10%,X6S,D97712-004!CAP_0402!!!F3657!!SB_DECOUPLING!!
S!@baseboard_fab2_lib.baseboard_fab2(sch_1):page132_i42@mstr_discrete.cap(chips)!CAP_0402-1.0UF,6.3V,10%,X6S,D9A!C3N18!//jf4cfls225.pdx.intel.com/apd_proj/ppg_lib/epg_masterlib/logical/mstr_discrete/cap/chips/chips.prt!CAP!CAP_0402-1.0UF,6.3V,10%,X6S,D97712-004!CAP_0402!!!F3656!!SB_DECOUPLING!!
S!@baseboard_fab2_lib.baseboard_fab2(sch_1):page132_i44@mstr_discrete.cap(chips)!CAP_0402-1.0UF,6.3V,10%,X6S,D9A!C3N6!//jf4cfls225.pdx.intel.com/apd_proj/ppg_lib/epg_masterlib/logical/mstr_discrete/cap/chips/chips.prt!CAP!CAP_0402-1.0UF,6.3V,10%,X6S,D97712-004!CAP_0402!!!F3661!!SB_DECOUPLING!!
S!@baseboard_fab2_lib.baseboard_fab2(sch_1):page132_i32@mstr_discrete.cap(chips)!CAP_0402-1.0UF,6.3V,10%,X6S,D9A!C3N3!//jf4cfls225.pdx.intel.com/apd_proj/ppg_lib/epg_masterlib/logical/mstr_discrete/cap/chips/chips.prt!CAP!CAP_0402-1.0UF,6.3V,10%,X6S,D97712-004!CAP_0402!!!F3664!!SB_DECOUPLING!!
S!@baseboard_fab2_lib.baseboard_fab2(sch_1):page132_i36@mstr_discrete.cap(chips)!CAP_0402-1.0UF,6.3V,10%,X6S,D9A!C3N16!//jf4cfls225.pdx.intel.com/apd_proj/ppg_lib/epg_masterlib/logical/mstr_discrete/cap/chips/chips.prt!CAP!CAP_0402-1.0UF,6.3V,10%,X6S,D97712-004!CAP_0402!!!F3658!!SB_DECOUPLING!!
S!@baseboard_fab2_lib.baseboard_fab2(sch_1):page132_i31@mstr_discrete.cap(chips)!CAP_0402-1.0UF,6.3V,10%,X6S,D9A!C3N19!//jf4cfls225.pdx.intel.com/apd_proj/ppg_lib/epg_masterlib/logical/mstr_discrete/cap/chips/chips.prt!CAP!CAP_0402-1.0UF,6.3V,10%,X6S,D97712-004!CAP_0402!!!F3655!!SB_DECOUPLING!!
S!@baseboard_fab2_lib.baseboard_fab2(sch_1):page132_i35@mstr_discrete.cap(chips)!CAP_0402-1.0UF,6.3V,10%,X6S,D9A!C3N7!//jf4cfls225.pdx.intel.com/apd_proj/ppg_lib/epg_masterlib/logical/mstr_discrete/cap/chips/chips.prt!CAP!CAP_0402-1.0UF,6.3V,10%,X6S,D97712-004!CAP_0402!!!F3660!!SB_DECOUPLING!!
S!@baseboard_fab2_lib.baseboard_fab2(sch_1):page132_i30@mstr_discrete.cap(chips)!CAP_0402-1.0UF,6.3V,10%,X6S,D9A!C2N11!//jf4cfls225.pdx.intel.com/apd_proj/ppg_lib/epg_masterlib/logical/mstr_discrete/cap/chips/chips.prt!CAP!CAP_0402-1.0UF,6.3V,10%,X6S,D97712-004!CAP_0402!!!F3699!!SB_DECOUPLING!!
S!@baseboard_fab2_lib.baseboard_fab2(sch_1):page132_i34@mstr_discrete.cap(chips)!CAP_0402-1.0UF,6.3V,10%,X6S,D9A!C3N1!//jf4cfls225.pdx.intel.com/apd_proj/ppg_lib/epg_masterlib/logical/mstr_discrete/cap/chips/chips.prt!CAP!CAP_0402-1.0UF,6.3V,10%,X6S,D97712-004!CAP_0402!!!F3666!!SB_DECOUPLING!!
S!@baseboard_fab2_lib.baseboard_fab2(sch_1):page132_i27@mstr_discrete.cap(chips)!CAP_0402-1.0UF,6.3V,10%,X6S,D9A!C2N3!//jf4cfls225.pdx.intel.com/apd_proj/ppg_lib/epg_masterlib/logical/mstr_discrete/cap/chips/chips.prt!CAP!CAP_0402-1.0UF,6.3V,10%,X6S,D97712-004!CAP_0402!!!F3705!!SB_DECOUPLING!!
S!@baseboard_fab2_lib.baseboard_fab2(sch_1):page132_i29@mstr_discrete.cap(chips)!CAP_0402-1.0UF,6.3V,10%,X6S,D9A!C2N12!//jf4cfls225.pdx.intel.com/apd_proj/ppg_lib/epg_masterlib/logical/mstr_discrete/cap/chips/chips.prt!CAP!CAP_0402-1.0UF,6.3V,10%,X6S,D97712-004!CAP_0402!!!F3698!!SB_DECOUPLING!!
S!@baseboard_fab2_lib.baseboard_fab2(sch_1):page132_i26@mstr_discrete.cap(chips)!CAP_0402-1.0UF,6.3V,10%,X6S,D9A!C2N9!//jf4cfls225.pdx.intel.com/apd_proj/ppg_lib/epg_masterlib/logical/mstr_discrete/cap/chips/chips.prt!CAP!CAP_0402-1.0UF,6.3V,10%,X6S,D97712-004!CAP_0402!!!F3700!!SB_DECOUPLING!!
S!@baseboard_fab2_lib.baseboard_fab2(sch_1):page132_i28@mstr_discrete.cap(chips)!CAP_0402-1.0UF,6.3V,10%,X6S,D9A!C2N4!//jf4cfls225.pdx.intel.com/apd_proj/ppg_lib/epg_masterlib/logical/mstr_discrete/cap/chips/chips.prt!CAP!CAP_0402-1.0UF,6.3V,10%,X6S,D97712-004!CAP_0402!!!F3704!!SB_DECOUPLING!!
S!@baseboard_fab2_lib.baseboard_fab2(sch_1):page130_i49@mstr_discrete.cap(chips)!CAP_0402-1.0UF,6.3V,10%,X6S,D9A!C3N21!//jf4cfls225.pdx.intel.com/apd_proj/ppg_lib/epg_masterlib/logical/mstr_discrete/cap/chips/chips.prt!CAP!CAP_0402-1.0UF,6.3V,10%,X6S,D97712-004!CAP_0402!!!F3653!!SB_DECOUPLING!!
S!@baseboard_fab2_lib.baseboard_fab2(sch_1):page130_i37@mstr_discrete.cap(chips)!CAP_0402-1.0UF,6.3V,10%,X6S,D9A!C2M16!//jf4cfls225.pdx.intel.com/apd_proj/ppg_lib/epg_masterlib/logical/mstr_discrete/cap/chips/chips.prt!CAP!CAP_0402-1.0UF,6.3V,10%,X6S,D97712-004!CAP_0402!!!F3713!!SB_DECOUPLING!!
S!@baseboard_fab2_lib.baseboard_fab2(sch_1):page130_i34@mstr_discrete.cap(chips)!CAP_0402-1.0UF,6.3V,10%,X6S,D9A!C2N25!//jf4cfls225.pdx.intel.com/apd_proj/ppg_lib/epg_masterlib/logical/mstr_discrete/cap/chips/chips.prt!CAP!CAP_0402-1.0UF,6.3V,10%,X6S,D97712-004!CAP_0402!!!F3691!!SB_DECOUPLING!!
S!@baseboard_fab2_lib.baseboard_fab2(sch_1):page130_i29@mstr_discrete.cap(chips)!CAP_0402-1.0UF,6.3V,10%,X6S,D9A!C2N18!//jf4cfls225.pdx.intel.com/apd_proj/ppg_lib/epg_masterlib/logical/mstr_discrete/cap/chips/chips.prt!CAP!CAP_0402-1.0UF,6.3V,10%,X6S,D97712-004!CAP_0402!!!F3694!!SB_DECOUPLING!!
S!@baseboard_fab2_lib.baseboard_fab2(sch_1):page130_i47@mstr_discrete.cap(chips)!CAP_0402-1.0UF,6.3V,10%,X6S,D9A!C2N15!//jf4cfls225.pdx.intel.com/apd_proj/ppg_lib/epg_masterlib/logical/mstr_discrete/cap/chips/chips.prt!CAP!CAP_0402-1.0UF,6.3V,10%,X6S,D97712-004!CAP_0402!!!F3696!!SB_DECOUPLING!!
S!@baseboard_fab2_lib.baseboard_fab2(sch_1):page131_i41@mstr_discrete.cap(chips)!CAP_0402-1.0UF,6.3V,10%,X6S,D9A!C2N2!//jf4cfls225.pdx.intel.com/apd_proj/ppg_lib/epg_masterlib/logical/mstr_discrete/cap/chips/chips.prt!CAP!CAP_0402-1.0UF,6.3V,10%,X6S,D97712-004!CAP_0402!!!F3706!!SB_DECOUPLING!!
S!@baseboard_fab2_lib.baseboard_fab2(sch_1):page131_i40@mstr_discrete.cap(chips)!CAP_0402-1.0UF,6.3V,10%,X6S,D9A!C2N13!//jf4cfls225.pdx.intel.com/apd_proj/ppg_lib/epg_masterlib/logical/mstr_discrete/cap/chips/chips.prt!CAP!CAP_0402-1.0UF,6.3V,10%,X6S,D97712-004!CAP_0402!!!F3697!!SB_DECOUPLING!!
S!@baseboard_fab2_lib.baseboard_fab2(sch_1):page131_i39@mstr_discrete.cap(chips)!CAP_0402-1.0UF,6.3V,10%,X6S,D9A!C2M20!//jf4cfls225.pdx.intel.com/apd_proj/ppg_lib/epg_masterlib/logical/mstr_discrete/cap/chips/chips.prt!CAP!CAP_0402-1.0UF,6.3V,10%,X6S,D97712-004!CAP_0402!!!F3710!!SB_DECOUPLING!!
S!@baseboard_fab2_lib.baseboard_fab2(sch_1):page131_i29@mstr_discrete.cap(chips)!CAP_0402-1.0UF,6.3V,10%,X6S,D9A!C2M18!//jf4cfls225.pdx.intel.com/apd_proj/ppg_lib/epg_masterlib/logical/mstr_discrete/cap/chips/chips.prt!CAP!CAP_0402-1.0UF,6.3V,10%,X6S,D97712-004!CAP_0402!!!F3712!!SB_DECOUPLING!!
S!@baseboard_fab2_lib.baseboard_fab2(sch_1):page130_i12@mstr_discrete.cap(chips)!CAP_0402-1.0UF,6.3V,10%,X6S,D9A!C2N20!//jf4cfls225.pdx.intel.com/apd_proj/ppg_lib/epg_masterlib/logical/mstr_discrete/cap/chips/chips.prt!CAP!CAP_0402-1.0UF,6.3V,10%,X6S,D97712-004!CAP_0402!!!F3692!!SB_DECOUPLING!!
S!@baseboard_fab2_lib.baseboard_fab2(sch_1):page131_i28@mstr_discrete.cap(chips)!CAP_0402-1.0UF,6.3V,10%,X6S,D9A!C2M21!//jf4cfls225.pdx.intel.com/apd_proj/ppg_lib/epg_masterlib/logical/mstr_discrete/cap/chips/chips.prt!CAP!CAP_0402-1.0UF,6.3V,10%,X6S,D97712-004!CAP_0402!!!F3709!!SB_DECOUPLING!!
S!@baseboard_fab2_lib.baseboard_fab2(sch_1):page130_i7@mstr_discrete.cap(chips)!CAP_0402-1.0UF,6.3V,10%,X6S,D9A!C2N19!//jf4cfls225.pdx.intel.com/apd_proj/ppg_lib/epg_masterlib/logical/mstr_discrete/cap/chips/chips.prt!CAP!CAP_0402-1.0UF,6.3V,10%,X6S,D97712-004!CAP_0402!!!F3693!!SB_DECOUPLING!!
S!@baseboard_fab2_lib.baseboard_fab2(sch_1):page131_i47@mstr_discrete.cap(chips)!CAP_0402-1.0UF,6.3V,10%,X6S,D9A!C2N8!//jf4cfls225.pdx.intel.com/apd_proj/ppg_lib/epg_masterlib/logical/mstr_discrete/cap/chips/chips.prt!CAP!CAP_0402-1.0UF,6.3V,10%,X6S,D97712-004!CAP_0402!!!F3701!!SB_DECOUPLING!!
S!@baseboard_fab2_lib.baseboard_fab2(sch_1):page131_i43@mstr_discrete.cap(chips)!CAP_0402-1.0UF,6.3V,10%,X6S,D9A!C2N7!//jf4cfls225.pdx.intel.com/apd_proj/ppg_lib/epg_masterlib/logical/mstr_discrete/cap/chips/chips.prt!CAP!CAP_0402-1.0UF,6.3V,10%,X6S,D97712-004!CAP_0402!!!F3702!!SB_DECOUPLING!!
S!@baseboard_fab2_lib.baseboard_fab2(sch_1):page131_i42@mstr_discrete.cap(chips)!CAP_0402-1.0UF,6.3V,10%,X6S,D9A!C3M43!//jf4cfls225.pdx.intel.com/apd_proj/ppg_lib/epg_masterlib/logical/mstr_discrete/cap/chips/chips.prt!CAP!CAP_0402-1.0UF,6.3V,10%,X6S,D97712-004!CAP_0402!!!F3667!!SB_DECOUPLING!!
S!@baseboard_fab2_lib.baseboard_fab2(sch_1):page131_i32@mstr_discrete.cap(chips)!CAP_0402-1.0UF,6.3V,10%,X6S,D9A!C3M38!//jf4cfls225.pdx.intel.com/apd_proj/ppg_lib/epg_masterlib/logical/mstr_discrete/cap/chips/chips.prt!CAP!CAP_0402-1.0UF,6.3V,10%,X6S,D97712-004!CAP_0402!!!F3670!!SB_DECOUPLING!!
S!@baseboard_fab2_lib.baseboard_fab2(sch_1):page131_i31@mstr_discrete.cap(chips)!CAP_0402-1.0UF,6.3V,10%,X6S,D9A!C2M19!//jf4cfls225.pdx.intel.com/apd_proj/ppg_lib/epg_masterlib/logical/mstr_discrete/cap/chips/chips.prt!CAP!CAP_0402-1.0UF,6.3V,10%,X6S,D97712-004!CAP_0402!!!F3711!!SB_DECOUPLING!!
S!@baseboard_fab2_lib.baseboard_fab2(sch_1):page131_i27@mstr_discrete.cap(chips)!CAP_0402-1.0UF,6.3V,10%,X6S,D9A!C2M22!//jf4cfls225.pdx.intel.com/apd_proj/ppg_lib/epg_masterlib/logical/mstr_discrete/cap/chips/chips.prt!CAP!CAP_0402-1.0UF,6.3V,10%,X6S,D97712-004!CAP_0402!!!F3708!!SB_DECOUPLING!!
S!@baseboard_fab2_lib.baseboard_fab2(sch_1):page130_i53@mstr_discrete.cap(chips)!CAP_0402-1.0UF,6.3V,10%,X6S,D9A!C3N22!//jf4cfls225.pdx.intel.com/apd_proj/ppg_lib/epg_masterlib/logical/mstr_discrete/cap/chips/chips.prt!CAP!CAP_0402-1.0UF,6.3V,10%,X6S,D97712-004!CAP_0402!!!F3652!!SB_DECOUPLING!!
S!@baseboard_fab2_lib.baseboard_fab2(sch_1):page130_i42@mstr_discrete.cap(chips)!CAP_0402-1.0UF,6.3V,10%,X6S,D9A!C3N23!//jf4cfls225.pdx.intel.com/apd_proj/ppg_lib/epg_masterlib/logical/mstr_discrete/cap/chips/chips.prt!CAP!CAP_0402-1.0UF,6.3V,10%,X6S,D97712-004!CAP_0402!!!F3651!!SB_DECOUPLING!!
S!@baseboard_fab2_lib.baseboard_fab2(sch_1):page130_i52@mstr_discrete.cap(chips)!CAP_0402-1.0UF,6.3V,10%,X6S,D9A!C2N16!//jf4cfls225.pdx.intel.com/apd_proj/ppg_lib/epg_masterlib/logical/mstr_discrete/cap/chips/chips.prt!CAP!CAP_0402-1.0UF,6.3V,10%,X6S,D97712-004!CAP_0402!!!F3695!!SB_DECOUPLING!!
S!@baseboard_fab2_lib.baseboard_fab2(sch_1):page130_i4@mstr_discrete.cap(chips)!CAP_0402-1.0UF,6.3V,10%,X6S,D9A!C2N26!//jf4cfls225.pdx.intel.com/apd_proj/ppg_lib/epg_masterlib/logical/mstr_discrete/cap/chips/chips.prt!CAP!CAP_0402-1.0UF,6.3V,10%,X6S,D97712-004!CAP_0402!!!F3690!!SB_DECOUPLING!!
S!@baseboard_fab2_lib.baseboard_fab2(sch_1):page130_i50@mstr_discrete.cap(chips)!CAP_0402-1.0UF,6.3V,10%,X6S,D9A!C3N25!//jf4cfls225.pdx.intel.com/apd_proj/ppg_lib/epg_masterlib/logical/mstr_discrete/cap/chips/chips.prt!CAP!CAP_0402-1.0UF,6.3V,10%,X6S,D97712-004!CAP_0402!!!F3650!!SB_DECOUPLING!!
S!@baseboard_fab2_lib.baseboard_fab2(sch_1):page149_i141@mstr_discrete.cap(chips)!CAP_0402-1.0UF,6.3V,10%,X6S,D9A!C1U18!//jf4cfls225.pdx.intel.com/apd_proj/ppg_lib/epg_masterlib/logical/mstr_discrete/cap/chips/chips.prt!CAP!CAP_0402-1.0UF,6.3V,10%,X6S,D97712-004!CAP_0402!!!F3719!!BMC!!
S!@baseboard_fab2_lib.baseboard_fab2(sch_1):page209_i21@mstr_discrete.cap(chips)!CAP_0402-1.0UF,6.3V,10%,X6S,D9A!C1C18!//jf4cfls225.pdx.intel.com/apd_proj/ppg_lib/epg_masterlib/logical/mstr_discrete/cap/chips/chips.prt!CAP!CAP_0402-1.0UF,6.3V,10%,X6S,D97712-004!CAP_0402!!!F3748!!PVCCIN_CPU1_PWR_VR!!
S!@baseboard_fab2_lib.baseboard_fab2(sch_1):page93_i72@mstr_discrete.cap(chips)!CAP_0402-1.0UF,6.3V,10%,X6S,D9A!C2T33!//jf4cfls225.pdx.intel.com/apd_proj/ppg_lib/epg_masterlib/logical/mstr_discrete/cap/chips/chips.prt!CAP!CAP_0402-1.0UF,6.3V,10%,X6S,D97712-004!CAP_0402!!!F3684!!PROC_SIDEBAND!!
S!@baseboard_fab2_lib.baseboard_fab2(sch_1):page101_i116@mstr_discrete.cap(chips)!CAP_0402-1.0UF,6.3V,10%,X6S,D9A!C2T28!//jf4cfls225.pdx.intel.com/apd_proj/ppg_lib/epg_masterlib/logical/mstr_discrete/cap/chips/chips.prt!CAP!CAP_0402-1.0UF,6.3V,10%,X6S,D97712-004!CAP_0402!!!F3686!!SYS_CLOCK!!
S!@baseboard_fab2_lib.baseboard_fab2(sch_1):page101_i106@mstr_discrete.cap(chips)!CAP_0402-1.0UF,6.3V,10%,X6S,D9A!C2T19!//jf4cfls225.pdx.intel.com/apd_proj/ppg_lib/epg_masterlib/logical/mstr_discrete/cap/chips/chips.prt!CAP!CAP_0402-1.0UF,6.3V,10%,X6S,D97712-004!CAP_0402!!!F3687!!SYS_CLOCK!!
S!@baseboard_fab2_lib.baseboard_fab2(sch_1):page101_i97@mstr_discrete.cap(chips)!CAP_0402-1.0UF,6.3V,10%,X6S,D9A!C2T38!//jf4cfls225.pdx.intel.com/apd_proj/ppg_lib/epg_masterlib/logical/mstr_discrete/cap/chips/chips.prt!CAP!CAP_0402-1.0UF,6.3V,10%,X6S,D97712-004!CAP_0402!!!F3683!!SYS_CLOCK!!
S!@baseboard_fab2_lib.baseboard_fab2(sch_1):page101_i89@mstr_discrete.cap(chips)!CAP_0402-1.0UF,6.3V,10%,X6S,D9A!C2T31!//jf4cfls225.pdx.intel.com/apd_proj/ppg_lib/epg_masterlib/logical/mstr_discrete/cap/chips/chips.prt!CAP!CAP_0402-1.0UF,6.3V,10%,X6S,D97712-004!CAP_0402!!!F3685!!SYS_CLOCK!!
S!@baseboard_fab2_lib.baseboard_fab2(sch_1):page127_i9@mstr_discrete.cap(chips)!CAP_0402-1.0UF,6.3V,10%,X6S,D9A!C3M21!//jf4cfls225.pdx.intel.com/apd_proj/ppg_lib/epg_masterlib/logical/mstr_discrete/cap/chips/chips.prt!CAP!CAP_0402-1.0UF,6.3V,10%,X6S,D97712-004!CAP_0402!!!F3676!!SB_FILTER_PLL0!!
S!@baseboard_fab2_lib.baseboard_fab2(sch_1):page127_i18@mstr_discrete.cap(chips)!CAP_0402-1.0UF,6.3V,10%,X6S,D9A!C3M22!//jf4cfls225.pdx.intel.com/apd_proj/ppg_lib/epg_masterlib/logical/mstr_discrete/cap/chips/chips.prt!CAP!CAP_0402-1.0UF,6.3V,10%,X6S,D97712-004!CAP_0402!!!F3675!!SB_FILTER_PLL1!!
S!@baseboard_fab2_lib.baseboard_fab2(sch_1):page127_i27@mstr_discrete.cap(chips)!CAP_0402-1.0UF,6.3V,10%,X6S,D9A!C3M30!//jf4cfls225.pdx.intel.com/apd_proj/ppg_lib/epg_masterlib/logical/mstr_discrete/cap/chips/chips.prt!CAP!CAP_0402-1.0UF,6.3V,10%,X6S,D97712-004!CAP_0402!!!F3672!!SB_FILTER_XTAL!!
S!@baseboard_fab2_lib.baseboard_fab2(sch_1):page96_i73@mstr_discrete.cap(chips)!CAP_0402-1.0UF,6.3V,10%,X6S,D9A!C3P42!//jf4cfls225.pdx.intel.com/apd_proj/ppg_lib/epg_masterlib/logical/mstr_discrete/cap/chips/chips.prt!CAP!CAP_0402-1.0UF,6.3V,10%,X6S,D97712-004!CAP_0402!!!F3643!!PROC_RSTS_PGOODS!!
S!@baseboard_fab2_lib.baseboard_fab2(sch_1):page96_i75@mstr_discrete.cap(chips)!CAP_0402-1.0UF,6.3V,10%,X6S,D9A!C4C3!//jf4cfls225.pdx.intel.com/apd_proj/ppg_lib/epg_masterlib/logical/mstr_discrete/cap/chips/chips.prt!CAP!CAP_0402-1.0UF,6.3V,10%,X6S,D97712-004!CAP_0402!!!F3641!!PROC_RSTS_PGOODS!!
S!@baseboard_fab2_lib.baseboard_fab2(sch_1):page149_i77@mstr_discrete.cap(chips)!CAP_0402-1.0UF,6.3V,10%,X6S,D9A!C1T28!//jf4cfls225.pdx.intel.com/apd_proj/ppg_lib/epg_masterlib/logical/mstr_discrete/cap/chips/chips.prt!CAP!CAP_0402-1.0UF,6.3V,10%,X6S,D97712-004!CAP_0402!!!F3730!!BMC!!
S!@baseboard_fab2_lib.baseboard_fab2(sch_1):page149_i89@mstr_discrete.cap(chips)!CAP_0402-1.0UF,6.3V,10%,X6S,D9A!C1T32!//jf4cfls225.pdx.intel.com/apd_proj/ppg_lib/epg_masterlib/logical/mstr_discrete/cap/chips/chips.prt!CAP!CAP_0402-1.0UF,6.3V,10%,X6S,D97712-004!CAP_0402!!!F3728!!BMC!!
S!@baseboard_fab2_lib.baseboard_fab2(sch_1):page149_i78@mstr_discrete.cap(chips)!CAP_0402-1.0UF,6.3V,10%,X6S,D9A!C1U6!//jf4cfls225.pdx.intel.com/apd_proj/ppg_lib/epg_masterlib/logical/mstr_discrete/cap/chips/chips.prt!CAP!CAP_0402-1.0UF,6.3V,10%,X6S,D97712-004!CAP_0402!!!F3722!!BMC!!
S!@baseboard_fab2_lib.baseboard_fab2(sch_1):page149_i90@mstr_discrete.cap(chips)!CAP_0402-1.0UF,6.3V,10%,X6S,D9A!C1T55!//jf4cfls225.pdx.intel.com/apd_proj/ppg_lib/epg_masterlib/logical/mstr_discrete/cap/chips/chips.prt!CAP!CAP_0402-1.0UF,6.3V,10%,X6S,D97712-004!CAP_0402!!!F3723!!BMC!!
S!@baseboard_fab2_lib.baseboard_fab2(sch_1):page149_i79@mstr_discrete.cap(chips)!CAP_0402-1.0UF,6.3V,10%,X6S,D9A!C1U7!//jf4cfls225.pdx.intel.com/apd_proj/ppg_lib/epg_masterlib/logical/mstr_discrete/cap/chips/chips.prt!CAP!CAP_0402-1.0UF,6.3V,10%,X6S,D97712-004!CAP_0402!!!F3721!!BMC!!
S!@baseboard_fab2_lib.baseboard_fab2(sch_1):page149_i91@mstr_discrete.cap(chips)!CAP_0402-1.0UF,6.3V,10%,X6S,D9A!C1T46!//jf4cfls225.pdx.intel.com/apd_proj/ppg_lib/epg_masterlib/logical/mstr_discrete/cap/chips/chips.prt!CAP!CAP_0402-1.0UF,6.3V,10%,X6S,D97712-004!CAP_0402!!!F3726!!BMC!!
S!@baseboard_fab2_lib.baseboard_fab2(sch_1):page149_i92@mstr_discrete.cap(chips)!CAP_0402-1.0UF,6.3V,10%,X6S,D9A!C1T31!//jf4cfls225.pdx.intel.com/apd_proj/ppg_lib/epg_masterlib/logical/mstr_discrete/cap/chips/chips.prt!CAP!CAP_0402-1.0UF,6.3V,10%,X6S,D97712-004!CAP_0402!!!F3729!!BMC!!
S!@baseboard_fab2_lib.baseboard_fab2(sch_1):page149_i93@mstr_discrete.cap(chips)!CAP_0402-1.0UF,6.3V,10%,X6S,D9A!C1T35!//jf4cfls225.pdx.intel.com/apd_proj/ppg_lib/epg_masterlib/logical/mstr_discrete/cap/chips/chips.prt!CAP!CAP_0402-1.0UF,6.3V,10%,X6S,D97712-004!CAP_0402!!!F3727!!BMC!!
S!@baseboard_fab2_lib.baseboard_fab2(sch_1):page149_i94@mstr_discrete.cap(chips)!CAP_0402-1.0UF,6.3V,10%,X6S,D9A!C1T49!//jf4cfls225.pdx.intel.com/apd_proj/ppg_lib/epg_masterlib/logical/mstr_discrete/cap/chips/chips.prt!CAP!CAP_0402-1.0UF,6.3V,10%,X6S,D97712-004!CAP_0402!!!F3725!!BMC!!
S!@baseboard_fab2_lib.baseboard_fab2(sch_1):page149_i106@mstr_discrete.cap(chips)!CAP_0402-1.0UF,6.3V,10%,X6S,D9A!C9F12!//jf4cfls225.pdx.intel.com/apd_proj/ppg_lib/epg_masterlib/logical/mstr_discrete/cap/chips/chips.prt!CAP!CAP_0402-1.0UF,6.3V,10%,X6S,D97712-004!CAP_0402!!!F3608!!BMC!!
S!@baseboard_fab2_lib.baseboard_fab2(sch_1):page149_i121@mstr_discrete.cap(chips)!CAP_0402-1.0UF,6.3V,10%,X6S,D9A!C1T19!//jf4cfls225.pdx.intel.com/apd_proj/ppg_lib/epg_masterlib/logical/mstr_discrete/cap/chips/chips.prt!CAP!CAP_0402-1.0UF,6.3V,10%,X6S,D97712-004!CAP_0402!!!F3732!!BMC!!
S!@baseboard_fab2_lib.baseboard_fab2(sch_1):page148_i28@mstr_discrete.cap(chips)!CAP_0402-1.0UF,6.3V,10%,X6S,D9A!C1T21!//jf4cfls225.pdx.intel.com/apd_proj/ppg_lib/epg_masterlib/logical/mstr_discrete/cap/chips/chips.prt!CAP!CAP_0402-1.0UF,6.3V,10%,X6S,D97712-004!CAP_0402!!!F3731!!BMC!!
S!@baseboard_fab2_lib.baseboard_fab2(sch_1):page112_i47@mstr_discrete.cap(chips)!CAP_0402-1.0UF,6.3V,10%,X6S,D9A!C1M37!//jf4cfls225.pdx.intel.com/apd_proj/ppg_lib/epg_masterlib/logical/mstr_discrete/cap/chips/chips.prt!CAP!CAP_0402-1.0UF,6.3V,10%,X6S,D97712-004!CAP_0402!!!F3609!!DEBUG!!
S!@baseboard_fab2_lib.baseboard_fab2(sch_1):page127_i57@mstr_discrete.cap(chips)!CAP_0402-1.0UF,6.3V,10%,X6S,D9A!C3M31!//jf4cfls225.pdx.intel.com/apd_proj/ppg_lib/epg_masterlib/logical/mstr_discrete/cap/chips/chips.prt!CAP!CAP_0402-1.0UF,6.3V,10%,X6S,D97712-004!CAP_0402!!!F3671!!SB_FILTER_ISCLK!!
S!@baseboard_fab2_lib.baseboard_fab2(sch_1):page127_i65@mstr_discrete.cap(chips)!CAP_0402-1.0UF,6.3V,10%,X6S,D9A!C2N5!//jf4cfls225.pdx.intel.com/apd_proj/ppg_lib/epg_masterlib/logical/mstr_discrete/cap/chips/chips.prt!CAP!CAP_0402-1.0UF,6.3V,10%,X6S,D97712-004!CAP_0402!!!F3703!!SB_FILTER_KR_PLL!!
S!@baseboard_fab2_lib.baseboard_fab2(sch_1):page127_i44@mstr_discrete.cap(chips)!CAP_0402-1.0UF,6.3V,10%,X6S,D9A!C2M7!//jf4cfls225.pdx.intel.com/apd_proj/ppg_lib/epg_masterlib/logical/mstr_discrete/cap/chips/chips.prt!CAP!CAP_0402-1.0UF,6.3V,10%,X6S,D97712-004!CAP_0402!!!F3716!!SB_FILTER_VM20!!
S!@baseboard_fab2_lib.baseboard_fab2(sch_1):page127_i50@mstr_discrete.cap(chips)!CAP_0402-1.0UF,6.3V,10%,X6S,D9A!C2M9!//jf4cfls225.pdx.intel.com/apd_proj/ppg_lib/epg_masterlib/logical/mstr_discrete/cap/chips/chips.prt!CAP!CAP_0402-1.0UF,6.3V,10%,X6S,D97712-004!CAP_0402!!!F3714!!SB_FILTER_VM26!!
S!@baseboard_fab2_lib.baseboard_fab2(sch_1):page202_i25@mstr_discrete.cap(chips)!CAP_0402-1.0UF,6.3V,10%,X6S,D9A!C4E25!//jf4cfls225.pdx.intel.com/apd_proj/ppg_lib/epg_masterlib/logical/mstr_discrete/cap/chips/chips.prt!CAP!CAP_0402-1.0UF,6.3V,10%,X6S,D97712-004!CAP_0402!!!F3630!!PVCCIN_CPU0_PWR_VR!!
S!@baseboard_fab2_lib.baseboard_fab2(sch_1):page202_i19@mstr_discrete.cap(chips)!CAP_0402-1.0UF,6.3V,10%,X6S,D9A!C4E6!//jf4cfls225.pdx.intel.com/apd_proj/ppg_lib/epg_masterlib/logical/mstr_discrete/cap/chips/chips.prt!CAP!CAP_0402-1.0UF,6.3V,10%,X6S,D97712-004!CAP_0402!!!F3629!!PVCCIN_CPU0_PWR_VR!!
S!@baseboard_fab2_lib.baseboard_fab2(sch_1):page204_i19@mstr_discrete.cap(chips)!CAP_0402-1.0UF,6.3V,10%,X6S,D9A!C4C14!//jf4cfls225.pdx.intel.com/apd_proj/ppg_lib/epg_masterlib/logical/mstr_discrete/cap/chips/chips.prt!CAP!CAP_0402-1.0UF,6.3V,10%,X6S,D97712-004!CAP_0402!!!F3639!!PVCCIN_CPU0_PWR_VR!!
S!@baseboard_fab2_lib.baseboard_fab2(sch_1):page111_i30@mstr_discrete.cap(chips)!CAP_0402-1.0UF,6.3V,10%,X6S,D9A!C1L5!//jf4cfls225.pdx.intel.com/apd_proj/ppg_lib/epg_masterlib/logical/mstr_discrete/cap/chips/chips.prt!CAP!CAP_0402-1.0UF,6.3V,10%,X6S,D97712-004!CAP_0402!!!F3739!!DEBUG!!
S!@baseboard_fab2_lib.baseboard_fab2(sch_1):page111_i25@mstr_discrete.cap(chips)!CAP_0402-1.0UF,6.3V,10%,X6S,D9A!C9A6!//jf4cfls225.pdx.intel.com/apd_proj/ppg_lib/epg_masterlib/logical/mstr_discrete/cap/chips/chips.prt!CAP!CAP_0402-1.0UF,6.3V,10%,X6S,D97712-004!CAP_0402!!!F3610!!DEBUG!!
S!@baseboard_fab2_lib.baseboard_fab2(sch_1):page131_i45@mstr_discrete.cap(chips)!CAP_0402-1.0UF,6.3V,10%,X6S,D9A!C3M42!//jf4cfls225.pdx.intel.com/apd_proj/ppg_lib/epg_masterlib/logical/mstr_discrete/cap/chips/chips.prt!CAP!CAP_0402-1.0UF,6.3V,10%,X6S,D97712-004!CAP_0402!!!F3668!!SB_DECOUPLING!!
S!@baseboard_fab2_lib.baseboard_fab2(sch_1):page131_i44@mstr_discrete.cap(chips)!CAP_0402-1.0UF,6.3V,10%,X6S,D9A!C3M39!//jf4cfls225.pdx.intel.com/apd_proj/ppg_lib/epg_masterlib/logical/mstr_discrete/cap/chips/chips.prt!CAP!CAP_0402-1.0UF,6.3V,10%,X6S,D97712-004!CAP_0402!!!F3669!!SB_DECOUPLING!!
S!@baseboard_fab2_lib.baseboard_fab2(sch_1):page137_i20@mstr_discrete.cap(chips)!CAP_0402-1.0UF,6.3V,10%,X6S,D9A!C3N32!//jf4cfls225.pdx.intel.com/apd_proj/ppg_lib/epg_masterlib/logical/mstr_discrete/cap/chips/chips.prt!CAP!CAP_0402-1.0UF,6.3V,10%,X6S,D97712-004!CAP_0402!!!F3649!!SB!!
S!@baseboard_fab2_lib.baseboard_fab2(sch_1):page137_i14@mstr_discrete.cap(chips)!CAP_0402-1.0UF,6.3V,10%,X6S,D9A!C7C19!//jf4cfls225.pdx.intel.com/apd_proj/ppg_lib/epg_masterlib/logical/mstr_discrete/cap/chips/chips.prt!CAP!CAP_0402-1.0UF,6.3V,10%,X6S,D97712-004!CAP_0402!!!F3619!!SB!!
S!@baseboard_fab2_lib.baseboard_fab2(sch_1):page149_i8@mstr_discrete.cap(chips)!CAP_0402-1.0UF,6.3V,10%,X6S,D9A!C1T12!//jf4cfls225.pdx.intel.com/apd_proj/ppg_lib/epg_masterlib/logical/mstr_discrete/cap/chips/chips.prt!CAP!CAP_0402-1.0UF,6.3V,10%,X6S,D97712-004!CAP_0402!!!F3733!!BMC!!
S!@baseboard_fab2_lib.baseboard_fab2(sch_1):page149_i19@mstr_discrete.cap(chips)!CAP_0402-1.0UF,6.3V,10%,X6S,D9A!C1U8!//jf4cfls225.pdx.intel.com/apd_proj/ppg_lib/epg_masterlib/logical/mstr_discrete/cap/chips/chips.prt!CAP!CAP_0402-1.0UF,6.3V,10%,X6S,D97712-004!CAP_0402!!!F3720!!BMC!!
S!@baseboard_fab2_lib.baseboard_fab2(sch_1):page216_i53@mstr_discrete.cap(chips)!CAP_0402-1.0UF,6.3V,10%,X6S,D9A!C7G35!//jf4cfls225.pdx.intel.com/apd_proj/ppg_lib/epg_masterlib/logical/mstr_discrete/cap/chips/chips.prt!CAP!CAP_0402-1.0UF,6.3V,10%,X6S,D97712-004!CAP_0402!!!F3615!!VDDQ_ABC_PWR_VR!!
S!@baseboard_fab2_lib.baseboard_fab2(sch_1):page216_i73@mstr_discrete.cap(chips)!CAP_0402-1.0UF,6.3V,10%,X6S,D9A!C7G42!//jf4cfls225.pdx.intel.com/apd_proj/ppg_lib/epg_masterlib/logical/mstr_discrete/cap/chips/chips.prt!CAP!CAP_0402-1.0UF,6.3V,10%,X6S,D97712-004!CAP_0402!!!F3614!!VDDQ_ABC_PWR_VR!!
S!@baseboard_fab2_lib.baseboard_fab2(sch_1):page219_i53@mstr_discrete.cap(chips)!CAP_0402-1.0UF,6.3V,10%,X6S,D9A!C7A18!//jf4cfls225.pdx.intel.com/apd_proj/ppg_lib/epg_masterlib/logical/mstr_discrete/cap/chips/chips.prt!CAP!CAP_0402-1.0UF,6.3V,10%,X6S,D97712-004!CAP_0402!!!F3623!!VDDQ_DEF_PWR_VR!!
S!@baseboard_fab2_lib.baseboard_fab2(sch_1):page219_i73@mstr_discrete.cap(chips)!CAP_0402-1.0UF,6.3V,10%,X6S,D9A!C7A26!//jf4cfls225.pdx.intel.com/apd_proj/ppg_lib/epg_masterlib/logical/mstr_discrete/cap/chips/chips.prt!CAP!CAP_0402-1.0UF,6.3V,10%,X6S,D97712-004!CAP_0402!!!F3622!!VDDQ_DEF_PWR_VR!!
S!@baseboard_fab2_lib.baseboard_fab2(sch_1):page227_i53@mstr_discrete.cap(chips)!CAP_0402-1.0UF,6.3V,10%,X6S,D9A!C1A2!//jf4cfls225.pdx.intel.com/apd_proj/ppg_lib/epg_masterlib/logical/mstr_discrete/cap/chips/chips.prt!CAP!CAP_0402-1.0UF,6.3V,10%,X6S,D97712-004!CAP_0402!!!F3755!!VDDQ_KLM_PWR_VR!!
S!@baseboard_fab2_lib.baseboard_fab2(sch_1):page227_i73@mstr_discrete.cap(chips)!CAP_0402-1.0UF,6.3V,10%,X6S,D9A!C1A11!//jf4cfls225.pdx.intel.com/apd_proj/ppg_lib/epg_masterlib/logical/mstr_discrete/cap/chips/chips.prt!CAP!CAP_0402-1.0UF,6.3V,10%,X6S,D97712-004!CAP_0402!!!F3754!!VDDQ_KLM_PWR_VR!!
S!@baseboard_fab2_lib.baseboard_fab2(sch_1):page224_i53@mstr_discrete.cap(chips)!CAP_0402-1.0UF,6.3V,10%,X6S,D9A!C1G4!//jf4cfls225.pdx.intel.com/apd_proj/ppg_lib/epg_masterlib/logical/mstr_discrete/cap/chips/chips.prt!CAP!CAP_0402-1.0UF,6.3V,10%,X6S,D97712-004!CAP_0402!!!F3742!!VDDQ_GHJ_PWR_VR!!
S!@baseboard_fab2_lib.baseboard_fab2(sch_1):page224_i73@mstr_discrete.cap(chips)!CAP_0402-1.0UF,6.3V,10%,X6S,D9A!C1F21!//jf4cfls225.pdx.intel.com/apd_proj/ppg_lib/epg_masterlib/logical/mstr_discrete/cap/chips/chips.prt!CAP!CAP_0402-1.0UF,6.3V,10%,X6S,D97712-004!CAP_0402!!!F3743!!VDDQ_GHJ_PWR_VR!!
S!@baseboard_fab2_lib.baseboard_fab2(sch_1):page207_i37@mstr_discrete.cap(chips)!CAP_0402-1.0UF,6.3V,10%,X6S,D9A!C1E23!//jf4cfls225.pdx.intel.com/apd_proj/ppg_lib/epg_masterlib/logical/mstr_discrete/cap/chips/chips.prt!CAP!CAP_0402-1.0UF,6.3V,10%,X6S,D97712-004!CAP_0402!!!F3745!!PVCCIN_CPU1_PWR_VR!!
S!@baseboard_fab2_lib.baseboard_fab2(sch_1):page207_i29@mstr_discrete.cap(chips)!CAP_0402-1.0UF,6.3V,10%,X6S,D9A!C1E6!//jf4cfls225.pdx.intel.com/apd_proj/ppg_lib/epg_masterlib/logical/mstr_discrete/cap/chips/chips.prt!CAP!CAP_0402-1.0UF,6.3V,10%,X6S,D97712-004!CAP_0402!!!F3744!!PVCCIN_CPU1_PWR_VR!!
S!@baseboard_fab2_lib.baseboard_fab2(sch_1):page208_i39@mstr_discrete.cap(chips)!CAP_0402-1.0UF,6.3V,10%,X6S,D9A!C1D15!//jf4cfls225.pdx.intel.com/apd_proj/ppg_lib/epg_masterlib/logical/mstr_discrete/cap/chips/chips.prt!CAP!CAP_0402-1.0UF,6.3V,10%,X6S,D97712-004!CAP_0402!!!F3746!!PVCCIN_CPU1_PWR_VR!!
S!@baseboard_fab2_lib.baseboard_fab2(sch_1):page208_i47@mstr_discrete.cap(chips)!CAP_0402-1.0UF,6.3V,10%,X6S,D9A!C1D5!//jf4cfls225.pdx.intel.com/apd_proj/ppg_lib/epg_masterlib/logical/mstr_discrete/cap/chips/chips.prt!CAP!CAP_0402-1.0UF,6.3V,10%,X6S,D97712-004!CAP_0402!!!F3747!!PVCCIN_CPU1_PWR_VR!!
S!@baseboard_fab2_lib.baseboard_fab2(sch_1):page210_i23@mstr_discrete.cap(chips)!CAP_0402-1.0UF,6.3V,10%,X6S,D9A!C1C3!//jf4cfls225.pdx.intel.com/apd_proj/ppg_lib/epg_masterlib/logical/mstr_discrete/cap/chips/chips.prt!CAP!CAP_0402-1.0UF,6.3V,10%,X6S,D97712-004!CAP_0402!!!F3751!!PVSA_CPU1_PWR_VR!!
S!@baseboard_fab2_lib.baseboard_fab2(sch_1):page113_i267@mstr_discrete.cap(chips)!CAP_0402LF-0.01UF,25V,10%,X7R,A!C1L20!//jf4cfls225.pdx.intel.com/apd_proj/ppg_lib/epg_masterlib/logical/mstr_discrete/cap/chips/chips.prt!CAP!CAP_0402LF-0.01UF,25V,10%,X7R,A36096-045!CAP!!!F3492!!DEBUG!!
S!@baseboard_fab2_lib.baseboard_fab2(sch_1):page113_i266@mstr_discrete.cap(chips)!CAP_0402LF-0.01UF,25V,10%,X7R,A!C1M35!//jf4cfls225.pdx.intel.com/apd_proj/ppg_lib/epg_masterlib/logical/mstr_discrete/cap/chips/chips.prt!CAP!CAP_0402LF-0.01UF,25V,10%,X7R,A36096-045!CAP!!!F3494!!DEBUG!!
S!@baseboard_fab2_lib.baseboard_fab2(sch_1):page113_i265@mstr_discrete.cap(chips)!CAP_0402LF-0.01UF,25V,10%,X7R,A!C1M34!//jf4cfls225.pdx.intel.com/apd_proj/ppg_lib/epg_masterlib/logical/mstr_discrete/cap/chips/chips.prt!CAP!CAP_0402LF-0.01UF,25V,10%,X7R,A36096-045!CAP!!!F3493!!DEBUG!!
S!@baseboard_fab2_lib.baseboard_fab2(sch_1):page161_i137@mstr_discrete.cap(chips)!CAP_0402LF-0.01UF,25V,10%,X7R,A!C9T1!//jf4cfls225.pdx.intel.com/apd_proj/ppg_lib/epg_masterlib/logical/mstr_discrete/cap/chips/chips.prt!CAP!CAP_0402LF-0.01UF,25V,10%,X7R,A36096-045!CAP!!!F3498!!CPU_FANS!!
S!@baseboard_fab2_lib.baseboard_fab2(sch_1):page161_i128@mstr_discrete.cap(chips)!CAP_0402LF-0.01UF,25V,10%,X7R,A!C1B17!//jf4cfls225.pdx.intel.com/apd_proj/ppg_lib/epg_masterlib/logical/mstr_discrete/cap/chips/chips.prt!CAP!CAP_0402LF-0.01UF,25V,10%,X7R,A36096-045!CAP!!!F3599!!CPU_FANS!!
S!@baseboard_fab2_lib.baseboard_fab2(sch_1):page113_i116@mstr_discrete.cap(chips)!CAP_0402LF-0.01UF,25V,10%,X7R,A!C1M31!//jf4cfls225.pdx.intel.com/apd_proj/ppg_lib/epg_masterlib/logical/mstr_discrete/cap/chips/chips.prt!CAP!CAP_0402LF-0.01UF,25V,10%,X7R,A36096-045!CAP!!!F3533!!DEBUG!!
S!@baseboard_fab2_lib.baseboard_fab2(sch_1):page113_i119@mstr_discrete.cap(chips)!CAP_0402LF-0.01UF,25V,10%,X7R,A!C1M28!//jf4cfls225.pdx.intel.com/apd_proj/ppg_lib/epg_masterlib/logical/mstr_discrete/cap/chips/chips.prt!CAP!CAP_0402LF-0.01UF,25V,10%,X7R,A36096-045!CAP!!!F3532!!DEBUG!!
S!@baseboard_fab2_lib.baseboard_fab2(sch_1):page112_i131@mstr_discrete.cap(chips)!CAP_0402LF-0.01UF,25V,10%,X7R,A!C1M30!//jf4cfls225.pdx.intel.com/apd_proj/ppg_lib/epg_masterlib/logical/mstr_discrete/cap/chips/chips.prt!CAP!CAP_0402LF-0.01UF,25V,10%,X7R,A36096-045!CAP!!!F3506!!DEBUG!!
S!@baseboard_fab2_lib.baseboard_fab2(sch_1):page174_i29@mstr_discrete.cap(chips)!CAP_0402LF-0.01UF,25V,10%,X7R,A!C2L31!//jf4cfls225.pdx.intel.com/apd_proj/ppg_lib/epg_masterlib/logical/mstr_discrete/cap/chips/chips.prt!CAP!CAP_0402LF-0.01UF,25V,10%,X7R,A36096-045!CAP!!!F3552!!ST_SATA!!
S!@baseboard_fab2_lib.baseboard_fab2(sch_1):page174_i32@mstr_discrete.cap(chips)!CAP_0402LF-0.01UF,25V,10%,X7R,A!C2L29!//jf4cfls225.pdx.intel.com/apd_proj/ppg_lib/epg_masterlib/logical/mstr_discrete/cap/chips/chips.prt!CAP!CAP_0402LF-0.01UF,25V,10%,X7R,A36096-045!CAP!!!F3554!!ST_SATA!!
S!@baseboard_fab2_lib.baseboard_fab2(sch_1):page174_i39@mstr_discrete.cap(chips)!CAP_0402LF-0.01UF,25V,10%,X7R,A!C2L36!//jf4cfls225.pdx.intel.com/apd_proj/ppg_lib/epg_masterlib/logical/mstr_discrete/cap/chips/chips.prt!CAP!CAP_0402LF-0.01UF,25V,10%,X7R,A36096-045!CAP!!!F3548!!ST_SATA!!
S!@baseboard_fab2_lib.baseboard_fab2(sch_1):page174_i41@mstr_discrete.cap(chips)!CAP_0402LF-0.01UF,25V,10%,X7R,A!C2L34!//jf4cfls225.pdx.intel.com/apd_proj/ppg_lib/epg_masterlib/logical/mstr_discrete/cap/chips/chips.prt!CAP!CAP_0402LF-0.01UF,25V,10%,X7R,A36096-045!CAP!!!F3550!!ST_SATA!!
S!@baseboard_fab2_lib.baseboard_fab2(sch_1):page174_i28@mstr_discrete.cap(chips)!CAP_0402LF-0.01UF,25V,10%,X7R,A!C2L30!//jf4cfls225.pdx.intel.com/apd_proj/ppg_lib/epg_masterlib/logical/mstr_discrete/cap/chips/chips.prt!CAP!CAP_0402LF-0.01UF,25V,10%,X7R,A36096-045!CAP!!!F3553!!ST_SATA!!
S!@baseboard_fab2_lib.baseboard_fab2(sch_1):page174_i30@mstr_discrete.cap(chips)!CAP_0402LF-0.01UF,25V,10%,X7R,A!C2L28!//jf4cfls225.pdx.intel.com/apd_proj/ppg_lib/epg_masterlib/logical/mstr_discrete/cap/chips/chips.prt!CAP!CAP_0402LF-0.01UF,25V,10%,X7R,A36096-045!CAP!!!F3555!!ST_SATA!!
S!@baseboard_fab2_lib.baseboard_fab2(sch_1):page174_i31@mstr_discrete.cap(chips)!CAP_0402LF-0.01UF,25V,10%,X7R,A!C2L35!//jf4cfls225.pdx.intel.com/apd_proj/ppg_lib/epg_masterlib/logical/mstr_discrete/cap/chips/chips.prt!CAP!CAP_0402LF-0.01UF,25V,10%,X7R,A36096-045!CAP!!!F3549!!ST_SATA!!
S!@baseboard_fab2_lib.baseboard_fab2(sch_1):page174_i40@mstr_discrete.cap(chips)!CAP_0402LF-0.01UF,25V,10%,X7R,A!C2L33!//jf4cfls225.pdx.intel.com/apd_proj/ppg_lib/epg_masterlib/logical/mstr_discrete/cap/chips/chips.prt!CAP!CAP_0402LF-0.01UF,25V,10%,X7R,A36096-045!CAP!!!F3551!!ST_SATA!!
S!@baseboard_fab2_lib.baseboard_fab2(sch_1):page174_i19@mstr_discrete.cap(chips)!CAP_0402LF-0.01UF,25V,10%,X7R,A!C1L12!//jf4cfls225.pdx.intel.com/apd_proj/ppg_lib/epg_masterlib/logical/mstr_discrete/cap/chips/chips.prt!CAP!CAP_0402LF-0.01UF,25V,10%,X7R,A36096-045!CAP!!!F3587!!ST_SATA!!
S!@baseboard_fab2_lib.baseboard_fab2(sch_1):page174_i20@mstr_discrete.cap(chips)!CAP_0402LF-0.01UF,25V,10%,X7R,A!C1L14!//jf4cfls225.pdx.intel.com/apd_proj/ppg_lib/epg_masterlib/logical/mstr_discrete/cap/chips/chips.prt!CAP!CAP_0402LF-0.01UF,25V,10%,X7R,A36096-045!CAP!!!F3585!!ST_SATA!!
S!@baseboard_fab2_lib.baseboard_fab2(sch_1):page174_i9@mstr_discrete.cap(chips)!CAP_0402LF-0.01UF,25V,10%,X7R,A!C1L2!//jf4cfls225.pdx.intel.com/apd_proj/ppg_lib/epg_masterlib/logical/mstr_discrete/cap/chips/chips.prt!CAP!CAP_0402LF-0.01UF,25V,10%,X7R,A36096-045!CAP!!!F3591!!ST_SATA!!
S!@baseboard_fab2_lib.baseboard_fab2(sch_1):page174_i13@mstr_discrete.cap(chips)!CAP_0402LF-0.01UF,25V,10%,X7R,A!C1L6!//jf4cfls225.pdx.intel.com/apd_proj/ppg_lib/epg_masterlib/logical/mstr_discrete/cap/chips/chips.prt!CAP!CAP_0402LF-0.01UF,25V,10%,X7R,A36096-045!CAP!!!F3589!!ST_SATA!!
S!@baseboard_fab2_lib.baseboard_fab2(sch_1):page174_i14@mstr_discrete.cap(chips)!CAP_0402LF-0.01UF,25V,10%,X7R,A!C1L13!//jf4cfls225.pdx.intel.com/apd_proj/ppg_lib/epg_masterlib/logical/mstr_discrete/cap/chips/chips.prt!CAP!CAP_0402LF-0.01UF,25V,10%,X7R,A36096-045!CAP!!!F3586!!ST_SATA!!
S!@baseboard_fab2_lib.baseboard_fab2(sch_1):page174_i18@mstr_discrete.cap(chips)!CAP_0402LF-0.01UF,25V,10%,X7R,A!C1L15!//jf4cfls225.pdx.intel.com/apd_proj/ppg_lib/epg_masterlib/logical/mstr_discrete/cap/chips/chips.prt!CAP!CAP_0402LF-0.01UF,25V,10%,X7R,A36096-045!CAP!!!F3584!!ST_SATA!!
S!@baseboard_fab2_lib.baseboard_fab2(sch_1):page174_i8@mstr_discrete.cap(chips)!CAP_0402LF-0.01UF,25V,10%,X7R,A!C1L3!//jf4cfls225.pdx.intel.com/apd_proj/ppg_lib/epg_masterlib/logical/mstr_discrete/cap/chips/chips.prt!CAP!CAP_0402LF-0.01UF,25V,10%,X7R,A36096-045!CAP!!!F3590!!ST_SATA!!
S!@baseboard_fab2_lib.baseboard_fab2(sch_1):page174_i12@mstr_discrete.cap(chips)!CAP_0402LF-0.01UF,25V,10%,X7R,A!C1L7!//jf4cfls225.pdx.intel.com/apd_proj/ppg_lib/epg_masterlib/logical/mstr_discrete/cap/chips/chips.prt!CAP!CAP_0402LF-0.01UF,25V,10%,X7R,A36096-045!CAP!!!F3588!!ST_SATA!!
S!@baseboard_fab2_lib.baseboard_fab2(sch_1):page173_i208@mstr_discrete.cap(chips)!CAP_0402LF-0.01UF,25V,10%,X7R,A!C2L14!//jf4cfls225.pdx.intel.com/apd_proj/ppg_lib/epg_masterlib/logical/mstr_discrete/cap/chips/chips.prt!CAP!CAP_0402LF-0.01UF,25V,10%,X7R,A36096-045!CAP!!!F3568!!ST_SATA!!
S!@baseboard_fab2_lib.baseboard_fab2(sch_1):page173_i209@mstr_discrete.cap(chips)!CAP_0402LF-0.01UF,25V,10%,X7R,A!C2L5!//jf4cfls225.pdx.intel.com/apd_proj/ppg_lib/epg_masterlib/logical/mstr_discrete/cap/chips/chips.prt!CAP!CAP_0402LF-0.01UF,25V,10%,X7R,A36096-045!CAP!!!F3575!!ST_SATA!!
S!@baseboard_fab2_lib.baseboard_fab2(sch_1):page173_i197@mstr_discrete.cap(chips)!CAP_0402LF-0.01UF,25V,10%,X7R,A!C2L18!//jf4cfls225.pdx.intel.com/apd_proj/ppg_lib/epg_masterlib/logical/mstr_discrete/cap/chips/chips.prt!CAP!CAP_0402LF-0.01UF,25V,10%,X7R,A36096-045!CAP!!!F3564!!ST_SATA!!
S!@baseboard_fab2_lib.baseboard_fab2(sch_1):page173_i207@mstr_discrete.cap(chips)!CAP_0402LF-0.01UF,25V,10%,X7R,A!C2L9!//jf4cfls225.pdx.intel.com/apd_proj/ppg_lib/epg_masterlib/logical/mstr_discrete/cap/chips/chips.prt!CAP!CAP_0402LF-0.01UF,25V,10%,X7R,A36096-045!CAP!!!F3572!!ST_SATA!!
S!@baseboard_fab2_lib.baseboard_fab2(sch_1):page173_i195@mstr_discrete.cap(chips)!CAP_0402LF-0.01UF,25V,10%,X7R,A!C2L20!//jf4cfls225.pdx.intel.com/apd_proj/ppg_lib/epg_masterlib/logical/mstr_discrete/cap/chips/chips.prt!CAP!CAP_0402LF-0.01UF,25V,10%,X7R,A36096-045!CAP!!!F3562!!ST_SATA!!
S!@baseboard_fab2_lib.baseboard_fab2(sch_1):page173_i196@mstr_discrete.cap(chips)!CAP_0402LF-0.01UF,25V,10%,X7R,A!C2L12!//jf4cfls225.pdx.intel.com/apd_proj/ppg_lib/epg_masterlib/logical/mstr_discrete/cap/chips/chips.prt!CAP!CAP_0402LF-0.01UF,25V,10%,X7R,A36096-045!CAP!!!F3570!!ST_SATA!!
S!@baseboard_fab2_lib.baseboard_fab2(sch_1):page173_i205@mstr_discrete.cap(chips)!CAP_0402LF-0.01UF,25V,10%,X7R,A!C2L16!//jf4cfls225.pdx.intel.com/apd_proj/ppg_lib/epg_masterlib/logical/mstr_discrete/cap/chips/chips.prt!CAP!CAP_0402LF-0.01UF,25V,10%,X7R,A36096-045!CAP!!!F3566!!ST_SATA!!
S!@baseboard_fab2_lib.baseboard_fab2(sch_1):page173_i206@mstr_discrete.cap(chips)!CAP_0402LF-0.01UF,25V,10%,X7R,A!C2L7!//jf4cfls225.pdx.intel.com/apd_proj/ppg_lib/epg_masterlib/logical/mstr_discrete/cap/chips/chips.prt!CAP!CAP_0402LF-0.01UF,25V,10%,X7R,A36096-045!CAP!!!F3573!!ST_SATA!!
S!@baseboard_fab2_lib.baseboard_fab2(sch_1):page173_i239@mstr_discrete.cap(chips)!CAP_0402LF-0.01UF,25V,10%,X7R,A!C2L47!//jf4cfls225.pdx.intel.com/apd_proj/ppg_lib/epg_masterlib/logical/mstr_discrete/cap/chips/chips.prt!CAP!CAP_0402LF-0.01UF,25V,10%,X7R,A36096-045!CAP!!!F3539!!ST_SATA!!
S!@baseboard_fab2_lib.baseboard_fab2(sch_1):page173_i240@mstr_discrete.cap(chips)!CAP_0402LF-0.01UF,25V,10%,X7R,A!C2L27!//jf4cfls225.pdx.intel.com/apd_proj/ppg_lib/epg_masterlib/logical/mstr_discrete/cap/chips/chips.prt!CAP!CAP_0402LF-0.01UF,25V,10%,X7R,A36096-045!CAP!!!F3556!!ST_SATA!!
S!@baseboard_fab2_lib.baseboard_fab2(sch_1):page173_i257@mstr_discrete.cap(chips)!CAP_0402LF-0.01UF,25V,10%,X7R,A!C2L48!//jf4cfls225.pdx.intel.com/apd_proj/ppg_lib/epg_masterlib/logical/mstr_discrete/cap/chips/chips.prt!CAP!CAP_0402LF-0.01UF,25V,10%,X7R,A36096-045!CAP!!!F3538!!ST_SATA!!
S!@baseboard_fab2_lib.baseboard_fab2(sch_1):page173_i258@mstr_discrete.cap(chips)!CAP_0402LF-0.01UF,25V,10%,X7R,A!C2L24!//jf4cfls225.pdx.intel.com/apd_proj/ppg_lib/epg_masterlib/logical/mstr_discrete/cap/chips/chips.prt!CAP!CAP_0402LF-0.01UF,25V,10%,X7R,A36096-045!CAP!!!F3558!!ST_SATA!!
S!@baseboard_fab2_lib.baseboard_fab2(sch_1):page173_i238@mstr_discrete.cap(chips)!CAP_0402LF-0.01UF,25V,10%,X7R,A!C2L37!//jf4cfls225.pdx.intel.com/apd_proj/ppg_lib/epg_masterlib/logical/mstr_discrete/cap/chips/chips.prt!CAP!CAP_0402LF-0.01UF,25V,10%,X7R,A36096-045!CAP!!!F3547!!ST_SATA!!
S!@baseboard_fab2_lib.baseboard_fab2(sch_1):page173_i255@mstr_discrete.cap(chips)!CAP_0402LF-0.01UF,25V,10%,X7R,A!C2L26!//jf4cfls225.pdx.intel.com/apd_proj/ppg_lib/epg_masterlib/logical/mstr_discrete/cap/chips/chips.prt!CAP!CAP_0402LF-0.01UF,25V,10%,X7R,A36096-045!CAP!!!F3557!!ST_SATA!!
S!@baseboard_fab2_lib.baseboard_fab2(sch_1):page173_i256@mstr_discrete.cap(chips)!CAP_0402LF-0.01UF,25V,10%,X7R,A!C2L38!//jf4cfls225.pdx.intel.com/apd_proj/ppg_lib/epg_masterlib/logical/mstr_discrete/cap/chips/chips.prt!CAP!CAP_0402LF-0.01UF,25V,10%,X7R,A36096-045!CAP!!!F3546!!ST_SATA!!
S!@baseboard_fab2_lib.baseboard_fab2(sch_1):page173_i259@mstr_discrete.cap(chips)!CAP_0402LF-0.01UF,25V,10%,X7R,A!C2L21!//jf4cfls225.pdx.intel.com/apd_proj/ppg_lib/epg_masterlib/logical/mstr_discrete/cap/chips/chips.prt!CAP!CAP_0402LF-0.01UF,25V,10%,X7R,A36096-045!CAP!!!F3561!!ST_SATA!!
S!@baseboard_fab2_lib.baseboard_fab2(sch_1):page192_i1@mstr_discrete.cap(chips)!CAP_0402LF-0.01UF,25V,10%,X7R,A!C2P8!//jf4cfls225.pdx.intel.com/apd_proj/ppg_lib/epg_masterlib/logical/mstr_discrete/cap/chips/chips.prt!CAP!CAP_0402LF-0.01UF,25V,10%,X7R,A36096-045!CAP!!!F3531!!CPLD!!
S!@baseboard_fab2_lib.baseboard_fab2(sch_1):page43_i272@mstr_discrete.cap(chips)!CAP_0402LF-0.01UF,25V,10%,X7R,A!C4F10!//jf4cfls225.pdx.intel.com/apd_proj/ppg_lib/epg_masterlib/logical/mstr_discrete/cap/chips/chips.prt!CAP!CAP_0402LF-0.01UF,25V,10%,X7R,A36096-045!CAP!!!F3522!!DDR4_CH_A!!
S!@baseboard_fab2_lib.baseboard_fab2(sch_1):page45_i179@mstr_discrete.cap(chips)!CAP_0402LF-0.01UF,25V,10%,X7R,A!C4G3!//jf4cfls225.pdx.intel.com/apd_proj/ppg_lib/epg_masterlib/logical/mstr_discrete/cap/chips/chips.prt!CAP!CAP_0402LF-0.01UF,25V,10%,X7R,A36096-045!CAP!!!F3520!!DDR4_CH_A!!
S!@baseboard_fab2_lib.baseboard_fab2(sch_1):page79_i178@mstr_discrete.cap(chips)!CAP_0402LF-0.01UF,25V,10%,X7R,A!C9U7!//jf4cfls225.pdx.intel.com/apd_proj/ppg_lib/epg_masterlib/logical/mstr_discrete/cap/chips/chips.prt!CAP!CAP_0402LF-0.01UF,25V,10%,X7R,A36096-045!CAP!!!F3496!!DDR4_CH_J!!
S!@baseboard_fab2_lib.baseboard_fab2(sch_1):page77_i181@mstr_discrete.cap(chips)!CAP_0402LF-0.01UF,25V,10%,X7R,A!C1F22!//jf4cfls225.pdx.intel.com/apd_proj/ppg_lib/epg_masterlib/logical/mstr_discrete/cap/chips/chips.prt!CAP!CAP_0402LF-0.01UF,25V,10%,X7R,A36096-045!CAP!!!F3596!!DDR4_CH_G!!
S!@baseboard_fab2_lib.baseboard_fab2(sch_1):page47_i188@mstr_discrete.cap(chips)!CAP_0402LF-0.01UF,25V,10%,X7R,A!C4G19!//jf4cfls225.pdx.intel.com/apd_proj/ppg_lib/epg_masterlib/logical/mstr_discrete/cap/chips/chips.prt!CAP!CAP_0402LF-0.01UF,25V,10%,X7R,A36096-045!CAP!!!F3518!!DDR4_CH_C!!
S!@baseboard_fab2_lib.baseboard_fab2(sch_1):page48_i176@mstr_discrete.cap(chips)!CAP_0402LF-0.01UF,25V,10%,X7R,A!C6U17!//jf4cfls225.pdx.intel.com/apd_proj/ppg_lib/epg_masterlib/logical/mstr_discrete/cap/chips/chips.prt!CAP!CAP_0402LF-0.01UF,25V,10%,X7R,A36096-045!CAP!!!F3509!!DDR4_CH_B!!
S!@baseboard_fab2_lib.baseboard_fab2(sch_1):page49_i179@mstr_discrete.cap(chips)!CAP_0402LF-0.01UF,25V,10%,X7R,A!C4B12!//jf4cfls225.pdx.intel.com/apd_proj/ppg_lib/epg_masterlib/logical/mstr_discrete/cap/chips/chips.prt!CAP!CAP_0402LF-0.01UF,25V,10%,X7R,A36096-045!CAP!!!F3524!!DDR4_CH_B!!
S!@baseboard_fab2_lib.baseboard_fab2(sch_1):page51_i175@mstr_discrete.cap(chips)!CAP_0402LF-0.01UF,25V,10%,X7R,A!C6L6!//jf4cfls225.pdx.intel.com/apd_proj/ppg_lib/epg_masterlib/logical/mstr_discrete/cap/chips/chips.prt!CAP!CAP_0402LF-0.01UF,25V,10%,X7R,A36096-045!CAP!!!F3515!!DDR4_CH_E!!
S!@baseboard_fab2_lib.baseboard_fab2(sch_1):page88_i177@mstr_discrete.cap(chips)!CAP_0402LF-0.01UF,25V,10%,X7R,A!C9L1!//jf4cfls225.pdx.intel.com/apd_proj/ppg_lib/epg_masterlib/logical/mstr_discrete/cap/chips/chips.prt!CAP!CAP_0402LF-0.01UF,25V,10%,X7R,A36096-045!CAP!!!F3504!!DDR4_CH_M1!!
S!@baseboard_fab2_lib.baseboard_fab2(sch_1):page87_i178@mstr_discrete.cap(chips)!CAP_0402LF-0.01UF,25V,10%,X7R,A!C1A5!//jf4cfls225.pdx.intel.com/apd_proj/ppg_lib/epg_masterlib/logical/mstr_discrete/cap/chips/chips.prt!CAP!CAP_0402LF-0.01UF,25V,10%,X7R,A36096-045!CAP!!!F3603!!DDR4_CH_M!!
S!@baseboard_fab2_lib.baseboard_fab2(sch_1):page53_i178@mstr_discrete.cap(chips)!CAP_0402LF-0.01UF,25V,10%,X7R,A!C6L1!//jf4cfls225.pdx.intel.com/apd_proj/ppg_lib/epg_masterlib/logical/mstr_discrete/cap/chips/chips.prt!CAP!CAP_0402LF-0.01UF,25V,10%,X7R,A36096-045!CAP!!!F3517!!DDR4_CH_F!!
S!@baseboard_fab2_lib.baseboard_fab2(sch_1):page83_i176@mstr_discrete.cap(chips)!CAP_0402LF-0.01UF,25V,10%,X7R,A!C1B9!//jf4cfls225.pdx.intel.com/apd_proj/ppg_lib/epg_masterlib/logical/mstr_discrete/cap/chips/chips.prt!CAP!CAP_0402LF-0.01UF,25V,10%,X7R,A36096-045!CAP!!!F3601!!DDR4_CH_K!!
S!@baseboard_fab2_lib.baseboard_fab2(sch_1):page54_i179@mstr_discrete.cap(chips)!CAP_0402LF-0.01UF,25V,10%,X7R,A!C4A5!//jf4cfls225.pdx.intel.com/apd_proj/ppg_lib/epg_masterlib/logical/mstr_discrete/cap/chips/chips.prt!CAP!CAP_0402LF-0.01UF,25V,10%,X7R,A36096-045!CAP!!!F3526!!DDR4_CH_F1!!
S!@baseboard_fab2_lib.baseboard_fab2(sch_1):page82_i180@mstr_discrete.cap(chips)!CAP_0402LF-0.01UF,25V,10%,X7R,A!C1G19!//jf4cfls225.pdx.intel.com/apd_proj/ppg_lib/epg_masterlib/logical/mstr_discrete/cap/chips/chips.prt!CAP!CAP_0402LF-0.01UF,25V,10%,X7R,A36096-045!CAP!!!F3592!!DDR4_CH_J!!
S!@baseboard_fab2_lib.baseboard_fab2(sch_1):page84_i4@mstr_discrete.cap(chips)!CAP_0402LF-0.01UF,25V,10%,X7R,A!C9M1!//jf4cfls225.pdx.intel.com/apd_proj/ppg_lib/epg_masterlib/logical/mstr_discrete/cap/chips/chips.prt!CAP!CAP_0402LF-0.01UF,25V,10%,X7R,A36096-045!CAP!!!F3500!!DDR4_CH_C!!
S!@baseboard_fab2_lib.baseboard_fab2(sch_1):page86_i182@mstr_discrete.cap(chips)!CAP_0402LF-0.01UF,25V,10%,X7R,A!C1A17!//jf4cfls225.pdx.intel.com/apd_proj/ppg_lib/epg_masterlib/logical/mstr_discrete/cap/chips/chips.prt!CAP!CAP_0402LF-0.01UF,25V,10%,X7R,A36096-045!CAP!!!F3602!!DDR4_CH_D!!
S!@baseboard_fab2_lib.baseboard_fab2(sch_1):page78_i2@mstr_discrete.cap(chips)!CAP_0402LF-0.01UF,25V,10%,X7R,A!C9T7!//jf4cfls225.pdx.intel.com/apd_proj/ppg_lib/epg_masterlib/logical/mstr_discrete/cap/chips/chips.prt!CAP!CAP_0402LF-0.01UF,25V,10%,X7R,A36096-045!CAP!!!F3497!!DDR4_GH_G!!
S!@baseboard_fab2_lib.baseboard_fab2(sch_1):page80_i3@mstr_discrete.cap(chips)!CAP_0402LF-0.01UF,25V,10%,X7R,A!C1G10!//jf4cfls225.pdx.intel.com/apd_proj/ppg_lib/epg_masterlib/logical/mstr_discrete/cap/chips/chips.prt!CAP!CAP_0402LF-0.01UF,25V,10%,X7R,A36096-045!CAP!!!F3594!!DDR4_GH_G!!
S!@baseboard_fab2_lib.baseboard_fab2(sch_1):page52_i3@mstr_discrete.cap(chips)!CAP_0402LF-0.01UF,25V,10%,X7R,A!C4A18!//jf4cfls225.pdx.intel.com/apd_proj/ppg_lib/epg_masterlib/logical/mstr_discrete/cap/chips/chips.prt!CAP!CAP_0402LF-0.01UF,25V,10%,X7R,A36096-045!CAP!!!F3525!!DDR4_CH_E!!
S!@baseboard_fab2_lib.baseboard_fab2(sch_1):page44_i2@mstr_discrete.cap(chips)!CAP_0402LF-0.01UF,25V,10%,X7R,A!C6T1!//jf4cfls225.pdx.intel.com/apd_proj/ppg_lib/epg_masterlib/logical/mstr_discrete/cap/chips/chips.prt!CAP!CAP_0402LF-0.01UF,25V,10%,X7R,A36096-045!CAP!!!F3511!!DDR4_CH_A!!
S!@baseboard_fab2_lib.baseboard_fab2(sch_1):page46_i5@mstr_discrete.cap(chips)!CAP_0402LF-0.01UF,25V,10%,X7R,A!C6U9!//jf4cfls225.pdx.intel.com/apd_proj/ppg_lib/epg_masterlib/logical/mstr_discrete/cap/chips/chips.prt!CAP!CAP_0402LF-0.01UF,25V,10%,X7R,A36096-045!CAP!!!F3510!!DDR4_CH_A!!
S!@baseboard_fab2_lib.baseboard_fab2(sch_1):page50_i177@mstr_discrete.cap(chips)!CAP_0402LF-0.01UF,25V,10%,X7R,A!C6M1!//jf4cfls225.pdx.intel.com/apd_proj/ppg_lib/epg_masterlib/logical/mstr_discrete/cap/chips/chips.prt!CAP!CAP_0402LF-0.01UF,25V,10%,X7R,A36096-045!CAP!!!F3513!!DDR4_CH_B!!
S!@baseboard_fab2_lib.baseboard_fab2(sch_1):page81_i178@mstr_discrete.cap(chips)!CAP_0402LF-0.01UF,25V,10%,X7R,A!C9U10!//jf4cfls225.pdx.intel.com/apd_proj/ppg_lib/epg_masterlib/logical/mstr_discrete/cap/chips/chips.prt!CAP!CAP_0402LF-0.01UF,25V,10%,X7R,A36096-045!CAP!!!F3495!!DDR4_CH_J!!
S!@baseboard_fab2_lib.baseboard_fab2(sch_1):page85_i181@mstr_discrete.cap(chips)!CAP_0402LF-0.01UF,25V,10%,X7R,A!C9L7!//jf4cfls225.pdx.intel.com/apd_proj/ppg_lib/epg_masterlib/logical/mstr_discrete/cap/chips/chips.prt!CAP!CAP_0402LF-0.01UF,25V,10%,X7R,A36096-045!CAP!!!F3502!!DDR4_CH_L!!
S!@baseboard_fab2_lib.baseboard_fab2(sch_1):page162_i28@mstr_discrete.cap(chips)!CAP_0402LF-0.01UF,25V,10%,X7R,A!C8F5!//jf4cfls225.pdx.intel.com/apd_proj/ppg_lib/epg_masterlib/logical/mstr_discrete/cap/chips/chips.prt!CAP!CAP_0402LF-0.01UF,25V,10%,X7R,A36096-045!CAP!!!F3507!!BMC_BOOT_SPI!!
S!@baseboard_fab2_lib.baseboard_fab2(sch_1):page153_i131@mstr_discrete.cap(chips)!CAP_0402LF-0.01UF,25V,10%,X7R,A!C7F1!//jf4cfls225.pdx.intel.com/apd_proj/ppg_lib/epg_masterlib/logical/mstr_discrete/cap/chips/chips.prt!CAP!CAP_0402LF-0.01UF,25V,10%,X7R,A36096-045!CAP!!!F3508!!SB_SPI!!
S!@baseboard_fab2_lib.baseboard_fab2(sch_1):page153_i136@mstr_discrete.cap(chips)!CAP_0402LF-0.01UF,25V,10%,X7R,A!C3T5!//jf4cfls225.pdx.intel.com/apd_proj/ppg_lib/epg_masterlib/logical/mstr_discrete/cap/chips/chips.prt!CAP!CAP_0402LF-0.01UF,25V,10%,X7R,A36096-045!CAP!!!F3527!!SB_SPI!!
S!@baseboard_fab2_lib.baseboard_fab2(sch_1):page173_i174@mstr_discrete.cap(chips)!CAP_0402LF-0.01UF,25V,10%,X7R,A!C2L17!//jf4cfls225.pdx.intel.com/apd_proj/ppg_lib/epg_masterlib/logical/mstr_discrete/cap/chips/chips.prt!CAP!CAP_0402LF-0.01UF,25V,10%,X7R,A36096-045!CAP!!!F3565!!ST_SATA!!
S!@baseboard_fab2_lib.baseboard_fab2(sch_1):page173_i166@mstr_discrete.cap(chips)!CAP_0402LF-0.01UF,25V,10%,X7R,A!C2L6!//jf4cfls225.pdx.intel.com/apd_proj/ppg_lib/epg_masterlib/logical/mstr_discrete/cap/chips/chips.prt!CAP!CAP_0402LF-0.01UF,25V,10%,X7R,A36096-045!CAP!!!F3574!!ST_SATA!!
S!@baseboard_fab2_lib.baseboard_fab2(sch_1):page173_i165@mstr_discrete.cap(chips)!CAP_0402LF-0.01UF,25V,10%,X7R,A!C2L13!//jf4cfls225.pdx.intel.com/apd_proj/ppg_lib/epg_masterlib/logical/mstr_discrete/cap/chips/chips.prt!CAP!CAP_0402LF-0.01UF,25V,10%,X7R,A36096-045!CAP!!!F3569!!ST_SATA!!
S!@baseboard_fab2_lib.baseboard_fab2(sch_1):page173_i194@mstr_discrete.cap(chips)!CAP_0402LF-0.01UF,25V,10%,X7R,A!C2L3!//jf4cfls225.pdx.intel.com/apd_proj/ppg_lib/epg_masterlib/logical/mstr_discrete/cap/chips/chips.prt!CAP!CAP_0402LF-0.01UF,25V,10%,X7R,A36096-045!CAP!!!F3577!!ST_SATA!!
S!@baseboard_fab2_lib.baseboard_fab2(sch_1):page173_i172@mstr_discrete.cap(chips)!CAP_0402LF-0.01UF,25V,10%,X7R,A!C2L19!//jf4cfls225.pdx.intel.com/apd_proj/ppg_lib/epg_masterlib/logical/mstr_discrete/cap/chips/chips.prt!CAP!CAP_0402LF-0.01UF,25V,10%,X7R,A36096-045!CAP!!!F3563!!ST_SATA!!
S!@baseboard_fab2_lib.baseboard_fab2(sch_1):page173_i173@mstr_discrete.cap(chips)!CAP_0402LF-0.01UF,25V,10%,X7R,A!C2L10!//jf4cfls225.pdx.intel.com/apd_proj/ppg_lib/epg_masterlib/logical/mstr_discrete/cap/chips/chips.prt!CAP!CAP_0402LF-0.01UF,25V,10%,X7R,A36096-045!CAP!!!F3571!!ST_SATA!!
S!@baseboard_fab2_lib.baseboard_fab2(sch_1):page173_i191@mstr_discrete.cap(chips)!CAP_0402LF-0.01UF,25V,10%,X7R,A!C2L15!//jf4cfls225.pdx.intel.com/apd_proj/ppg_lib/epg_masterlib/logical/mstr_discrete/cap/chips/chips.prt!CAP!CAP_0402LF-0.01UF,25V,10%,X7R,A36096-045!CAP!!!F3567!!ST_SATA!!
S!@baseboard_fab2_lib.baseboard_fab2(sch_1):page173_i192@mstr_discrete.cap(chips)!CAP_0402LF-0.01UF,25V,10%,X7R,A!C2L4!//jf4cfls225.pdx.intel.com/apd_proj/ppg_lib/epg_masterlib/logical/mstr_discrete/cap/chips/chips.prt!CAP!CAP_0402LF-0.01UF,25V,10%,X7R,A36096-045!CAP!!!F3576!!ST_SATA!!
S!@baseboard_fab2_lib.baseboard_fab2(sch_1):page173_i242@mstr_discrete.cap(chips)!CAP_0402LF-0.01UF,25V,10%,X7R,A!C2L41!//jf4cfls225.pdx.intel.com/apd_proj/ppg_lib/epg_masterlib/logical/mstr_discrete/cap/chips/chips.prt!CAP!CAP_0402LF-0.01UF,25V,10%,X7R,A36096-045!CAP!!!F3543!!ST_SATA!!
S!@baseboard_fab2_lib.baseboard_fab2(sch_1):page173_i241@mstr_discrete.cap(chips)!CAP_0402LF-0.01UF,25V,10%,X7R,A!C2L23!//jf4cfls225.pdx.intel.com/apd_proj/ppg_lib/epg_masterlib/logical/mstr_discrete/cap/chips/chips.prt!CAP!CAP_0402LF-0.01UF,25V,10%,X7R,A36096-045!CAP!!!F3559!!ST_SATA!!
S!@baseboard_fab2_lib.baseboard_fab2(sch_1):page173_i221@mstr_discrete.cap(chips)!CAP_0402LF-0.01UF,25V,10%,X7R,A!C2L39!//jf4cfls225.pdx.intel.com/apd_proj/ppg_lib/epg_masterlib/logical/mstr_discrete/cap/chips/chips.prt!CAP!CAP_0402LF-0.01UF,25V,10%,X7R,A36096-045!CAP!!!F3545!!ST_SATA!!
S!@baseboard_fab2_lib.baseboard_fab2(sch_1):page173_i222@mstr_discrete.cap(chips)!CAP_0402LF-0.01UF,25V,10%,X7R,A!C2L43!//jf4cfls225.pdx.intel.com/apd_proj/ppg_lib/epg_masterlib/logical/mstr_discrete/cap/chips/chips.prt!CAP!CAP_0402LF-0.01UF,25V,10%,X7R,A36096-045!CAP!!!F3541!!ST_SATA!!
S!@baseboard_fab2_lib.baseboard_fab2(sch_1):page173_i233@mstr_discrete.cap(chips)!CAP_0402LF-0.01UF,25V,10%,X7R,A!C2L42!//jf4cfls225.pdx.intel.com/apd_proj/ppg_lib/epg_masterlib/logical/mstr_discrete/cap/chips/chips.prt!CAP!CAP_0402LF-0.01UF,25V,10%,X7R,A36096-045!CAP!!!F3542!!ST_SATA!!
S!@baseboard_fab2_lib.baseboard_fab2(sch_1):page173_i234@mstr_discrete.cap(chips)!CAP_0402LF-0.01UF,25V,10%,X7R,A!C2L22!//jf4cfls225.pdx.intel.com/apd_proj/ppg_lib/epg_masterlib/logical/mstr_discrete/cap/chips/chips.prt!CAP!CAP_0402LF-0.01UF,25V,10%,X7R,A36096-045!CAP!!!F3560!!ST_SATA!!
S!@baseboard_fab2_lib.baseboard_fab2(sch_1):page173_i220@mstr_discrete.cap(chips)!CAP_0402LF-0.01UF,25V,10%,X7R,A!C2L40!//jf4cfls225.pdx.intel.com/apd_proj/ppg_lib/epg_masterlib/logical/mstr_discrete/cap/chips/chips.prt!CAP!CAP_0402LF-0.01UF,25V,10%,X7R,A36096-045!CAP!!!F3544!!ST_SATA!!
S!@baseboard_fab2_lib.baseboard_fab2(sch_1):page173_i228@mstr_discrete.cap(chips)!CAP_0402LF-0.01UF,25V,10%,X7R,A!C2L44!//jf4cfls225.pdx.intel.com/apd_proj/ppg_lib/epg_masterlib/logical/mstr_discrete/cap/chips/chips.prt!CAP!CAP_0402LF-0.01UF,25V,10%,X7R,A36096-045!CAP!!!F3540!!ST_SATA!!
S!@baseboard_fab2_lib.baseboard_fab2(sch_1):page161_i46@mstr_discrete.cap(chips)!CAP_0402LF-0.01UF,25V,10%,X7R,A!C1F9!//jf4cfls225.pdx.intel.com/apd_proj/ppg_lib/epg_masterlib/logical/mstr_discrete/cap/chips/chips.prt!CAP!CAP_0402LF-0.01UF,25V,10%,X7R,A36096-045!CAP!!!F3598!!CPU_FANS!!
S!@baseboard_fab2_lib.baseboard_fab2(sch_1):page161_i68@mstr_discrete.cap(chips)!CAP_0402LF-0.01UF,25V,10%,X7R,A!C1B15!//jf4cfls225.pdx.intel.com/apd_proj/ppg_lib/epg_masterlib/logical/mstr_discrete/cap/chips/chips.prt!CAP!CAP_0402LF-0.01UF,25V,10%,X7R,A36096-045!CAP!!!F3600!!CPU_FANS!!
S!@baseboard_fab2_lib.baseboard_fab2(sch_1):page101_i104@mstr_discrete.cap(chips)!CAP_0402LF-0.01UF,25V,10%,X7R,A!C2T18!//jf4cfls225.pdx.intel.com/apd_proj/ppg_lib/epg_masterlib/logical/mstr_discrete/cap/chips/chips.prt!CAP!CAP_0402LF-0.01UF,25V,10%,X7R,A36096-045!CAP!!!F3530!!SYS_CLOCK!!
S!@baseboard_fab2_lib.baseboard_fab2(sch_1):page101_i99@mstr_discrete.cap(chips)!CAP_0402LF-0.01UF,25V,10%,X7R,A!C2T37!//jf4cfls225.pdx.intel.com/apd_proj/ppg_lib/epg_masterlib/logical/mstr_discrete/cap/chips/chips.prt!CAP!CAP_0402LF-0.01UF,25V,10%,X7R,A36096-045!CAP!!!F3528!!SYS_CLOCK!!
S!@baseboard_fab2_lib.baseboard_fab2(sch_1):page101_i90@mstr_discrete.cap(chips)!CAP_0402LF-0.01UF,25V,10%,X7R,A!C2T27!//jf4cfls225.pdx.intel.com/apd_proj/ppg_lib/epg_masterlib/logical/mstr_discrete/cap/chips/chips.prt!CAP!CAP_0402LF-0.01UF,25V,10%,X7R,A36096-045!CAP!!!F3529!!SYS_CLOCK!!
S!@baseboard_fab2_lib.baseboard_fab2(sch_1):page100_i26@mstr_discrete.cap(chips)!CAP_0402LF-0.01UF,25V,10%,X7R,A!C1G8!//jf4cfls225.pdx.intel.com/apd_proj/ppg_lib/epg_masterlib/logical/mstr_discrete/cap/chips/chips.prt!CAP!CAP_0402LF-0.01UF,25V,10%,X7R,A36096-045!CAP!!!F3595!!PROC!!
S!@baseboard_fab2_lib.baseboard_fab2(sch_1):page100_i42@mstr_discrete.cap(chips)!CAP_0402LF-0.01UF,25V,10%,X7R,A!C1G18!//jf4cfls225.pdx.intel.com/apd_proj/ppg_lib/epg_masterlib/logical/mstr_discrete/cap/chips/chips.prt!CAP!CAP_0402LF-0.01UF,25V,10%,X7R,A36096-045!CAP!!!F3593!!PROC!!
S!@baseboard_fab2_lib.baseboard_fab2(sch_1):page100_i30@mstr_discrete.cap(chips)!CAP_0402LF-0.01UF,25V,10%,X7R,A!C9L8!//jf4cfls225.pdx.intel.com/apd_proj/ppg_lib/epg_masterlib/logical/mstr_discrete/cap/chips/chips.prt!CAP!CAP_0402LF-0.01UF,25V,10%,X7R,A36096-045!CAP!!!F3501!!MEM!!
S!@baseboard_fab2_lib.baseboard_fab2(sch_1):page100_i46@mstr_discrete.cap(chips)!CAP_0402LF-0.01UF,25V,10%,X7R,A!C9L3!//jf4cfls225.pdx.intel.com/apd_proj/ppg_lib/epg_masterlib/logical/mstr_discrete/cap/chips/chips.prt!CAP!CAP_0402LF-0.01UF,25V,10%,X7R,A36096-045!CAP!!!F3503!!MEM!!
S!@baseboard_fab2_lib.baseboard_fab2(sch_1):page98_i59@mstr_discrete.cap(chips)!CAP_0402LF-0.01UF,25V,10%,X7R,A!C6L7!//jf4cfls225.pdx.intel.com/apd_proj/ppg_lib/epg_masterlib/logical/mstr_discrete/cap/chips/chips.prt!CAP!CAP_0402LF-0.01UF,25V,10%,X7R,A36096-045!CAP!!!F3514!!MEM!!
S!@baseboard_fab2_lib.baseboard_fab2(sch_1):page98_i43@mstr_discrete.cap(chips)!CAP_0402LF-0.01UF,25V,10%,X7R,A!C4G1!//jf4cfls225.pdx.intel.com/apd_proj/ppg_lib/epg_masterlib/logical/mstr_discrete/cap/chips/chips.prt!CAP!CAP_0402LF-0.01UF,25V,10%,X7R,A36096-045!CAP!!!F3521!!MEM!!
S!@baseboard_fab2_lib.baseboard_fab2(sch_1):page98_i51@mstr_discrete.cap(chips)!CAP_0402LF-0.01UF,25V,10%,X7R,A!C4G17!//jf4cfls225.pdx.intel.com/apd_proj/ppg_lib/epg_masterlib/logical/mstr_discrete/cap/chips/chips.prt!CAP!CAP_0402LF-0.01UF,25V,10%,X7R,A36096-045!CAP!!!F3519!!MEM!!
S!@baseboard_fab2_lib.baseboard_fab2(sch_1):page98_i67@mstr_discrete.cap(chips)!CAP_0402LF-0.01UF,25V,10%,X7R,A!C6L2!//jf4cfls225.pdx.intel.com/apd_proj/ppg_lib/epg_masterlib/logical/mstr_discrete/cap/chips/chips.prt!CAP!CAP_0402LF-0.01UF,25V,10%,X7R,A36096-045!CAP!!!F3516!!MEM!!
S!@baseboard_fab2_lib.baseboard_fab2(sch_1):page151_i64@mstr_discrete.cap(chips)!CAP_0402LF-0.01UF,25V,10%,X7R,A!C1T39!//jf4cfls225.pdx.intel.com/apd_proj/ppg_lib/epg_masterlib/logical/mstr_discrete/cap/chips/chips.prt!CAP!CAP_0402LF-0.01UF,25V,10%,X7R,A36096-045!CAP!!!F3579!!BMC_MEMORY!!
S!@baseboard_fab2_lib.baseboard_fab2(sch_1):page151_i63@mstr_discrete.cap(chips)!CAP_0402LF-0.01UF,25V,10%,X7R,A!C1T41!//jf4cfls225.pdx.intel.com/apd_proj/ppg_lib/epg_masterlib/logical/mstr_discrete/cap/chips/chips.prt!CAP!CAP_0402LF-0.01UF,25V,10%,X7R,A36096-045!CAP!!!F3578!!BMC_MEMORY!!
S!@baseboard_fab2_lib.baseboard_fab2(sch_1):page149_i80@mstr_discrete.cap(chips)!CAP_0402LF-0.01UF,25V,10%,X7R,A!C1T34!//jf4cfls225.pdx.intel.com/apd_proj/ppg_lib/epg_masterlib/logical/mstr_discrete/cap/chips/chips.prt!CAP!CAP_0402LF-0.01UF,25V,10%,X7R,A36096-045!CAP!!!F3581!!BMC!!
S!@baseboard_fab2_lib.baseboard_fab2(sch_1):page149_i81@mstr_discrete.cap(chips)!CAP_0402LF-0.01UF,25V,10%,X7R,A!C1T24!//jf4cfls225.pdx.intel.com/apd_proj/ppg_lib/epg_masterlib/logical/mstr_discrete/cap/chips/chips.prt!CAP!CAP_0402LF-0.01UF,25V,10%,X7R,A36096-045!CAP!!!F3583!!BMC!!
S!@baseboard_fab2_lib.baseboard_fab2(sch_1):page149_i82@mstr_discrete.cap(chips)!CAP_0402LF-0.01UF,25V,10%,X7R,A!C1T27!//jf4cfls225.pdx.intel.com/apd_proj/ppg_lib/epg_masterlib/logical/mstr_discrete/cap/chips/chips.prt!CAP!CAP_0402LF-0.01UF,25V,10%,X7R,A36096-045!CAP!!!F3582!!BMC!!
S!@baseboard_fab2_lib.baseboard_fab2(sch_1):page149_i83@mstr_discrete.cap(chips)!CAP_0402LF-0.01UF,25V,10%,X7R,A!C1T36!//jf4cfls225.pdx.intel.com/apd_proj/ppg_lib/epg_masterlib/logical/mstr_discrete/cap/chips/chips.prt!CAP!CAP_0402LF-0.01UF,25V,10%,X7R,A36096-045!CAP!!!F3580!!BMC!!
S!@baseboard_fab2_lib.baseboard_fab2(sch_1):page98_i33@mstr_discrete.cap(chips)!CAP_0402LF-0.01UF,25V,10%,X7R,A!C6M2!//jf4cfls225.pdx.intel.com/apd_proj/ppg_lib/epg_masterlib/logical/mstr_discrete/cap/chips/chips.prt!CAP!CAP_0402LF-0.01UF,25V,10%,X7R,A36096-045!CAP!!!F3512!!MEM!!
S!@baseboard_fab2_lib.baseboard_fab2(sch_1):page98_i7@mstr_discrete.cap(chips)!CAP_0402LF-0.01UF,25V,10%,X7R,A!C4F9!//jf4cfls225.pdx.intel.com/apd_proj/ppg_lib/epg_masterlib/logical/mstr_discrete/cap/chips/chips.prt!CAP!CAP_0402LF-0.01UF,25V,10%,X7R,A36096-045!CAP!!!F3523!!MEM!!
S!@baseboard_fab2_lib.baseboard_fab2(sch_1):page112_i42@mstr_discrete.cap(chips)!CAP_0402LF-0.01UF,25V,10%,X7R,A!C1M36!//jf4cfls225.pdx.intel.com/apd_proj/ppg_lib/epg_masterlib/logical/mstr_discrete/cap/chips/chips.prt!CAP!CAP_0402LF-0.01UF,25V,10%,X7R,A36096-045!CAP!!!F3505!!DEBUG!!
S!@baseboard_fab2_lib.baseboard_fab2(sch_1):page172_i6@mstr_discrete.cap(chips)!CAP_0402LF-0.01UF,25V,10%,X7R,A!C2L52!//jf4cfls225.pdx.intel.com/apd_proj/ppg_lib/epg_masterlib/logical/mstr_discrete/cap/chips/chips.prt!CAP!CAP_0402LF-0.01UF,25V,10%,X7R,A36096-045!CAP!!!F3534!!ST_SATA!!
S!@baseboard_fab2_lib.baseboard_fab2(sch_1):page172_i5@mstr_discrete.cap(chips)!CAP_0402LF-0.01UF,25V,10%,X7R,A!C2L49!//jf4cfls225.pdx.intel.com/apd_proj/ppg_lib/epg_masterlib/logical/mstr_discrete/cap/chips/chips.prt!CAP!CAP_0402LF-0.01UF,25V,10%,X7R,A36096-045!CAP!!!F3537!!ST_SATA!!
S!@baseboard_fab2_lib.baseboard_fab2(sch_1):page172_i8@mstr_discrete.cap(chips)!CAP_0402LF-0.01UF,25V,10%,X7R,A!C2L51!//jf4cfls225.pdx.intel.com/apd_proj/ppg_lib/epg_masterlib/logical/mstr_discrete/cap/chips/chips.prt!CAP!CAP_0402LF-0.01UF,25V,10%,X7R,A36096-045!CAP!!!F3535!!ST_SATA!!
S!@baseboard_fab2_lib.baseboard_fab2(sch_1):page172_i7@mstr_discrete.cap(chips)!CAP_0402LF-0.01UF,25V,10%,X7R,A!C2L50!//jf4cfls225.pdx.intel.com/apd_proj/ppg_lib/epg_masterlib/logical/mstr_discrete/cap/chips/chips.prt!CAP!CAP_0402LF-0.01UF,25V,10%,X7R,A36096-045!CAP!!!F3536!!ST_SATA!!
S!@baseboard_fab2_lib.baseboard_fab2(sch_1):page100_i8@mstr_discrete.cap(chips)!CAP_0402LF-0.01UF,25V,10%,X7R,A!C1F19!//jf4cfls225.pdx.intel.com/apd_proj/ppg_lib/epg_masterlib/logical/mstr_discrete/cap/chips/chips.prt!CAP!CAP_0402LF-0.01UF,25V,10%,X7R,A36096-045!CAP!!!F3597!!PROC!!
S!@baseboard_fab2_lib.baseboard_fab2(sch_1):page100_i15@mstr_discrete.cap(chips)!CAP_0402LF-0.01UF,25V,10%,X7R,A!C9M2!//jf4cfls225.pdx.intel.com/apd_proj/ppg_lib/epg_masterlib/logical/mstr_discrete/cap/chips/chips.prt!CAP!CAP_0402LF-0.01UF,25V,10%,X7R,A36096-045!CAP!!!F3499!!MEM!!
S!@baseboard_fab2_lib.baseboard_fab2(sch_1):page209_i30@mstr_discrete.cap(chips)!CAP_0402LF-0.1UF,16V,10%,EMPTYA!C1B16!//jf4cfls225.pdx.intel.com/apd_proj/ppg_lib/epg_masterlib/logical/mstr_discrete/cap/chips/chips.prt!CAP!CAP_0402LF-0.1UF,16V,10%,EMPTY,A36096-030!CAP!!!F3489!!PVCCIN_CPU1_FILTER_VR!!
S!@baseboard_fab2_lib.baseboard_fab2(sch_1):page149_i151@mstr_discrete.cap(chips)!CAP_0402LF-0.1UF,16V,10%,EMPTYA!C1T17!//jf4cfls225.pdx.intel.com/apd_proj/ppg_lib/epg_masterlib/logical/mstr_discrete/cap/chips/chips.prt!CAP!CAP_0402LF-0.1UF,16V,10%,EMPTY,A36096-030!CAP!!!F3487!!BMC!!
S!@baseboard_fab2_lib.baseboard_fab2(sch_1):page204_i51@mstr_discrete.cap(chips)!CAP_0402LF-0.1UF,16V,10%,EMPTYA!C4C2!//jf4cfls225.pdx.intel.com/apd_proj/ppg_lib/epg_masterlib/logical/mstr_discrete/cap/chips/chips.prt!CAP!CAP_0402LF-0.1UF,16V,10%,EMPTY,A36096-030!CAP!!!F3482!!PVCCIN_CPU0_FILTER_VR!!
S!@baseboard_fab2_lib.baseboard_fab2(sch_1):page149_i160@mstr_discrete.cap(chips)!CAP_0402LF-0.1UF,16V,10%,EMPTYA!C9F15!//jf4cfls225.pdx.intel.com/apd_proj/ppg_lib/epg_masterlib/logical/mstr_discrete/cap/chips/chips.prt!CAP!CAP_0402LF-0.1UF,16V,10%,EMPTY,A36096-030!CAP!!!F3481!!BMC!!
S!@baseboard_fab2_lib.baseboard_fab2(sch_1):page145_i202@mstr_discrete.cap(chips)!CAP_0402LF-0.1UF,16V,10%,EMPTYA!C9F16!//jf4cfls225.pdx.intel.com/apd_proj/ppg_lib/epg_masterlib/logical/mstr_discrete/cap/chips/chips.prt!CAP!CAP_0402LF-0.1UF,16V,10%,EMPTY,A36096-030!CAP!!!F3480!!BMC!!
S!@baseboard_fab2_lib.baseboard_fab2(sch_1):page145_i201@mstr_discrete.cap(chips)!CAP_0402LF-0.1UF,16V,10%,EMPTYA!C9F17!//jf4cfls225.pdx.intel.com/apd_proj/ppg_lib/epg_masterlib/logical/mstr_discrete/cap/chips/chips.prt!CAP!CAP_0402LF-0.1UF,16V,10%,EMPTY,A36096-030!CAP!!!F3479!!BMC!!
S!@baseboard_fab2_lib.baseboard_fab2(sch_1):page116_i182@mstr_discrete.cap(chips)!CAP_0402LF-0.1UF,16V,10%,EMPTYA!C2M4!//jf4cfls225.pdx.intel.com/apd_proj/ppg_lib/epg_masterlib/logical/mstr_discrete/cap/chips/chips.prt!CAP!CAP_0402LF-0.1UF,16V,10%,EMPTY,A36096-030!CAP!!!F3485!!SB!!
S!@baseboard_fab2_lib.baseboard_fab2(sch_1):page116_i183@mstr_discrete.cap(chips)!CAP_0402LF-0.1UF,16V,10%,EMPTYA!C2M3!//jf4cfls225.pdx.intel.com/apd_proj/ppg_lib/epg_masterlib/logical/mstr_discrete/cap/chips/chips.prt!CAP!CAP_0402LF-0.1UF,16V,10%,EMPTY,A36096-030!CAP!!!F3486!!SB!!
S!@baseboard_fab2_lib.baseboard_fab2(sch_1):page214_i96@mstr_discrete.cap(chips)!CAP_0402LF-0.1UF,16V,10%,EMPTYA!C3D27!//jf4cfls225.pdx.intel.com/apd_proj/ppg_lib/epg_masterlib/logical/mstr_discrete/cap/chips/chips.prt!CAP!CAP_0402LF-0.1UF,16V,10%,EMPTY,A36096-030!CAP!!!F3484!!PVCCIO_CPU1!!
S!@baseboard_fab2_lib.baseboard_fab2(sch_1):page212_i60@mstr_discrete.cap(chips)!CAP_0402LF-0.1UF,16V,10%,EMPTYA!C3P1!//jf4cfls225.pdx.intel.com/apd_proj/ppg_lib/epg_masterlib/logical/mstr_discrete/cap/chips/chips.prt!CAP!CAP_0402LF-0.1UF,16V,10%,EMPTY,A36096-030!CAP!!!F3483!!PVCCIO_CPU0!!
S!@baseboard_fab2_lib.baseboard_fab2(sch_1):page199_i67@mstr_discrete.cap(chips)!CAP_0402LF-0.1UF,16V,10%,EMPTYA!C9P12!//jf4cfls225.pdx.intel.com/apd_proj/ppg_lib/epg_masterlib/logical/mstr_discrete/cap/chips/chips.prt!CAP!CAP_0402LF-0.1UF,16V,10%,EMPTY,A36096-030!CAP!!!F3478!!HOT_SWAP!!
S!@baseboard_fab2_lib.baseboard_fab2(sch_1):page200_i36@mstr_discrete.cap(chips)!CAP_0402LF-0.1UF,16V,10%,EMPTYA!C9P17!//jf4cfls225.pdx.intel.com/apd_proj/ppg_lib/epg_masterlib/logical/mstr_discrete/cap/chips/chips.prt!CAP!CAP_0402LF-0.1UF,16V,10%,EMPTY,A36096-030!CAP!!!F3476!!HOT_SWAP!!
S!@baseboard_fab2_lib.baseboard_fab2(sch_1):page200_i40@mstr_discrete.cap(chips)!CAP_0402LF-0.1UF,16V,10%,EMPTYA!C9P16!//jf4cfls225.pdx.intel.com/apd_proj/ppg_lib/epg_masterlib/logical/mstr_discrete/cap/chips/chips.prt!CAP!CAP_0402LF-0.1UF,16V,10%,EMPTY,A36096-030!CAP!!!F3477!!HOT_SWAP!!
S!@baseboard_fab2_lib.baseboard_fab2(sch_1):page200_i42@mstr_discrete.cap(chips)!CAP_0402LF-0.1UF,16V,10%,EMPTYA!C1D22!//jf4cfls225.pdx.intel.com/apd_proj/ppg_lib/epg_masterlib/logical/mstr_discrete/cap/chips/chips.prt!CAP!CAP_0402LF-0.1UF,16V,10%,EMPTY,A36096-030!CAP!!!F3488!!HOT_SWAP!!
S!@baseboard_fab2_lib.baseboard_fab2(sch_1):page113_i248@mstr_discrete.cap(chips)!CAP_0402LF-0.1UF,16V,10%,X7R,AA!C1M33!//jf4cfls225.pdx.intel.com/apd_proj/ppg_lib/epg_masterlib/logical/mstr_discrete/cap/chips/chips.prt!CAP!CAP_0402LF-0.1UF,16V,10%,X7R,A36096-030!CAP!!!F3216!!DEBUG!!
S!@baseboard_fab2_lib.baseboard_fab2(sch_1):page113_i250@mstr_discrete.cap(chips)!CAP_0402LF-0.1UF,16V,10%,X7R,AA!C6M6!//jf4cfls225.pdx.intel.com/apd_proj/ppg_lib/epg_masterlib/logical/mstr_discrete/cap/chips/chips.prt!CAP!CAP_0402LF-0.1UF,16V,10%,X7R,A36096-030!CAP!!!F3215!!DEBUG!!
S!@baseboard_fab2_lib.baseboard_fab2(sch_1):page145_i258@mstr_discrete.cap(chips)!CAP_0402LF-0.1UF,16V,10%,X7R,AA!C9F23!//jf4cfls225.pdx.intel.com/apd_proj/ppg_lib/epg_masterlib/logical/mstr_discrete/cap/chips/chips.prt!CAP!CAP_0402LF-0.1UF,16V,10%,X7R,A36096-030!CAP!!!F3213!!BMC!!
S!@baseboard_fab2_lib.baseboard_fab2(sch_1):page113_i246@mstr_discrete.cap(chips)!CAP_0402LF-0.1UF,16V,10%,X7R,AA!C4R2!//jf4cfls225.pdx.intel.com/apd_proj/ppg_lib/epg_masterlib/logical/mstr_discrete/cap/chips/chips.prt!CAP!CAP_0402LF-0.1UF,16V,10%,X7R,A36096-030!CAP!!!F3214!!DEBUG!!
S!@baseboard_fab2_lib.baseboard_fab2(sch_1):page188_i64@mstr_discrete.cap(chips)!CAP_0402LF-0.1UF,16V,10%,X7R,AA!C8C8!//jf4cfls225.pdx.intel.com/apd_proj/ppg_lib/epg_masterlib/logical/mstr_discrete/cap/chips/chips.prt!CAP!CAP_0402LF-0.1UF,16V,10%,X7R,A36096-030!CAP!!!F3224!!!!
S!@baseboard_fab2_lib.baseboard_fab2(sch_1):page188_i68@mstr_discrete.cap(chips)!CAP_0402LF-0.1UF,16V,10%,X7R,AA!C8C9!//jf4cfls225.pdx.intel.com/apd_proj/ppg_lib/epg_masterlib/logical/mstr_discrete/cap/chips/chips.prt!CAP!CAP_0402LF-0.1UF,16V,10%,X7R,A36096-030!CAP!!!F3223!!!!
S!@baseboard_fab2_lib.baseboard_fab2(sch_1):page188_i72@mstr_discrete.cap(chips)!CAP_0402LF-0.1UF,16V,10%,X7R,AA!C8C11!//jf4cfls225.pdx.intel.com/apd_proj/ppg_lib/epg_masterlib/logical/mstr_discrete/cap/chips/chips.prt!CAP!CAP_0402LF-0.1UF,16V,10%,X7R,A36096-030!CAP!!!F3222!!!!
S!@baseboard_fab2_lib.baseboard_fab2(sch_1):page188_i73@mstr_discrete.cap(chips)!CAP_0402LF-0.1UF,16V,10%,X7R,AA!C8C10!//jf4cfls225.pdx.intel.com/apd_proj/ppg_lib/epg_masterlib/logical/mstr_discrete/cap/chips/chips.prt!CAP!CAP_0402LF-0.1UF,16V,10%,X7R,A36096-030!CAP!!!F3221!!!!
S!@baseboard_fab2_lib.baseboard_fab2(sch_1):page188_i80@mstr_discrete.cap(chips)!CAP_0402LF-0.1UF,16V,10%,X7R,AA!C8C12!//jf4cfls225.pdx.intel.com/apd_proj/ppg_lib/epg_masterlib/logical/mstr_discrete/cap/chips/chips.prt!CAP!CAP_0402LF-0.1UF,16V,10%,X7R,A36096-030!CAP!!!F3220!!!!
S!@baseboard_fab2_lib.baseboard_fab2(sch_1):page188_i81@mstr_discrete.cap(chips)!CAP_0402LF-0.1UF,16V,10%,X7R,AA!C8C13!//jf4cfls225.pdx.intel.com/apd_proj/ppg_lib/epg_masterlib/logical/mstr_discrete/cap/chips/chips.prt!CAP!CAP_0402LF-0.1UF,16V,10%,X7R,A36096-030!CAP!!!F3219!!!!
S!@baseboard_fab2_lib.baseboard_fab2(sch_1):page188_i82@mstr_discrete.cap(chips)!CAP_0402LF-0.1UF,16V,10%,X7R,AA!C8C15!//jf4cfls225.pdx.intel.com/apd_proj/ppg_lib/epg_masterlib/logical/mstr_discrete/cap/chips/chips.prt!CAP!CAP_0402LF-0.1UF,16V,10%,X7R,A36096-030!CAP!!!F3218!!!!
S!@baseboard_fab2_lib.baseboard_fab2(sch_1):page188_i86@mstr_discrete.cap(chips)!CAP_0402LF-0.1UF,16V,10%,X7R,AA!C8C14!//jf4cfls225.pdx.intel.com/apd_proj/ppg_lib/epg_masterlib/logical/mstr_discrete/cap/chips/chips.prt!CAP!CAP_0402LF-0.1UF,16V,10%,X7R,A36096-030!CAP!!!F3217!!!!
S!@baseboard_fab2_lib.baseboard_fab2(sch_1):page188_i23@mstr_discrete.cap(chips)!CAP_0402LF-0.1UF,16V,10%,X7R,AA!C2P12!//jf4cfls225.pdx.intel.com/apd_proj/ppg_lib/epg_masterlib/logical/mstr_discrete/cap/chips/chips.prt!CAP!CAP_0402LF-0.1UF,16V,10%,X7R,A36096-030!CAP!!!F3326!!IO_MODULE!!
S!@baseboard_fab2_lib.baseboard_fab2(sch_1):page188_i21@mstr_discrete.cap(chips)!CAP_0402LF-0.1UF,16V,10%,X7R,AA!C2P11!//jf4cfls225.pdx.intel.com/apd_proj/ppg_lib/epg_masterlib/logical/mstr_discrete/cap/chips/chips.prt!CAP!CAP_0402LF-0.1UF,16V,10%,X7R,A36096-030!CAP!!!F3307!!IO_MODULE!!
S!@baseboard_fab2_lib.baseboard_fab2(sch_1):page188_i2@mstr_discrete.cap(chips)!CAP_0402LF-0.1UF,16V,10%,X7R,AA!C2R15!//jf4cfls225.pdx.intel.com/apd_proj/ppg_lib/epg_masterlib/logical/mstr_discrete/cap/chips/chips.prt!CAP!CAP_0402LF-0.1UF,16V,10%,X7R,A36096-030!CAP!!!F3306!!IO_MODULE!!
S!@baseboard_fab2_lib.baseboard_fab2(sch_1):page188_i57@mstr_discrete.cap(chips)!CAP_0402LF-0.1UF,16V,10%,X7R,AA!C2P13!//jf4cfls225.pdx.intel.com/apd_proj/ppg_lib/epg_masterlib/logical/mstr_discrete/cap/chips/chips.prt!CAP!CAP_0402LF-0.1UF,16V,10%,X7R,A36096-030!CAP!!!F3294!!IO_MODULE!!
S!@baseboard_fab2_lib.baseboard_fab2(sch_1):page188_i56@mstr_discrete.cap(chips)!CAP_0402LF-0.1UF,16V,10%,X7R,AA!C2P14!//jf4cfls225.pdx.intel.com/apd_proj/ppg_lib/epg_masterlib/logical/mstr_discrete/cap/chips/chips.prt!CAP!CAP_0402LF-0.1UF,16V,10%,X7R,A36096-030!CAP!!!F3273!!IO_MODULE!!
S!@baseboard_fab2_lib.baseboard_fab2(sch_1):page188_i55@mstr_discrete.cap(chips)!CAP_0402LF-0.1UF,16V,10%,X7R,AA!C2P15!//jf4cfls225.pdx.intel.com/apd_proj/ppg_lib/epg_masterlib/logical/mstr_discrete/cap/chips/chips.prt!CAP!CAP_0402LF-0.1UF,16V,10%,X7R,A36096-030!CAP!!!F3258!!IO_MODULE!!
S!@baseboard_fab2_lib.baseboard_fab2(sch_1):page188_i53@mstr_discrete.cap(chips)!CAP_0402LF-0.1UF,16V,10%,X7R,AA!C2P16!//jf4cfls225.pdx.intel.com/apd_proj/ppg_lib/epg_masterlib/logical/mstr_discrete/cap/chips/chips.prt!CAP!CAP_0402LF-0.1UF,16V,10%,X7R,A36096-030!CAP!!!F3228!!IO_MODULE!!
S!@baseboard_fab2_lib.baseboard_fab2(sch_1):page188_i40@mstr_discrete.cap(chips)!CAP_0402LF-0.1UF,16V,10%,X7R,AA!C2R16!//jf4cfls225.pdx.intel.com/apd_proj/ppg_lib/epg_masterlib/logical/mstr_discrete/cap/chips/chips.prt!CAP!CAP_0402LF-0.1UF,16V,10%,X7R,A36096-030!CAP!!!F3227!!IO_MODULE!!
S!@baseboard_fab2_lib.baseboard_fab2(sch_1):page188_i25@mstr_discrete.cap(chips)!CAP_0402LF-0.1UF,16V,10%,X7R,AA!C2R17!//jf4cfls225.pdx.intel.com/apd_proj/ppg_lib/epg_masterlib/logical/mstr_discrete/cap/chips/chips.prt!CAP!CAP_0402LF-0.1UF,16V,10%,X7R,A36096-030!CAP!!!F3226!!IO_MODULE!!
S!@baseboard_fab2_lib.baseboard_fab2(sch_1):page188_i3@mstr_discrete.cap(chips)!CAP_0402LF-0.1UF,16V,10%,X7R,AA!C2R18!//jf4cfls225.pdx.intel.com/apd_proj/ppg_lib/epg_masterlib/logical/mstr_discrete/cap/chips/chips.prt!CAP!CAP_0402LF-0.1UF,16V,10%,X7R,A36096-030!CAP!!!F3225!!IO_MODULE!!
S!@baseboard_fab2_lib.baseboard_fab2(sch_1):page118_i136@mstr_discrete.cap(chips)!CAP_0402LF-0.1UF,16V,10%,X7R,AA!C7D1!//jf4cfls225.pdx.intel.com/apd_proj/ppg_lib/epg_masterlib/logical/mstr_discrete/cap/chips/chips.prt!CAP!CAP_0402LF-0.1UF,16V,10%,X7R,A36096-030!CAP!!!F3287!!SB!!
S!@baseboard_fab2_lib.baseboard_fab2(sch_1):page199_i121@mstr_discrete.cap(chips)!CAP_0402LF-0.1UF,16V,10%,X7R,AA!C1D21!//jf4cfls225.pdx.intel.com/apd_proj/ppg_lib/epg_masterlib/logical/mstr_discrete/cap/chips/chips.prt!CAP!CAP_0402LF-0.1UF,16V,10%,X7R,A36096-030!CAP!!!F3462!!HOT_SWAP!!
S!@baseboard_fab2_lib.baseboard_fab2(sch_1):page223_i92@mstr_discrete.cap(chips)!CAP_0402LF-0.1UF,16V,10%,X7R,AA!C9U12!//jf4cfls225.pdx.intel.com/apd_proj/ppg_lib/epg_masterlib/logical/mstr_discrete/cap/chips/chips.prt!CAP!CAP_0402LF-0.1UF,16V,10%,X7R,A36096-030!CAP!!!F3229!!VDDQ_GHJ_PWR_VR!!
S!@baseboard_fab2_lib.baseboard_fab2(sch_1):page218_i77@mstr_discrete.cap(chips)!CAP_0402LF-0.1UF,16V,10%,X7R,AA!C3L31!//jf4cfls225.pdx.intel.com/apd_proj/ppg_lib/epg_masterlib/logical/mstr_discrete/cap/chips/chips.prt!CAP!CAP_0402LF-0.1UF,16V,10%,X7R,A36096-030!CAP!!!F3324!!VDDQ_DEF_PWR_VR!!
S!@baseboard_fab2_lib.baseboard_fab2(sch_1):page215_i360@mstr_discrete.cap(chips)!CAP_0402LF-0.1UF,16V,10%,X7R,AA!C3U10!//jf4cfls225.pdx.intel.com/apd_proj/ppg_lib/epg_masterlib/logical/mstr_discrete/cap/chips/chips.prt!CAP!CAP_0402LF-0.1UF,16V,10%,X7R,A36096-030!CAP!!!F3310!!VDDQ_ABC_PWR_VR!!
S!@baseboard_fab2_lib.baseboard_fab2(sch_1):page226_i92@mstr_discrete.cap(chips)!CAP_0402LF-0.1UF,16V,10%,X7R,AA!C9M11!//jf4cfls225.pdx.intel.com/apd_proj/ppg_lib/epg_masterlib/logical/mstr_discrete/cap/chips/chips.prt!CAP!CAP_0402LF-0.1UF,16V,10%,X7R,A36096-030!CAP!!!F3471!!VDDQ_KLM_PWR_VR!!
S!@baseboard_fab2_lib.baseboard_fab2(sch_1):page95_i115@mstr_discrete.cap(chips)!CAP_0402LF-0.1UF,16V,10%,X7R,AA!C7E4!//jf4cfls225.pdx.intel.com/apd_proj/ppg_lib/epg_masterlib/logical/mstr_discrete/cap/chips/chips.prt!CAP!CAP_0402LF-0.1UF,16V,10%,X7R,A36096-030!CAP!!!F3282!!PROC_SIDEBAND!!
S!@baseboard_fab2_lib.baseboard_fab2(sch_1):page155_i184@mstr_discrete.cap(chips)!CAP_0402LF-0.1UF,16V,10%,X7R,AA!C9F7!//jf4cfls225.pdx.intel.com/apd_proj/ppg_lib/epg_masterlib/logical/mstr_discrete/cap/chips/chips.prt!CAP!CAP_0402LF-0.1UF,16V,10%,X7R,A36096-030!CAP!!!F3247!!BMC_DEBUG_HEADER!!
S!@baseboard_fab2_lib.baseboard_fab2(sch_1):page151_i90@mstr_discrete.cap(chips)!CAP_0402LF-0.1UF,16V,10%,X7R,AA!C9F11!//jf4cfls225.pdx.intel.com/apd_proj/ppg_lib/epg_masterlib/logical/mstr_discrete/cap/chips/chips.prt!CAP!CAP_0402LF-0.1UF,16V,10%,X7R,A36096-030!CAP!!!F3246!!BMC_MEMORY!!
S!@baseboard_fab2_lib.baseboard_fab2(sch_1):page156_i275@mstr_discrete.cap(chips)!CAP_0402LF-0.1UF,16V,10%,X7R,AA!C8F16!//jf4cfls225.pdx.intel.com/apd_proj/ppg_lib/epg_masterlib/logical/mstr_discrete/cap/chips/chips.prt!CAP!CAP_0402LF-0.1UF,16V,10%,X7R,A36096-030!CAP!!!F3260!!BMC_MISC!!
S!@baseboard_fab2_lib.baseboard_fab2(sch_1):page156_i273@mstr_discrete.cap(chips)!CAP_0402LF-0.1UF,16V,10%,X7R,AA!C2T35!//jf4cfls225.pdx.intel.com/apd_proj/ppg_lib/epg_masterlib/logical/mstr_discrete/cap/chips/chips.prt!CAP!CAP_0402LF-0.1UF,16V,10%,X7R,A36096-030!CAP!!!F3355!!BMC_MISC!!
S!@baseboard_fab2_lib.baseboard_fab2(sch_1):page111_i87@mstr_discrete.cap(chips)!CAP_0402LF-0.1UF,16V,10%,X7R,AA!C1L11!//jf4cfls225.pdx.intel.com/apd_proj/ppg_lib/epg_masterlib/logical/mstr_discrete/cap/chips/chips.prt!CAP!CAP_0402LF-0.1UF,16V,10%,X7R,A36096-030!CAP!!!F3445!!DEBUG!!
S!@baseboard_fab2_lib.baseboard_fab2(sch_1):page181_i253@mstr_discrete.cap(chips)!CAP_0402LF-0.1UF,16V,10%,X7R,AA!C8E1!//jf4cfls225.pdx.intel.com/apd_proj/ppg_lib/epg_masterlib/logical/mstr_discrete/cap/chips/chips.prt!CAP!CAP_0402LF-0.1UF,16V,10%,X7R,A36096-030!CAP!!!F3265!!IO_SLOT!!
S!@baseboard_fab2_lib.baseboard_fab2(sch_1):page154_i132@mstr_discrete.cap(chips)!CAP_0402LF-0.1UF,16V,10%,X7R,AA!C2T12!//jf4cfls225.pdx.intel.com/apd_proj/ppg_lib/epg_masterlib/logical/mstr_discrete/cap/chips/chips.prt!CAP!CAP_0402LF-0.1UF,16V,10%,X7R,A36096-030!CAP!!!F3367!!SB_BMC_SPI_MUX!!
S!@baseboard_fab2_lib.baseboard_fab2(sch_1):page154_i135@mstr_discrete.cap(chips)!CAP_0402LF-0.1UF,16V,10%,X7R,AA!C2T8!//jf4cfls225.pdx.intel.com/apd_proj/ppg_lib/epg_masterlib/logical/mstr_discrete/cap/chips/chips.prt!CAP!CAP_0402LF-0.1UF,16V,10%,X7R,A36096-030!CAP!!!F3368!!SB_BMC_SPI_MUX!!
S!@baseboard_fab2_lib.baseboard_fab2(sch_1):page157_i376@mstr_discrete.cap(chips)!CAP_0402LF-0.1UF,16V,10%,X7R,AA!C8D1!//jf4cfls225.pdx.intel.com/apd_proj/ppg_lib/epg_masterlib/logical/mstr_discrete/cap/chips/chips.prt!CAP!CAP_0402LF-0.1UF,16V,10%,X7R,A36096-030!CAP!!!F3267!!!!
S!@baseboard_fab2_lib.baseboard_fab2(sch_1):page157_i370@mstr_discrete.cap(chips)!CAP_0402LF-0.1UF,16V,10%,X7R,AA!C2T3!//jf4cfls225.pdx.intel.com/apd_proj/ppg_lib/epg_masterlib/logical/mstr_discrete/cap/chips/chips.prt!CAP!CAP_0402LF-0.1UF,16V,10%,X7R,A36096-030!CAP!!!F3371!!MIO_CHASSIS!!
S!@baseboard_fab2_lib.baseboard_fab2(sch_1):page102_i79@mstr_discrete.cap(chips)!CAP_0402LF-0.1UF,16V,10%,X7R,AA!C6P9!//jf4cfls225.pdx.intel.com/apd_proj/ppg_lib/epg_masterlib/logical/mstr_discrete/cap/chips/chips.prt!CAP!CAP_0402LF-0.1UF,16V,10%,X7R,A36096-030!CAP!!!F3299!!DB1200ZL!!
S!@baseboard_fab2_lib.baseboard_fab2(sch_1):page101_i109@mstr_discrete.cap(chips)!CAP_0402LF-0.1UF,16V,10%,X7R,AA!C2T34!//jf4cfls225.pdx.intel.com/apd_proj/ppg_lib/epg_masterlib/logical/mstr_discrete/cap/chips/chips.prt!CAP!CAP_0402LF-0.1UF,16V,10%,X7R,A36096-030!CAP!!!F3356!!SYS_CLOCK!!
S!@baseboard_fab2_lib.baseboard_fab2(sch_1):page200_i201@mstr_discrete.cap(chips)!CAP_0402LF-0.1UF,16V,10%,X7R,AA!C9P11!//jf4cfls225.pdx.intel.com/apd_proj/ppg_lib/epg_masterlib/logical/mstr_discrete/cap/chips/chips.prt!CAP!CAP_0402LF-0.1UF,16V,10%,X7R,A36096-030!CAP!!!F3235!!HOT_SWAP!!
S!@baseboard_fab2_lib.baseboard_fab2(sch_1):page136_i128@mstr_discrete.cap(chips)!CAP_0402LF-0.1UF,16V,10%,X7R,AA!C8E8!//jf4cfls225.pdx.intel.com/apd_proj/ppg_lib/epg_masterlib/logical/mstr_discrete/cap/chips/chips.prt!CAP!CAP_0402LF-0.1UF,16V,10%,X7R,A36096-030!CAP!!!F3262!!SB!!
S!@baseboard_fab2_lib.baseboard_fab2(sch_1):page199_i107@mstr_discrete.cap(chips)!CAP_0402LF-0.1UF,16V,10%,X7R,AA!C1D26!//jf4cfls225.pdx.intel.com/apd_proj/ppg_lib/epg_masterlib/logical/mstr_discrete/cap/chips/chips.prt!CAP!CAP_0402LF-0.1UF,16V,10%,X7R,A36096-030!CAP!!!F3461!!HOT_SWAP!!
S!@baseboard_fab2_lib.baseboard_fab2(sch_1):page200_i187@mstr_discrete.cap(chips)!CAP_0402LF-0.1UF,16V,10%,X7R,AA!C1D9!//jf4cfls225.pdx.intel.com/apd_proj/ppg_lib/epg_masterlib/logical/mstr_discrete/cap/chips/chips.prt!CAP!CAP_0402LF-0.1UF,16V,10%,X7R,A36096-030!CAP!!!F3465!!HOT_SWAP!!
S!@baseboard_fab2_lib.baseboard_fab2(sch_1):page200_i185@mstr_discrete.cap(chips)!CAP_0402LF-0.1UF,16V,10%,X7R,AA!C9P6!//jf4cfls225.pdx.intel.com/apd_proj/ppg_lib/epg_masterlib/logical/mstr_discrete/cap/chips/chips.prt!CAP!CAP_0402LF-0.1UF,16V,10%,X7R,A36096-030!CAP!!!F3236!!HOT_SWAP!!
S!@baseboard_fab2_lib.baseboard_fab2(sch_1):page199_i105@mstr_discrete.cap(chips)!CAP_0402LF-0.1UF,16V,10%,X7R,AA!C9P15!//jf4cfls225.pdx.intel.com/apd_proj/ppg_lib/epg_masterlib/logical/mstr_discrete/cap/chips/chips.prt!CAP!CAP_0402LF-0.1UF,16V,10%,X7R,A36096-030!CAP!!!F3234!!HOT_SWAP!!
S!@baseboard_fab2_lib.baseboard_fab2(sch_1):page232_i252@mstr_discrete.cap(chips)!CAP_0402LF-0.1UF,16V,10%,X7R,AA!C7B6!//jf4cfls225.pdx.intel.com/apd_proj/ppg_lib/epg_masterlib/logical/mstr_discrete/cap/chips/chips.prt!CAP!CAP_0402LF-0.1UF,16V,10%,X7R,A36096-030!CAP!!!F3289!!!!
S!@baseboard_fab2_lib.baseboard_fab2(sch_1):page231_i205@mstr_discrete.cap(chips)!CAP_0402LF-0.1UF,16V,10%,X7R,AA!C7F6!//jf4cfls225.pdx.intel.com/apd_proj/ppg_lib/epg_masterlib/logical/mstr_discrete/cap/chips/chips.prt!CAP!CAP_0402LF-0.1UF,16V,10%,X7R,A36096-030!CAP!!!F3278!!!!
S!@baseboard_fab2_lib.baseboard_fab2(sch_1):page233_i242@mstr_discrete.cap(chips)!CAP_0402LF-0.1UF,16V,10%,X7R,AA!C6U5!//jf4cfls225.pdx.intel.com/apd_proj/ppg_lib/epg_masterlib/logical/mstr_discrete/cap/chips/chips.prt!CAP!CAP_0402LF-0.1UF,16V,10%,X7R,A36096-030!CAP!!!F3295!!!!
S!@baseboard_fab2_lib.baseboard_fab2(sch_1):page234_i199@mstr_discrete.cap(chips)!CAP_0402LF-0.1UF,16V,10%,X7R,AA!C4A20!//jf4cfls225.pdx.intel.com/apd_proj/ppg_lib/epg_masterlib/logical/mstr_discrete/cap/chips/chips.prt!CAP!CAP_0402LF-0.1UF,16V,10%,X7R,A36096-030!CAP!!!F3325!!!!
S!@baseboard_fab2_lib.baseboard_fab2(sch_1):page113_i147@mstr_discrete.cap(chips)!CAP_0402LF-0.1UF,16V,10%,X7R,AA!C1M29!//jf4cfls225.pdx.intel.com/apd_proj/ppg_lib/epg_masterlib/logical/mstr_discrete/cap/chips/chips.prt!CAP!CAP_0402LF-0.1UF,16V,10%,X7R,A36096-030!CAP!!!F3386!!DEBUG!!
S!@baseboard_fab2_lib.baseboard_fab2(sch_1):page170_i49@mstr_discrete.cap(chips)!CAP_0402LF-0.1UF,16V,10%,X7R,AA!C1R28!//jf4cfls225.pdx.intel.com/apd_proj/ppg_lib/epg_masterlib/logical/mstr_discrete/cap/chips/chips.prt!CAP!CAP_0402LF-0.1UF,16V,10%,X7R,A36096-030!CAP!!!F3427!!FAST_PROCHOT!!
S!@baseboard_fab2_lib.baseboard_fab2(sch_1):page170_i8@mstr_discrete.cap(chips)!CAP_0402LF-0.1UF,16V,10%,X7R,AA!C2P1!//jf4cfls225.pdx.intel.com/apd_proj/ppg_lib/epg_masterlib/logical/mstr_discrete/cap/chips/chips.prt!CAP!CAP_0402LF-0.1UF,16V,10%,X7R,A36096-030!CAP!!!F3385!!FAST_PROCHOT!!
S!@baseboard_fab2_lib.baseboard_fab2(sch_1):page170_i33@mstr_discrete.cap(chips)!CAP_0402LF-0.1UF,16V,10%,X7R,AA!C8D2!//jf4cfls225.pdx.intel.com/apd_proj/ppg_lib/epg_masterlib/logical/mstr_discrete/cap/chips/chips.prt!CAP!CAP_0402LF-0.1UF,16V,10%,X7R,A36096-030!CAP!!!F3266!!FAST_PROCHOT!!
S!@baseboard_fab2_lib.baseboard_fab2(sch_1):page170_i30@mstr_discrete.cap(chips)!CAP_0402LF-0.1UF,16V,10%,X7R,AA!C1R27!//jf4cfls225.pdx.intel.com/apd_proj/ppg_lib/epg_masterlib/logical/mstr_discrete/cap/chips/chips.prt!CAP!CAP_0402LF-0.1UF,16V,10%,X7R,A36096-030!CAP!!!F3428!!FAST_PROCHOT!!
S!@baseboard_fab2_lib.baseboard_fab2(sch_1):page185_i120@mstr_discrete.cap(chips)!CAP_0402LF-0.1UF,16V,10%,X7R,AA!C2T29!//jf4cfls225.pdx.intel.com/apd_proj/ppg_lib/epg_masterlib/logical/mstr_discrete/cap/chips/chips.prt!CAP!CAP_0402LF-0.1UF,16V,10%,X7R,A36096-030!CAP!!!F3359!!M_2!!
S!@baseboard_fab2_lib.baseboard_fab2(sch_1):page185_i129@mstr_discrete.cap(chips)!CAP_0402LF-0.1UF,16V,10%,X7R,AA!C2T24!//jf4cfls225.pdx.intel.com/apd_proj/ppg_lib/epg_masterlib/logical/mstr_discrete/cap/chips/chips.prt!CAP!CAP_0402LF-0.1UF,16V,10%,X7R,A36096-030!CAP!!!F3362!!M_2!!
S!@baseboard_fab2_lib.baseboard_fab2(sch_1):page185_i135@mstr_discrete.cap(chips)!CAP_0402LF-0.1UF,16V,10%,X7R,AA!C2T5!//jf4cfls225.pdx.intel.com/apd_proj/ppg_lib/epg_masterlib/logical/mstr_discrete/cap/chips/chips.prt!CAP!CAP_0402LF-0.1UF,16V,10%,X7R,A36096-030!CAP!!!F3369!!M_2!!
S!@baseboard_fab2_lib.baseboard_fab2(sch_1):page185_i123@mstr_discrete.cap(chips)!CAP_0402LF-0.1UF,16V,10%,X7R,AA!C2T26!//jf4cfls225.pdx.intel.com/apd_proj/ppg_lib/epg_masterlib/logical/mstr_discrete/cap/chips/chips.prt!CAP!CAP_0402LF-0.1UF,16V,10%,X7R,A36096-030!CAP!!!F3360!!M_2!!
S!@baseboard_fab2_lib.baseboard_fab2(sch_1):page185_i127@mstr_discrete.cap(chips)!CAP_0402LF-0.1UF,16V,10%,X7R,AA!C2T15!//jf4cfls225.pdx.intel.com/apd_proj/ppg_lib/epg_masterlib/logical/mstr_discrete/cap/chips/chips.prt!CAP!CAP_0402LF-0.1UF,16V,10%,X7R,A36096-030!CAP!!!F3366!!M_2!!
S!@baseboard_fab2_lib.baseboard_fab2(sch_1):page185_i132@mstr_discrete.cap(chips)!CAP_0402LF-0.1UF,16V,10%,X7R,AA!C2T4!//jf4cfls225.pdx.intel.com/apd_proj/ppg_lib/epg_masterlib/logical/mstr_discrete/cap/chips/chips.prt!CAP!CAP_0402LF-0.1UF,16V,10%,X7R,A36096-030!CAP!!!F3370!!M_2!!
S!@baseboard_fab2_lib.baseboard_fab2(sch_1):page185_i124@mstr_discrete.cap(chips)!CAP_0402LF-0.1UF,16V,10%,X7R,AA!C2T21!//jf4cfls225.pdx.intel.com/apd_proj/ppg_lib/epg_masterlib/logical/mstr_discrete/cap/chips/chips.prt!CAP!CAP_0402LF-0.1UF,16V,10%,X7R,A36096-030!CAP!!!F3363!!M_2!!
S!@baseboard_fab2_lib.baseboard_fab2(sch_1):page185_i126@mstr_discrete.cap(chips)!CAP_0402LF-0.1UF,16V,10%,X7R,AA!C2T16!//jf4cfls225.pdx.intel.com/apd_proj/ppg_lib/epg_masterlib/logical/mstr_discrete/cap/chips/chips.prt!CAP!CAP_0402LF-0.1UF,16V,10%,X7R,A36096-030!CAP!!!F3365!!M_2!!
S!@baseboard_fab2_lib.baseboard_fab2(sch_1):page185_i131@mstr_discrete.cap(chips)!CAP_0402LF-0.1UF,16V,10%,X7R,AA!C2T2!//jf4cfls225.pdx.intel.com/apd_proj/ppg_lib/epg_masterlib/logical/mstr_discrete/cap/chips/chips.prt!CAP!CAP_0402LF-0.1UF,16V,10%,X7R,A36096-030!CAP!!!F3372!!M_2!!
S!@baseboard_fab2_lib.baseboard_fab2(sch_1):page183_i7@mstr_discrete.cap(chips)!CAP_0402LF-0.1UF,16V,10%,X7R,AA!C9F19!//jf4cfls225.pdx.intel.com/apd_proj/ppg_lib/epg_masterlib/logical/mstr_discrete/cap/chips/chips.prt!CAP!CAP_0402LF-0.1UF,16V,10%,X7R,A36096-030!CAP!!!F3244!!LBG!!
S!@baseboard_fab2_lib.baseboard_fab2(sch_1):page108_i318@mstr_discrete.cap(chips)!CAP_0402LF-0.1UF,16V,10%,X7R,AA!C2U22!//jf4cfls225.pdx.intel.com/apd_proj/ppg_lib/epg_masterlib/logical/mstr_discrete/cap/chips/chips.prt!CAP!CAP_0402LF-0.1UF,16V,10%,X7R,A36096-030!CAP!!!F3350!!IO_SLOT!!
S!@baseboard_fab2_lib.baseboard_fab2(sch_1):page108_i315@mstr_discrete.cap(chips)!CAP_0402LF-0.1UF,16V,10%,X7R,AA!C2U23!//jf4cfls225.pdx.intel.com/apd_proj/ppg_lib/epg_masterlib/logical/mstr_discrete/cap/chips/chips.prt!CAP!CAP_0402LF-0.1UF,16V,10%,X7R,A36096-030!CAP!!!F3349!!IO_SLOT!!
S!@baseboard_fab2_lib.baseboard_fab2(sch_1):page239_i71@mstr_discrete.cap(chips)!CAP_0402LF-0.1UF,16V,10%,X7R,AA!C9F5!//jf4cfls225.pdx.intel.com/apd_proj/ppg_lib/epg_masterlib/logical/mstr_discrete/cap/chips/chips.prt!CAP!CAP_0402LF-0.1UF,16V,10%,X7R,A36096-030!CAP!!!F3248!!!!
S!@baseboard_fab2_lib.baseboard_fab2(sch_1):page155_i127@mstr_discrete.cap(chips)!CAP_0402LF-0.1UF,16V,10%,X7R,AA!C9A1!//jf4cfls225.pdx.intel.com/apd_proj/ppg_lib/epg_masterlib/logical/mstr_discrete/cap/chips/chips.prt!CAP!CAP_0402LF-0.1UF,16V,10%,X7R,A36096-030!CAP!!!F3257!!BMC_DEBUG_HEADER!!
S!@baseboard_fab2_lib.baseboard_fab2(sch_1):page170_i40@mstr_discrete.cap(chips)!CAP_0402LF-0.1UF,16V,10%,X7R,AA!C8E2!//jf4cfls225.pdx.intel.com/apd_proj/ppg_lib/epg_masterlib/logical/mstr_discrete/cap/chips/chips.prt!CAP!CAP_0402LF-0.1UF,16V,10%,X7R,A36096-030!CAP!!!F3264!!PROC_SIDEBAND!!
S!@baseboard_fab2_lib.baseboard_fab2(sch_1):page104_i34@mstr_discrete.cap(chips)!CAP_0402LF-0.1UF,16V,10%,X7R,AA!C3F2!//jf4cfls225.pdx.intel.com/apd_proj/ppg_lib/epg_masterlib/logical/mstr_discrete/cap/chips/chips.prt!CAP!CAP_0402LF-0.1UF,16V,10%,X7R,A36096-030!CAP!!!F3342!!CLOCK_CPU1_OSC!!
S!@baseboard_fab2_lib.baseboard_fab2(sch_1):page104_i25@mstr_discrete.cap(chips)!CAP_0402LF-0.1UF,16V,10%,X7R,AA!C6F1!//jf4cfls225.pdx.intel.com/apd_proj/ppg_lib/epg_masterlib/logical/mstr_discrete/cap/chips/chips.prt!CAP!CAP_0402LF-0.1UF,16V,10%,X7R,A36096-030!CAP!!!F3305!!CLOCK_CPU0_OSC!!
S!@baseboard_fab2_lib.baseboard_fab2(sch_1):page192_i20@mstr_discrete.cap(chips)!CAP_0402LF-0.1UF,16V,10%,X7R,AA!C2P7!//jf4cfls225.pdx.intel.com/apd_proj/ppg_lib/epg_masterlib/logical/mstr_discrete/cap/chips/chips.prt!CAP!CAP_0402LF-0.1UF,16V,10%,X7R,A36096-030!CAP!!!F3379!!CPLD!!
S!@baseboard_fab2_lib.baseboard_fab2(sch_1):page192_i19@mstr_discrete.cap(chips)!CAP_0402LF-0.1UF,16V,10%,X7R,AA!C2R3!//jf4cfls225.pdx.intel.com/apd_proj/ppg_lib/epg_masterlib/logical/mstr_discrete/cap/chips/chips.prt!CAP!CAP_0402LF-0.1UF,16V,10%,X7R,A36096-030!CAP!!!F3376!!CPLD!!
S!@baseboard_fab2_lib.baseboard_fab2(sch_1):page192_i12@mstr_discrete.cap(chips)!CAP_0402LF-0.1UF,16V,10%,X7R,AA!C3P47!//jf4cfls225.pdx.intel.com/apd_proj/ppg_lib/epg_masterlib/logical/mstr_discrete/cap/chips/chips.prt!CAP!CAP_0402LF-0.1UF,16V,10%,X7R,A36096-030!CAP!!!F3334!!CPLD!!
S!@baseboard_fab2_lib.baseboard_fab2(sch_1):page192_i17@mstr_discrete.cap(chips)!CAP_0402LF-0.1UF,16V,10%,X7R,AA!C3P52!//jf4cfls225.pdx.intel.com/apd_proj/ppg_lib/epg_masterlib/logical/mstr_discrete/cap/chips/chips.prt!CAP!CAP_0402LF-0.1UF,16V,10%,X7R,A36096-030!CAP!!!F3330!!CPLD!!
S!@baseboard_fab2_lib.baseboard_fab2(sch_1):page192_i11@mstr_discrete.cap(chips)!CAP_0402LF-0.1UF,16V,10%,X7R,AA!C3P51!//jf4cfls225.pdx.intel.com/apd_proj/ppg_lib/epg_masterlib/logical/mstr_discrete/cap/chips/chips.prt!CAP!CAP_0402LF-0.1UF,16V,10%,X7R,A36096-030!CAP!!!F3331!!CPLD!!
S!@baseboard_fab2_lib.baseboard_fab2(sch_1):page192_i18@mstr_discrete.cap(chips)!CAP_0402LF-0.1UF,16V,10%,X7R,AA!C2P6!//jf4cfls225.pdx.intel.com/apd_proj/ppg_lib/epg_masterlib/logical/mstr_discrete/cap/chips/chips.prt!CAP!CAP_0402LF-0.1UF,16V,10%,X7R,A36096-030!CAP!!!F3380!!CPLD!!
S!@baseboard_fab2_lib.baseboard_fab2(sch_1):page192_i15@mstr_discrete.cap(chips)!CAP_0402LF-0.1UF,16V,10%,X7R,AA!C2R5!//jf4cfls225.pdx.intel.com/apd_proj/ppg_lib/epg_masterlib/logical/mstr_discrete/cap/chips/chips.prt!CAP!CAP_0402LF-0.1UF,16V,10%,X7R,A36096-030!CAP!!!F3374!!CPLD!!
S!@baseboard_fab2_lib.baseboard_fab2(sch_1):page192_i7@mstr_discrete.cap(chips)!CAP_0402LF-0.1UF,16V,10%,X7R,AA!C3R3!//jf4cfls225.pdx.intel.com/apd_proj/ppg_lib/epg_masterlib/logical/mstr_discrete/cap/chips/chips.prt!CAP!CAP_0402LF-0.1UF,16V,10%,X7R,A36096-030!CAP!!!F3327!!CPLD!!
S!@baseboard_fab2_lib.baseboard_fab2(sch_1):page192_i8@mstr_discrete.cap(chips)!CAP_0402LF-0.1UF,16V,10%,X7R,AA!C2R1!//jf4cfls225.pdx.intel.com/apd_proj/ppg_lib/epg_masterlib/logical/mstr_discrete/cap/chips/chips.prt!CAP!CAP_0402LF-0.1UF,16V,10%,X7R,A36096-030!CAP!!!F3378!!CPLD!!
S!@baseboard_fab2_lib.baseboard_fab2(sch_1):page192_i6@mstr_discrete.cap(chips)!CAP_0402LF-0.1UF,16V,10%,X7R,AA!C3P43!//jf4cfls225.pdx.intel.com/apd_proj/ppg_lib/epg_masterlib/logical/mstr_discrete/cap/chips/chips.prt!CAP!CAP_0402LF-0.1UF,16V,10%,X7R,A36096-030!CAP!!!F3336!!CPLD!!
S!@baseboard_fab2_lib.baseboard_fab2(sch_1):page192_i3@mstr_discrete.cap(chips)!CAP_0402LF-0.1UF,16V,10%,X7R,AA!C2P5!//jf4cfls225.pdx.intel.com/apd_proj/ppg_lib/epg_masterlib/logical/mstr_discrete/cap/chips/chips.prt!CAP!CAP_0402LF-0.1UF,16V,10%,X7R,A36096-030!CAP!!!F3381!!CPLD!!
S!@baseboard_fab2_lib.baseboard_fab2(sch_1):page192_i16@mstr_discrete.cap(chips)!CAP_0402LF-0.1UF,16V,10%,X7R,AA!C2P4!//jf4cfls225.pdx.intel.com/apd_proj/ppg_lib/epg_masterlib/logical/mstr_discrete/cap/chips/chips.prt!CAP!CAP_0402LF-0.1UF,16V,10%,X7R,A36096-030!CAP!!!F3382!!CPLD!!
S!@baseboard_fab2_lib.baseboard_fab2(sch_1):page192_i9@mstr_discrete.cap(chips)!CAP_0402LF-0.1UF,16V,10%,X7R,AA!C2P2!//jf4cfls225.pdx.intel.com/apd_proj/ppg_lib/epg_masterlib/logical/mstr_discrete/cap/chips/chips.prt!CAP!CAP_0402LF-0.1UF,16V,10%,X7R,A36096-030!CAP!!!F3384!!CPLD!!
S!@baseboard_fab2_lib.baseboard_fab2(sch_1):page192_i4@mstr_discrete.cap(chips)!CAP_0402LF-0.1UF,16V,10%,X7R,AA!C3R1!//jf4cfls225.pdx.intel.com/apd_proj/ppg_lib/epg_masterlib/logical/mstr_discrete/cap/chips/chips.prt!CAP!CAP_0402LF-0.1UF,16V,10%,X7R,A36096-030!CAP!!!F3329!!CPLD!!
S!@baseboard_fab2_lib.baseboard_fab2(sch_1):page192_i10@mstr_discrete.cap(chips)!CAP_0402LF-0.1UF,16V,10%,X7R,AA!C3R2!//jf4cfls225.pdx.intel.com/apd_proj/ppg_lib/epg_masterlib/logical/mstr_discrete/cap/chips/chips.prt!CAP!CAP_0402LF-0.1UF,16V,10%,X7R,A36096-030!CAP!!!F3328!!CPLD!!
S!@baseboard_fab2_lib.baseboard_fab2(sch_1):page192_i21@mstr_discrete.cap(chips)!CAP_0402LF-0.1UF,16V,10%,X7R,AA!C2R4!//jf4cfls225.pdx.intel.com/apd_proj/ppg_lib/epg_masterlib/logical/mstr_discrete/cap/chips/chips.prt!CAP!CAP_0402LF-0.1UF,16V,10%,X7R,A36096-030!CAP!!!F3375!!CPLD!!
S!@baseboard_fab2_lib.baseboard_fab2(sch_1):page192_i28@mstr_discrete.cap(chips)!CAP_0402LF-0.1UF,16V,10%,X7R,AA!C2R2!//jf4cfls225.pdx.intel.com/apd_proj/ppg_lib/epg_masterlib/logical/mstr_discrete/cap/chips/chips.prt!CAP!CAP_0402LF-0.1UF,16V,10%,X7R,A36096-030!CAP!!!F3377!!CPLD!!
S!@baseboard_fab2_lib.baseboard_fab2(sch_1):page192_i22@mstr_discrete.cap(chips)!CAP_0402LF-0.1UF,16V,10%,X7R,AA!C2P3!//jf4cfls225.pdx.intel.com/apd_proj/ppg_lib/epg_masterlib/logical/mstr_discrete/cap/chips/chips.prt!CAP!CAP_0402LF-0.1UF,16V,10%,X7R,A36096-030!CAP!!!F3383!!CPLD!!
S!@baseboard_fab2_lib.baseboard_fab2(sch_1):page192_i23@mstr_discrete.cap(chips)!CAP_0402LF-0.1UF,16V,10%,X7R,AA!C3P44!//jf4cfls225.pdx.intel.com/apd_proj/ppg_lib/epg_masterlib/logical/mstr_discrete/cap/chips/chips.prt!CAP!CAP_0402LF-0.1UF,16V,10%,X7R,A36096-030!CAP!!!F3335!!CPLD!!
S!@baseboard_fab2_lib.baseboard_fab2(sch_1):page192_i25@mstr_discrete.cap(chips)!CAP_0402LF-0.1UF,16V,10%,X7R,AA!C3P48!//jf4cfls225.pdx.intel.com/apd_proj/ppg_lib/epg_masterlib/logical/mstr_discrete/cap/chips/chips.prt!CAP!CAP_0402LF-0.1UF,16V,10%,X7R,A36096-030!CAP!!!F3333!!CPLD!!
S!@baseboard_fab2_lib.baseboard_fab2(sch_1):page102_i28@mstr_discrete.cap(chips)!CAP_0402LF-0.1UF,16V,10%,X7R,AA!C4D22!//jf4cfls225.pdx.intel.com/apd_proj/ppg_lib/epg_masterlib/logical/mstr_discrete/cap/chips/chips.prt!CAP!CAP_0402LF-0.1UF,16V,10%,X7R,A36096-030!CAP!!!F3319!!DB1200ZL!!
S!@baseboard_fab2_lib.baseboard_fab2(sch_1):page102_i18@mstr_discrete.cap(chips)!CAP_0402LF-0.1UF,16V,10%,X7R,AA!C4D24!//jf4cfls225.pdx.intel.com/apd_proj/ppg_lib/epg_masterlib/logical/mstr_discrete/cap/chips/chips.prt!CAP!CAP_0402LF-0.1UF,16V,10%,X7R,A36096-030!CAP!!!F3318!!DB1200ZL!!
S!@baseboard_fab2_lib.baseboard_fab2(sch_1):page102_i11@mstr_discrete.cap(chips)!CAP_0402LF-0.1UF,16V,10%,X7R,AA!C6P4!//jf4cfls225.pdx.intel.com/apd_proj/ppg_lib/epg_masterlib/logical/mstr_discrete/cap/chips/chips.prt!CAP!CAP_0402LF-0.1UF,16V,10%,X7R,A36096-030!CAP!!!F3302!!DB1200ZL!!
S!@baseboard_fab2_lib.baseboard_fab2(sch_1):page102_i12@mstr_discrete.cap(chips)!CAP_0402LF-0.1UF,16V,10%,X7R,AA!C6P6!//jf4cfls225.pdx.intel.com/apd_proj/ppg_lib/epg_masterlib/logical/mstr_discrete/cap/chips/chips.prt!CAP!CAP_0402LF-0.1UF,16V,10%,X7R,A36096-030!CAP!!!F3300!!DB1200ZL!!
S!@baseboard_fab2_lib.baseboard_fab2(sch_1):page102_i13@mstr_discrete.cap(chips)!CAP_0402LF-0.1UF,16V,10%,X7R,AA!C6P10!//jf4cfls225.pdx.intel.com/apd_proj/ppg_lib/epg_masterlib/logical/mstr_discrete/cap/chips/chips.prt!CAP!CAP_0402LF-0.1UF,16V,10%,X7R,A36096-030!CAP!!!F3298!!DB1200ZL!!
S!@baseboard_fab2_lib.baseboard_fab2(sch_1):page102_i14@mstr_discrete.cap(chips)!CAP_0402LF-0.1UF,16V,10%,X7R,AA!C6P5!//jf4cfls225.pdx.intel.com/apd_proj/ppg_lib/epg_masterlib/logical/mstr_discrete/cap/chips/chips.prt!CAP!CAP_0402LF-0.1UF,16V,10%,X7R,A36096-030!CAP!!!F3301!!DB1200ZL!!
S!@baseboard_fab2_lib.baseboard_fab2(sch_1):page102_i15@mstr_discrete.cap(chips)!CAP_0402LF-0.1UF,16V,10%,X7R,AA!C6P12!//jf4cfls225.pdx.intel.com/apd_proj/ppg_lib/epg_masterlib/logical/mstr_discrete/cap/chips/chips.prt!CAP!CAP_0402LF-0.1UF,16V,10%,X7R,A36096-030!CAP!!!F3296!!DB1200ZL!!
S!@baseboard_fab2_lib.baseboard_fab2(sch_1):page102_i16@mstr_discrete.cap(chips)!CAP_0402LF-0.1UF,16V,10%,X7R,AA!C6P11!//jf4cfls225.pdx.intel.com/apd_proj/ppg_lib/epg_masterlib/logical/mstr_discrete/cap/chips/chips.prt!CAP!CAP_0402LF-0.1UF,16V,10%,X7R,A36096-030!CAP!!!F3297!!DB1200ZL!!
S!@baseboard_fab2_lib.baseboard_fab2(sch_1):page175_i40@mstr_discrete.cap(chips)!CAP_0402LF-0.1UF,16V,10%,X7R,AA!C9A3!//jf4cfls225.pdx.intel.com/apd_proj/ppg_lib/epg_masterlib/logical/mstr_discrete/cap/chips/chips.prt!CAP!CAP_0402LF-0.1UF,16V,10%,X7R,A36096-030!CAP!!!F3255!!MIO_CHASSIS!!
S!@baseboard_fab2_lib.baseboard_fab2(sch_1):page175_i38@mstr_discrete.cap(chips)!CAP_0402LF-0.1UF,16V,10%,X7R,AA!C1L9!//jf4cfls225.pdx.intel.com/apd_proj/ppg_lib/epg_masterlib/logical/mstr_discrete/cap/chips/chips.prt!CAP!CAP_0402LF-0.1UF,16V,10%,X7R,A36096-030!CAP!!!F3446!!MIO_CHASSIS!!
S!@baseboard_fab2_lib.baseboard_fab2(sch_1):page175_i37@mstr_discrete.cap(chips)!CAP_0402LF-0.1UF,16V,10%,X7R,AA!C1L17!//jf4cfls225.pdx.intel.com/apd_proj/ppg_lib/epg_masterlib/logical/mstr_discrete/cap/chips/chips.prt!CAP!CAP_0402LF-0.1UF,16V,10%,X7R,A36096-030!CAP!!!F3444!!MIO_CHASSIS!!
S!@baseboard_fab2_lib.baseboard_fab2(sch_1):page175_i64@mstr_discrete.cap(chips)!CAP_0402LF-0.1UF,16V,10%,X7R,AA!C1L4!//jf4cfls225.pdx.intel.com/apd_proj/ppg_lib/epg_masterlib/logical/mstr_discrete/cap/chips/chips.prt!CAP!CAP_0402LF-0.1UF,16V,10%,X7R,A36096-030!CAP!!!F3448!!MIO_CHASSIS!!
S!@baseboard_fab2_lib.baseboard_fab2(sch_1):page198_i67@mstr_discrete.cap(chips)!CAP_0402LF-0.1UF,16V,10%,X7R,AA!C9M6!//jf4cfls225.pdx.intel.com/apd_proj/ppg_lib/epg_masterlib/logical/mstr_discrete/cap/chips/chips.prt!CAP!CAP_0402LF-0.1UF,16V,10%,X7R,A36096-030!CAP!!!F3238!!P12V_FAN_PWR_SWITCH!!
S!@baseboard_fab2_lib.baseboard_fab2(sch_1):page198_i76@mstr_discrete.cap(chips)!CAP_0402LF-0.1UF,16V,10%,X7R,AA!C9M9!//jf4cfls225.pdx.intel.com/apd_proj/ppg_lib/epg_masterlib/logical/mstr_discrete/cap/chips/chips.prt!CAP!CAP_0402LF-0.1UF,16V,10%,X7R,A36096-030!CAP!!!F3237!!P12V_FAN_PWR_SWITCH!!
S!@baseboard_fab2_lib.baseboard_fab2(sch_1):page198_i64@mstr_discrete.cap(chips)!CAP_0402LF-0.1UF,16V,10%,X7R,AA!C1B19!//jf4cfls225.pdx.intel.com/apd_proj/ppg_lib/epg_masterlib/logical/mstr_discrete/cap/chips/chips.prt!CAP!CAP_0402LF-0.1UF,16V,10%,X7R,A36096-030!CAP!!!F3470!!P12V_FAN_PWR_SWITCH!!
S!@baseboard_fab2_lib.baseboard_fab2(sch_1):page235_i169@mstr_discrete.cap(chips)!CAP_0402LF-0.1UF,16V,10%,X7R,AA!C2L11!//jf4cfls225.pdx.intel.com/apd_proj/ppg_lib/epg_masterlib/logical/mstr_discrete/cap/chips/chips.prt!CAP!CAP_0402LF-0.1UF,16V,10%,X7R,A36096-030!CAP!!!F3389!!PVNN_PCH_STBY!!
S!@baseboard_fab2_lib.baseboard_fab2(sch_1):page154_i14@mstr_discrete.cap(chips)!CAP_0402LF-0.1UF,16V,10%,X7R,AA!C8E18!//jf4cfls225.pdx.intel.com/apd_proj/ppg_lib/epg_masterlib/logical/mstr_discrete/cap/chips/chips.prt!CAP!CAP_0402LF-0.1UF,16V,10%,X7R,A36096-030!CAP!!!F3261!!SB_BMC_SPI_MUX!!
S!@baseboard_fab2_lib.baseboard_fab2(sch_1):page158_i70@mstr_discrete.cap(chips)!CAP_0402LF-0.1UF,16V,10%,X7R,AA!C1T10!//jf4cfls225.pdx.intel.com/apd_proj/ppg_lib/epg_masterlib/logical/mstr_discrete/cap/chips/chips.prt!CAP!CAP_0402LF-0.1UF,16V,10%,X7R,A36096-030!CAP!!!F3421!!UART_MUX!!
S!@baseboard_fab2_lib.baseboard_fab2(sch_1):page161_i113@mstr_discrete.cap(chips)!CAP_0402LF-0.1UF,16V,10%,X7R,AA!C1E22!//jf4cfls225.pdx.intel.com/apd_proj/ppg_lib/epg_masterlib/logical/mstr_discrete/cap/chips/chips.prt!CAP!CAP_0402LF-0.1UF,16V,10%,X7R,A36096-030!CAP!!!F3453!!CPUFANS!!
S!@baseboard_fab2_lib.baseboard_fab2(sch_1):page185_i117@mstr_discrete.cap(chips)!CAP_0402LF-0.1UF,16V,10%,X7R,AA!C2P9!//jf4cfls225.pdx.intel.com/apd_proj/ppg_lib/epg_masterlib/logical/mstr_discrete/cap/chips/chips.prt!CAP!CAP_0402LF-0.1UF,16V,10%,X7R,A36096-030!CAP!!!F3268!!M_2!!
S!@baseboard_fab2_lib.baseboard_fab2(sch_1):page95_i92@mstr_discrete.cap(chips)!CAP_0402LF-0.1UF,16V,10%,X7R,AA!C7E3!//jf4cfls225.pdx.intel.com/apd_proj/ppg_lib/epg_masterlib/logical/mstr_discrete/cap/chips/chips.prt!CAP!CAP_0402LF-0.1UF,16V,10%,X7R,A36096-030!CAP!!!F3283!!PROC_SIDEBAND!!
S!@baseboard_fab2_lib.baseboard_fab2(sch_1):page235_i145@mstr_discrete.cap(chips)!CAP_0402LF-0.1UF,16V,10%,X7R,AA!C8A8!//jf4cfls225.pdx.intel.com/apd_proj/ppg_lib/epg_masterlib/logical/mstr_discrete/cap/chips/chips.prt!CAP!CAP_0402LF-0.1UF,16V,10%,X7R,A36096-030!CAP!!!F3272!!PVNN_PCH_STBY!!
S!@baseboard_fab2_lib.baseboard_fab2(sch_1):page236_i35@mstr_discrete.cap(chips)!CAP_0402LF-0.1UF,16V,10%,X7R,AA!C7A40!//jf4cfls225.pdx.intel.com/apd_proj/ppg_lib/epg_masterlib/logical/mstr_discrete/cap/chips/chips.prt!CAP!CAP_0402LF-0.1UF,16V,10%,X7R,A36096-030!CAP!!!F3341!!P1V05_PCH_STBY_VR!!
S!@baseboard_fab2_lib.baseboard_fab2(sch_1):page236_i20@mstr_discrete.cap(chips)!CAP_0402LF-0.1UF,16V,10%,X7R,AA!C7A39!//jf4cfls225.pdx.intel.com/apd_proj/ppg_lib/epg_masterlib/logical/mstr_discrete/cap/chips/chips.prt!CAP!CAP_0402LF-0.1UF,16V,10%,X7R,A36096-030!CAP!!!F3340!!PVNN_PCH_STBY!!
S!@baseboard_fab2_lib.baseboard_fab2(sch_1):page154_i94@mstr_discrete.cap(chips)!CAP_0402LF-0.1UF,16V,10%,X7R,AA!C2T1!//jf4cfls225.pdx.intel.com/apd_proj/ppg_lib/epg_masterlib/logical/mstr_discrete/cap/chips/chips.prt!CAP!CAP_0402LF-0.1UF,16V,10%,X7R,A36096-030!CAP!!!F3373!!SB_BMC_SPI_MUX!!
S!@baseboard_fab2_lib.baseboard_fab2(sch_1):page142_i20@mstr_discrete.cap(chips)!CAP_0402LF-0.1UF,16V,10%,X7R,AA!C8E5!//jf4cfls225.pdx.intel.com/apd_proj/ppg_lib/epg_masterlib/logical/mstr_discrete/cap/chips/chips.prt!CAP!CAP_0402LF-0.1UF,16V,10%,X7R,A36096-030!CAP!!!F3263!!PCIE_WAKE_BUFFER!!
S!@baseboard_fab2_lib.baseboard_fab2(sch_1):page152_i27@mstr_discrete.cap(chips)!CAP_0402LF-0.1UF,16V,10%,X7R,AA!C1U22!//jf4cfls225.pdx.intel.com/apd_proj/ppg_lib/epg_masterlib/logical/mstr_discrete/cap/chips/chips.prt!CAP!CAP_0402LF-0.1UF,16V,10%,X7R,A36096-030!CAP!!!F3390!!PROC_SIDEBAND!!
S!@baseboard_fab2_lib.baseboard_fab2(sch_1):page211_i13@mstr_discrete.cap(chips)!CAP_0402LF-0.1UF,16V,10%,X7R,AA!C3P5!//jf4cfls225.pdx.intel.com/apd_proj/ppg_lib/epg_masterlib/logical/mstr_discrete/cap/chips/chips.prt!CAP!CAP_0402LF-0.1UF,16V,10%,X7R,A36096-030!CAP!!!F3338!!PVCCIO_CPU0!!
S!@baseboard_fab2_lib.baseboard_fab2(sch_1):page212_i38@mstr_discrete.cap(chips)!CAP_0402LF-0.1UF,16V,10%,X7R,AA!C7C11!//jf4cfls225.pdx.intel.com/apd_proj/ppg_lib/epg_masterlib/logical/mstr_discrete/cap/chips/chips.prt!CAP!CAP_0402LF-0.1UF,16V,10%,X7R,A36096-030!CAP!!!F3288!!PVCCIO_CPU0!!
S!@baseboard_fab2_lib.baseboard_fab2(sch_1):page213_i11@mstr_discrete.cap(chips)!CAP_0402LF-0.1UF,16V,10%,X7R,AA!C4D32!//jf4cfls225.pdx.intel.com/apd_proj/ppg_lib/epg_masterlib/logical/mstr_discrete/cap/chips/chips.prt!CAP!CAP_0402LF-0.1UF,16V,10%,X7R,A36096-030!CAP!!!F3316!!PVCCIO_CPU1!!
S!@baseboard_fab2_lib.baseboard_fab2(sch_1):page214_i77@mstr_discrete.cap(chips)!CAP_0402LF-0.1UF,16V,10%,X7R,AA!C4E13!//jf4cfls225.pdx.intel.com/apd_proj/ppg_lib/epg_masterlib/logical/mstr_discrete/cap/chips/chips.prt!CAP!CAP_0402LF-0.1UF,16V,10%,X7R,A36096-030!CAP!!!F3312!!PVCCIO_CPU1!!
S!@baseboard_fab2_lib.baseboard_fab2(sch_1):page211_i22@mstr_discrete.cap(chips)!CAP_0402LF-0.1UF,16V,10%,X7R,AA!C3P7!//jf4cfls225.pdx.intel.com/apd_proj/ppg_lib/epg_masterlib/logical/mstr_discrete/cap/chips/chips.prt!CAP!CAP_0402LF-0.1UF,16V,10%,X7R,A36096-030!CAP!!!F3337!!PVCCIO_CPU0!!
S!@baseboard_fab2_lib.baseboard_fab2(sch_1):page213_i35@mstr_discrete.cap(chips)!CAP_0402LF-0.1UF,16V,10%,X7R,AA!C4D38!//jf4cfls225.pdx.intel.com/apd_proj/ppg_lib/epg_masterlib/logical/mstr_discrete/cap/chips/chips.prt!CAP!CAP_0402LF-0.1UF,16V,10%,X7R,A36096-030!CAP!!!F3314!!PVCCIO_CPU1!!
S!@baseboard_fab2_lib.baseboard_fab2(sch_1):page161_i90@mstr_discrete.cap(chips)!CAP_0402LF-0.1UF,16V,10%,X7R,AA!C2U27!//jf4cfls225.pdx.intel.com/apd_proj/ppg_lib/epg_masterlib/logical/mstr_discrete/cap/chips/chips.prt!CAP!CAP_0402LF-0.1UF,16V,10%,X7R,A36096-030!CAP!!!F3346!!CPU_FANS!!
S!@baseboard_fab2_lib.baseboard_fab2(sch_1):page161_i93@mstr_discrete.cap(chips)!CAP_0402LF-0.1UF,16V,10%,X7R,AA!C2U28!//jf4cfls225.pdx.intel.com/apd_proj/ppg_lib/epg_masterlib/logical/mstr_discrete/cap/chips/chips.prt!CAP!CAP_0402LF-0.1UF,16V,10%,X7R,A36096-030!CAP!!!F3345!!CPU_FANS!!
S!@baseboard_fab2_lib.baseboard_fab2(sch_1):page165_i61@mstr_discrete.cap(chips)!CAP_0402LF-0.1UF,16V,10%,X7R,AA!C9G19!//jf4cfls225.pdx.intel.com/apd_proj/ppg_lib/epg_masterlib/logical/mstr_discrete/cap/chips/chips.prt!CAP!CAP_0402LF-0.1UF,16V,10%,X7R,A36096-030!CAP!!!F3240!!HEC_VOLT_MONITOR!!
S!@baseboard_fab2_lib.baseboard_fab2(sch_1):page203_i46@mstr_discrete.cap(chips)!CAP_0402LF-0.1UF,16V,10%,X7R,AA!C4D35!//jf4cfls225.pdx.intel.com/apd_proj/ppg_lib/epg_masterlib/logical/mstr_discrete/cap/chips/chips.prt!CAP!CAP_0402LF-0.1UF,16V,10%,X7R,A36096-030!CAP!!!F3315!!PVCCIN_CPU0_PWR_VR!!
S!@baseboard_fab2_lib.baseboard_fab2(sch_1):page203_i52@mstr_discrete.cap(chips)!CAP_0402LF-0.1UF,16V,10%,X7R,AA!C4D11!//jf4cfls225.pdx.intel.com/apd_proj/ppg_lib/epg_masterlib/logical/mstr_discrete/cap/chips/chips.prt!CAP!CAP_0402LF-0.1UF,16V,10%,X7R,A36096-030!CAP!!!F3321!!PVCCIN_CPU0_PWR_VR!!
S!@baseboard_fab2_lib.baseboard_fab2(sch_1):page151_i86@mstr_discrete.cap(chips)!CAP_0402LF-0.1UF,16V,10%,X7R,AA!C1U10!//jf4cfls225.pdx.intel.com/apd_proj/ppg_lib/epg_masterlib/logical/mstr_discrete/cap/chips/chips.prt!CAP!CAP_0402LF-0.1UF,16V,10%,X7R,A36096-030!CAP!!!F3396!!BMC_MEMORY!!
S!@baseboard_fab2_lib.baseboard_fab2(sch_1):page151_i84@mstr_discrete.cap(chips)!CAP_0402LF-0.1UF,16V,10%,X7R,AA!C1U14!//jf4cfls225.pdx.intel.com/apd_proj/ppg_lib/epg_masterlib/logical/mstr_discrete/cap/chips/chips.prt!CAP!CAP_0402LF-0.1UF,16V,10%,X7R,A36096-030!CAP!!!F3393!!BMC_MEMORY!!
S!@baseboard_fab2_lib.baseboard_fab2(sch_1):page151_i83@mstr_discrete.cap(chips)!CAP_0402LF-0.1UF,16V,10%,X7R,AA!C1T54!//jf4cfls225.pdx.intel.com/apd_proj/ppg_lib/epg_masterlib/logical/mstr_discrete/cap/chips/chips.prt!CAP!CAP_0402LF-0.1UF,16V,10%,X7R,A36096-030!CAP!!!F3401!!BMC_MEMORY!!
S!@baseboard_fab2_lib.baseboard_fab2(sch_1):page151_i82@mstr_discrete.cap(chips)!CAP_0402LF-0.1UF,16V,10%,X7R,AA!C1T53!//jf4cfls225.pdx.intel.com/apd_proj/ppg_lib/epg_masterlib/logical/mstr_discrete/cap/chips/chips.prt!CAP!CAP_0402LF-0.1UF,16V,10%,X7R,A36096-030!CAP!!!F3402!!BMC_MEMORY!!
S!@baseboard_fab2_lib.baseboard_fab2(sch_1):page151_i81@mstr_discrete.cap(chips)!CAP_0402LF-0.1UF,16V,10%,X7R,AA!C1U16!//jf4cfls225.pdx.intel.com/apd_proj/ppg_lib/epg_masterlib/logical/mstr_discrete/cap/chips/chips.prt!CAP!CAP_0402LF-0.1UF,16V,10%,X7R,A36096-030!CAP!!!F3391!!BMC_MEMORY!!
S!@baseboard_fab2_lib.baseboard_fab2(sch_1):page151_i80@mstr_discrete.cap(chips)!CAP_0402LF-0.1UF,16V,10%,X7R,AA!C1T33!//jf4cfls225.pdx.intel.com/apd_proj/ppg_lib/epg_masterlib/logical/mstr_discrete/cap/chips/chips.prt!CAP!CAP_0402LF-0.1UF,16V,10%,X7R,A36096-030!CAP!!!F3412!!BMC_MEMORY!!
S!@baseboard_fab2_lib.baseboard_fab2(sch_1):page151_i76@mstr_discrete.cap(chips)!CAP_0402LF-0.1UF,16V,10%,X7R,AA!C1T40!//jf4cfls225.pdx.intel.com/apd_proj/ppg_lib/epg_masterlib/logical/mstr_discrete/cap/chips/chips.prt!CAP!CAP_0402LF-0.1UF,16V,10%,X7R,A36096-030!CAP!!!F3409!!BMC_MEMORY!!
S!@baseboard_fab2_lib.baseboard_fab2(sch_1):page151_i79@mstr_discrete.cap(chips)!CAP_0402LF-0.1UF,16V,10%,X7R,AA!C1U13!//jf4cfls225.pdx.intel.com/apd_proj/ppg_lib/epg_masterlib/logical/mstr_discrete/cap/chips/chips.prt!CAP!CAP_0402LF-0.1UF,16V,10%,X7R,A36096-030!CAP!!!F3394!!BMC_MEMORY!!
S!@baseboard_fab2_lib.baseboard_fab2(sch_1):page151_i78@mstr_discrete.cap(chips)!CAP_0402LF-0.1UF,16V,10%,X7R,AA!C1U15!//jf4cfls225.pdx.intel.com/apd_proj/ppg_lib/epg_masterlib/logical/mstr_discrete/cap/chips/chips.prt!CAP!CAP_0402LF-0.1UF,16V,10%,X7R,A36096-030!CAP!!!F3392!!BMC_MEMORY!!
S!@baseboard_fab2_lib.baseboard_fab2(sch_1):page151_i58@mstr_discrete.cap(chips)!CAP_0402LF-0.1UF,16V,10%,X7R,AA!C1T48!//jf4cfls225.pdx.intel.com/apd_proj/ppg_lib/epg_masterlib/logical/mstr_discrete/cap/chips/chips.prt!CAP!CAP_0402LF-0.1UF,16V,10%,X7R,A36096-030!CAP!!!F3405!!BMC_MEMORY!!
S!@baseboard_fab2_lib.baseboard_fab2(sch_1):page161_i4@mstr_discrete.cap(chips)!CAP_0402LF-0.1UF,16V,10%,X7R,AA!C1E20!//jf4cfls225.pdx.intel.com/apd_proj/ppg_lib/epg_masterlib/logical/mstr_discrete/cap/chips/chips.prt!CAP!CAP_0402LF-0.1UF,16V,10%,X7R,A36096-030!CAP!!!F3454!!CPU_FANS!!
S!@baseboard_fab2_lib.baseboard_fab2(sch_1):page161_i26@mstr_discrete.cap(chips)!CAP_0402LF-0.1UF,16V,10%,X7R,AA!C9M5!//jf4cfls225.pdx.intel.com/apd_proj/ppg_lib/epg_masterlib/logical/mstr_discrete/cap/chips/chips.prt!CAP!CAP_0402LF-0.1UF,16V,10%,X7R,A36096-030!CAP!!!F3239!!CPU_FANS!!
S!@baseboard_fab2_lib.baseboard_fab2(sch_1):page198_i52@mstr_discrete.cap(chips)!CAP_0402LF-0.1UF,16V,10%,X7R,AA!C7E5!//jf4cfls225.pdx.intel.com/apd_proj/ppg_lib/epg_masterlib/logical/mstr_discrete/cap/chips/chips.prt!CAP!CAP_0402LF-0.1UF,16V,10%,X7R,A36096-030!CAP!!!F3281!!P12V_PWR_SWITCH!!
S!@baseboard_fab2_lib.baseboard_fab2(sch_1):page198_i49@mstr_discrete.cap(chips)!CAP_0402LF-0.1UF,16V,10%,X7R,AA!C7E9!//jf4cfls225.pdx.intel.com/apd_proj/ppg_lib/epg_masterlib/logical/mstr_discrete/cap/chips/chips.prt!CAP!CAP_0402LF-0.1UF,16V,10%,X7R,A36096-030!CAP!!!F3279!!P12V_PWR_SWITCH!!
S!@baseboard_fab2_lib.baseboard_fab2(sch_1):page198_i43@mstr_discrete.cap(chips)!CAP_0402LF-0.1UF,16V,10%,X7R,AA!C2T36!//jf4cfls225.pdx.intel.com/apd_proj/ppg_lib/epg_masterlib/logical/mstr_discrete/cap/chips/chips.prt!CAP!CAP_0402LF-0.1UF,16V,10%,X7R,A36096-030!CAP!!!F3354!!P3V3_PWR_SWITCH!!
S!@baseboard_fab2_lib.baseboard_fab2(sch_1):page198_i46@mstr_discrete.cap(chips)!CAP_0402LF-0.1UF,16V,10%,X7R,AA!C2U19!//jf4cfls225.pdx.intel.com/apd_proj/ppg_lib/epg_masterlib/logical/mstr_discrete/cap/chips/chips.prt!CAP!CAP_0402LF-0.1UF,16V,10%,X7R,A36096-030!CAP!!!F3353!!P3V3_PWR_SWITCH!!
S!@baseboard_fab2_lib.baseboard_fab2(sch_1):page198_i37@mstr_discrete.cap(chips)!CAP_0402LF-0.1UF,16V,10%,X7R,AA!C8B5!//jf4cfls225.pdx.intel.com/apd_proj/ppg_lib/epg_masterlib/logical/mstr_discrete/cap/chips/chips.prt!CAP!CAP_0402LF-0.1UF,16V,10%,X7R,A36096-030!CAP!!!F3271!!P5V_PWR_SWITCH!!
S!@baseboard_fab2_lib.baseboard_fab2(sch_1):page198_i41@mstr_discrete.cap(chips)!CAP_0402LF-0.1UF,16V,10%,X7R,AA!C8B7!//jf4cfls225.pdx.intel.com/apd_proj/ppg_lib/epg_masterlib/logical/mstr_discrete/cap/chips/chips.prt!CAP!CAP_0402LF-0.1UF,16V,10%,X7R,A36096-030!CAP!!!F3270!!P5V_PWR_SWITCH!!
S!@baseboard_fab2_lib.baseboard_fab2(sch_1):page198_i24@mstr_discrete.cap(chips)!CAP_0402LF-0.1UF,16V,10%,X7R,AA!C8F17!//jf4cfls225.pdx.intel.com/apd_proj/ppg_lib/epg_masterlib/logical/mstr_discrete/cap/chips/chips.prt!CAP!CAP_0402LF-0.1UF,16V,10%,X7R,A36096-030!CAP!!!F3259!!P3V3_PWR_SWITCH!!
S!@baseboard_fab2_lib.baseboard_fab2(sch_1):page198_i28@mstr_discrete.cap(chips)!CAP_0402LF-0.1UF,16V,10%,X7R,AA!C8E19!//jf4cfls225.pdx.intel.com/apd_proj/ppg_lib/epg_masterlib/logical/mstr_discrete/cap/chips/chips.prt!CAP!CAP_0402LF-0.1UF,16V,10%,X7R,A36096-030!CAP!!!F3280!!P12V_PWR_SWITCH!!
S!@baseboard_fab2_lib.baseboard_fab2(sch_1):page198_i26@mstr_discrete.cap(chips)!CAP_0402LF-0.1UF,16V,10%,X7R,AA!C8B8!//jf4cfls225.pdx.intel.com/apd_proj/ppg_lib/epg_masterlib/logical/mstr_discrete/cap/chips/chips.prt!CAP!CAP_0402LF-0.1UF,16V,10%,X7R,A36096-030!CAP!!!F3269!!P5V_PWR_SWITCH!!
S!@baseboard_fab2_lib.baseboard_fab2(sch_1):page130_i16@mstr_discrete.cap(chips)!CAP_0402LF-0.1UF,16V,10%,X7R,AA!C3N29!//jf4cfls225.pdx.intel.com/apd_proj/ppg_lib/epg_masterlib/logical/mstr_discrete/cap/chips/chips.prt!CAP!CAP_0402LF-0.1UF,16V,10%,X7R,A36096-030!CAP!!!F3339!!SB_DECOUPLING!!
S!@baseboard_fab2_lib.baseboard_fab2(sch_1):page149_i147@mstr_discrete.cap(chips)!CAP_0402LF-0.1UF,16V,10%,X7R,AA!C1T23!//jf4cfls225.pdx.intel.com/apd_proj/ppg_lib/epg_masterlib/logical/mstr_discrete/cap/chips/chips.prt!CAP!CAP_0402LF-0.1UF,16V,10%,X7R,A36096-030!CAP!!!F3417!!BMC!!
S!@baseboard_fab2_lib.baseboard_fab2(sch_1):page158_i97@mstr_discrete.cap(chips)!CAP_0402LF-0.1UF,16V,10%,X7R,AA!C1T11!//jf4cfls225.pdx.intel.com/apd_proj/ppg_lib/epg_masterlib/logical/mstr_discrete/cap/chips/chips.prt!CAP!CAP_0402LF-0.1UF,16V,10%,X7R,A36096-030!CAP!!!F3420!!UART_MUX!!
S!@baseboard_fab2_lib.baseboard_fab2(sch_1):page176_i108@mstr_discrete.cap(chips)!CAP_0402LF-0.1UF,16V,10%,X7R,AA!C1M38!//jf4cfls225.pdx.intel.com/apd_proj/ppg_lib/epg_masterlib/logical/mstr_discrete/cap/chips/chips.prt!CAP!CAP_0402LF-0.1UF,16V,10%,X7R,A36096-030!CAP!!!F3252!!USB_REAR!!
S!@baseboard_fab2_lib.baseboard_fab2(sch_1):page141_i47@mstr_discrete.cap(chips)!CAP_0402LF-0.1UF,16V,10%,X7R,AA!C9G6!//jf4cfls225.pdx.intel.com/apd_proj/ppg_lib/epg_masterlib/logical/mstr_discrete/cap/chips/chips.prt!CAP!CAP_0402LF-0.1UF,16V,10%,X7R,A36096-030!CAP!!!F3242!!NIC_SPRV!!
S!@baseboard_fab2_lib.baseboard_fab2(sch_1):page141_i46@mstr_discrete.cap(chips)!CAP_0402LF-0.1UF,16V,10%,X7R,AA!C9G4!//jf4cfls225.pdx.intel.com/apd_proj/ppg_lib/epg_masterlib/logical/mstr_discrete/cap/chips/chips.prt!CAP!CAP_0402LF-0.1UF,16V,10%,X7R,A36096-030!CAP!!!F3243!!NIC_SPRV!!
S!@baseboard_fab2_lib.baseboard_fab2(sch_1):page141_i33@mstr_discrete.cap(chips)!CAP_0402LF-0.1UF,16V,10%,X7R,AA!C9G7!//jf4cfls225.pdx.intel.com/apd_proj/ppg_lib/epg_masterlib/logical/mstr_discrete/cap/chips/chips.prt!CAP!CAP_0402LF-0.1UF,16V,10%,X7R,A36096-030!CAP!!!F3241!!NIC_SPRV!!
S!@baseboard_fab2_lib.baseboard_fab2(sch_1):page167_i39@mstr_discrete.cap(chips)!CAP_0402LF-0.1UF,16V,10%,X7R,AA!C9B7!//jf4cfls225.pdx.intel.com/apd_proj/ppg_lib/epg_masterlib/logical/mstr_discrete/cap/chips/chips.prt!CAP!CAP_0402LF-0.1UF,16V,10%,X7R,A36096-030!CAP!!!F3251!!TEMP_SENSORS!!
S!@baseboard_fab2_lib.baseboard_fab2(sch_1):page167_i41@mstr_discrete.cap(chips)!CAP_0402LF-0.1UF,16V,10%,X7R,AA!C9R14!//jf4cfls225.pdx.intel.com/apd_proj/ppg_lib/epg_masterlib/logical/mstr_discrete/cap/chips/chips.prt!CAP!CAP_0402LF-0.1UF,16V,10%,X7R,A36096-030!CAP!!!F3230!!TEMP_SENSORS!!
S!@baseboard_fab2_lib.baseboard_fab2(sch_1):page167_i42@mstr_discrete.cap(chips)!CAP_0402LF-0.1UF,16V,10%,X7R,AA!C9R13!//jf4cfls225.pdx.intel.com/apd_proj/ppg_lib/epg_masterlib/logical/mstr_discrete/cap/chips/chips.prt!CAP!CAP_0402LF-0.1UF,16V,10%,X7R,A36096-030!CAP!!!F3231!!TEMP_SENSORS!!
S!@baseboard_fab2_lib.baseboard_fab2(sch_1):page218_i31@mstr_discrete.cap(chips)!CAP_0402LF-0.1UF,16V,10%,X7R,AA!C7A38!//jf4cfls225.pdx.intel.com/apd_proj/ppg_lib/epg_masterlib/logical/mstr_discrete/cap/chips/chips.prt!CAP!CAP_0402LF-0.1UF,16V,10%,X7R,A36096-030!CAP!!!F3291!!VDDQ_DEF_PWR_VR!!
S!@baseboard_fab2_lib.baseboard_fab2(sch_1):page218_i23@mstr_discrete.cap(chips)!CAP_0402LF-0.1UF,16V,10%,X7R,AA!C7B2!//jf4cfls225.pdx.intel.com/apd_proj/ppg_lib/epg_masterlib/logical/mstr_discrete/cap/chips/chips.prt!CAP!CAP_0402LF-0.1UF,16V,10%,X7R,A36096-030!CAP!!!F3290!!VDDQ_DEF_PWR_VR!!
S!@baseboard_fab2_lib.baseboard_fab2(sch_1):page223_i27@mstr_discrete.cap(chips)!CAP_0402LF-0.1UF,16V,10%,X7R,AA!C1G25!//jf4cfls225.pdx.intel.com/apd_proj/ppg_lib/epg_masterlib/logical/mstr_discrete/cap/chips/chips.prt!CAP!CAP_0402LF-0.1UF,16V,10%,X7R,A36096-030!CAP!!!F3449!!VDDQ_GHJ_PWR_VR!!
S!@baseboard_fab2_lib.baseboard_fab2(sch_1):page223_i44@mstr_discrete.cap(chips)!CAP_0402LF-0.1UF,16V,10%,X7R,AA!C1G22!//jf4cfls225.pdx.intel.com/apd_proj/ppg_lib/epg_masterlib/logical/mstr_discrete/cap/chips/chips.prt!CAP!CAP_0402LF-0.1UF,16V,10%,X7R,A36096-030!CAP!!!F3450!!VDDQ_GHJ_PWR_VR!!
S!@baseboard_fab2_lib.baseboard_fab2(sch_1):page226_i27@mstr_discrete.cap(chips)!CAP_0402LF-0.1UF,16V,10%,X7R,AA!C1B5!//jf4cfls225.pdx.intel.com/apd_proj/ppg_lib/epg_masterlib/logical/mstr_discrete/cap/chips/chips.prt!CAP!CAP_0402LF-0.1UF,16V,10%,X7R,A36096-030!CAP!!!F3472!!VDDQ_KLM_PWR_VR!!
S!@baseboard_fab2_lib.baseboard_fab2(sch_1):page226_i44@mstr_discrete.cap(chips)!CAP_0402LF-0.1UF,16V,10%,X7R,AA!C1B2!//jf4cfls225.pdx.intel.com/apd_proj/ppg_lib/epg_masterlib/logical/mstr_discrete/cap/chips/chips.prt!CAP!CAP_0402LF-0.1UF,16V,10%,X7R,A36096-030!CAP!!!F3473!!VDDQ_KLM_PWR_VR!!
S!@baseboard_fab2_lib.baseboard_fab2(sch_1):page139_i90@mstr_discrete.cap(chips)!CAP_0402LF-0.1UF,16V,10%,X7R,AA!C2M24!//jf4cfls225.pdx.intel.com/apd_proj/ppg_lib/epg_masterlib/logical/mstr_discrete/cap/chips/chips.prt!CAP!CAP_0402LF-0.1UF,16V,10%,X7R,A36096-030!CAP!!!F3387!!NIC_SPRV!!
S!@baseboard_fab2_lib.baseboard_fab2(sch_1):page139_i89@mstr_discrete.cap(chips)!CAP_0402LF-0.1UF,16V,10%,X7R,AA!C2M23!//jf4cfls225.pdx.intel.com/apd_proj/ppg_lib/epg_masterlib/logical/mstr_discrete/cap/chips/chips.prt!CAP!CAP_0402LF-0.1UF,16V,10%,X7R,A36096-030!CAP!!!F3388!!NIC_SPRV!!
S!@baseboard_fab2_lib.baseboard_fab2(sch_1):page139_i88@mstr_discrete.cap(chips)!CAP_0402LF-0.1UF,16V,10%,X7R,AA!C9E4!//jf4cfls225.pdx.intel.com/apd_proj/ppg_lib/epg_masterlib/logical/mstr_discrete/cap/chips/chips.prt!CAP!CAP_0402LF-0.1UF,16V,10%,X7R,A36096-030!CAP!!!F3250!!NIC_SPRV!!
S!@baseboard_fab2_lib.baseboard_fab2(sch_1):page139_i87@mstr_discrete.cap(chips)!CAP_0402LF-0.1UF,16V,10%,X7R,AA!C9E5!//jf4cfls225.pdx.intel.com/apd_proj/ppg_lib/epg_masterlib/logical/mstr_discrete/cap/chips/chips.prt!CAP!CAP_0402LF-0.1UF,16V,10%,X7R,A36096-030!CAP!!!F3249!!NIC_SPRV!!
S!@baseboard_fab2_lib.baseboard_fab2(sch_1):page209_i17@mstr_discrete.cap(chips)!CAP_0402LF-0.1UF,16V,10%,X7R,AA!C1C25!//jf4cfls225.pdx.intel.com/apd_proj/ppg_lib/epg_masterlib/logical/mstr_discrete/cap/chips/chips.prt!CAP!CAP_0402LF-0.1UF,16V,10%,X7R,A36096-030!CAP!!!F3466!!PVCCIN_CPU1_PWR_VR!!
S!@baseboard_fab2_lib.baseboard_fab2(sch_1):page93_i95@mstr_discrete.cap(chips)!CAP_0402LF-0.1UF,16V,10%,X7R,AA!C2T32!//jf4cfls225.pdx.intel.com/apd_proj/ppg_lib/epg_masterlib/logical/mstr_discrete/cap/chips/chips.prt!CAP!CAP_0402LF-0.1UF,16V,10%,X7R,A36096-030!CAP!!!F3357!!PROC_SIDEBAND!!
S!@baseboard_fab2_lib.baseboard_fab2(sch_1):page101_i112@mstr_discrete.cap(chips)!CAP_0402LF-0.1UF,16V,10%,X7R,AA!C2T17!//jf4cfls225.pdx.intel.com/apd_proj/ppg_lib/epg_masterlib/logical/mstr_discrete/cap/chips/chips.prt!CAP!CAP_0402LF-0.1UF,16V,10%,X7R,A36096-030!CAP!!!F3364!!SYS_CLOCK!!
S!@baseboard_fab2_lib.baseboard_fab2(sch_1):page101_i111@mstr_discrete.cap(chips)!CAP_0402LF-0.1UF,16V,10%,X7R,AA!C2T25!//jf4cfls225.pdx.intel.com/apd_proj/ppg_lib/epg_masterlib/logical/mstr_discrete/cap/chips/chips.prt!CAP!CAP_0402LF-0.1UF,16V,10%,X7R,A36096-030!CAP!!!F3361!!SYS_CLOCK!!
S!@baseboard_fab2_lib.baseboard_fab2(sch_1):page101_i110@mstr_discrete.cap(chips)!CAP_0402LF-0.1UF,16V,10%,X7R,AA!C2T30!//jf4cfls225.pdx.intel.com/apd_proj/ppg_lib/epg_masterlib/logical/mstr_discrete/cap/chips/chips.prt!CAP!CAP_0402LF-0.1UF,16V,10%,X7R,A36096-030!CAP!!!F3358!!SYS_CLOCK!!
S!@baseboard_fab2_lib.baseboard_fab2(sch_1):page140_i3@mstr_discrete.cap(chips)!CAP_0402LF-0.1UF,16V,10%,X7R,AA!C1R25!//jf4cfls225.pdx.intel.com/apd_proj/ppg_lib/epg_masterlib/logical/mstr_discrete/cap/chips/chips.prt!CAP!CAP_0402LF-0.1UF,16V,10%,X7R,A36096-030!CAP!!!F3430!!NIC_SPRV!!
S!@baseboard_fab2_lib.baseboard_fab2(sch_1):page139_i143@mstr_discrete.cap(chips)!CAP_0402LF-0.1UF,16V,10%,X7R,AA!C1R20!//jf4cfls225.pdx.intel.com/apd_proj/ppg_lib/epg_masterlib/logical/mstr_discrete/cap/chips/chips.prt!CAP!CAP_0402LF-0.1UF,16V,10%,X7R,A36096-030!CAP!!!F3433!!NIC_SPRV!!
S!@baseboard_fab2_lib.baseboard_fab2(sch_1):page139_i144@mstr_discrete.cap(chips)!CAP_0402LF-0.1UF,16V,10%,X7R,AA!C1T3!//jf4cfls225.pdx.intel.com/apd_proj/ppg_lib/epg_masterlib/logical/mstr_discrete/cap/chips/chips.prt!CAP!CAP_0402LF-0.1UF,16V,10%,X7R,A36096-030!CAP!!!F3424!!NIC_SPRV!!
S!@baseboard_fab2_lib.baseboard_fab2(sch_1):page139_i145@mstr_discrete.cap(chips)!CAP_0402LF-0.1UF,16V,10%,X7R,AA!C1R14!//jf4cfls225.pdx.intel.com/apd_proj/ppg_lib/epg_masterlib/logical/mstr_discrete/cap/chips/chips.prt!CAP!CAP_0402LF-0.1UF,16V,10%,X7R,A36096-030!CAP!!!F3437!!NIC_SPRV!!
S!@baseboard_fab2_lib.baseboard_fab2(sch_1):page139_i146@mstr_discrete.cap(chips)!CAP_0402LF-0.1UF,16V,10%,X7R,AA!C1R21!//jf4cfls225.pdx.intel.com/apd_proj/ppg_lib/epg_masterlib/logical/mstr_discrete/cap/chips/chips.prt!CAP!CAP_0402LF-0.1UF,16V,10%,X7R,A36096-030!CAP!!!F3432!!NIC_SPRV!!
S!@baseboard_fab2_lib.baseboard_fab2(sch_1):page139_i152@mstr_discrete.cap(chips)!CAP_0402LF-0.1UF,16V,10%,X7R,AA!C1R31!//jf4cfls225.pdx.intel.com/apd_proj/ppg_lib/epg_masterlib/logical/mstr_discrete/cap/chips/chips.prt!CAP!CAP_0402LF-0.1UF,16V,10%,X7R,A36096-030!CAP!!!F3425!!NIC_SPRV!!
S!@baseboard_fab2_lib.baseboard_fab2(sch_1):page139_i151@mstr_discrete.cap(chips)!CAP_0402LF-0.1UF,16V,10%,X7R,AA!C1R19!//jf4cfls225.pdx.intel.com/apd_proj/ppg_lib/epg_masterlib/logical/mstr_discrete/cap/chips/chips.prt!CAP!CAP_0402LF-0.1UF,16V,10%,X7R,A36096-030!CAP!!!F3434!!NIC_SPRV!!
S!@baseboard_fab2_lib.baseboard_fab2(sch_1):page139_i150@mstr_discrete.cap(chips)!CAP_0402LF-0.1UF,16V,10%,X7R,AA!C1R29!//jf4cfls225.pdx.intel.com/apd_proj/ppg_lib/epg_masterlib/logical/mstr_discrete/cap/chips/chips.prt!CAP!CAP_0402LF-0.1UF,16V,10%,X7R,A36096-030!CAP!!!F3426!!NIC_SPRV!!
S!@baseboard_fab2_lib.baseboard_fab2(sch_1):page139_i149@mstr_discrete.cap(chips)!CAP_0402LF-0.1UF,16V,10%,X7R,AA!C1R26!//jf4cfls225.pdx.intel.com/apd_proj/ppg_lib/epg_masterlib/logical/mstr_discrete/cap/chips/chips.prt!CAP!CAP_0402LF-0.1UF,16V,10%,X7R,A36096-030!CAP!!!F3429!!NIC_SPRV!!
S!@baseboard_fab2_lib.baseboard_fab2(sch_1):page139_i160@mstr_discrete.cap(chips)!CAP_0402LF-0.1UF,16V,10%,X7R,AA!C1R15!//jf4cfls225.pdx.intel.com/apd_proj/ppg_lib/epg_masterlib/logical/mstr_discrete/cap/chips/chips.prt!CAP!CAP_0402LF-0.1UF,16V,10%,X7R,A36096-030!CAP!!!F3436!!NIC_SPRV!!
S!@baseboard_fab2_lib.baseboard_fab2(sch_1):page139_i159@mstr_discrete.cap(chips)!CAP_0402LF-0.1UF,16V,10%,X7R,AA!C1R24!//jf4cfls225.pdx.intel.com/apd_proj/ppg_lib/epg_masterlib/logical/mstr_discrete/cap/chips/chips.prt!CAP!CAP_0402LF-0.1UF,16V,10%,X7R,A36096-030!CAP!!!F3431!!NIC_SPRV!!
S!@baseboard_fab2_lib.baseboard_fab2(sch_1):page139_i158@mstr_discrete.cap(chips)!CAP_0402LF-0.1UF,16V,10%,X7R,AA!C1T5!//jf4cfls225.pdx.intel.com/apd_proj/ppg_lib/epg_masterlib/logical/mstr_discrete/cap/chips/chips.prt!CAP!CAP_0402LF-0.1UF,16V,10%,X7R,A36096-030!CAP!!!F3423!!NIC_SPRV!!
S!@baseboard_fab2_lib.baseboard_fab2(sch_1):page139_i157@mstr_discrete.cap(chips)!CAP_0402LF-0.1UF,16V,10%,X7R,AA!C1R18!//jf4cfls225.pdx.intel.com/apd_proj/ppg_lib/epg_masterlib/logical/mstr_discrete/cap/chips/chips.prt!CAP!CAP_0402LF-0.1UF,16V,10%,X7R,A36096-030!CAP!!!F3435!!NIC_SPRV!!
S!@baseboard_fab2_lib.baseboard_fab2(sch_1):page176_i63@mstr_discrete.cap(chips)!CAP_0402LF-0.1UF,16V,10%,X7R,AA!C1M2!//jf4cfls225.pdx.intel.com/apd_proj/ppg_lib/epg_masterlib/logical/mstr_discrete/cap/chips/chips.prt!CAP!CAP_0402LF-0.1UF,16V,10%,X7R,A36096-030!CAP!!!F3442!!USB_REAR!!
S!@baseboard_fab2_lib.baseboard_fab2(sch_1):page176_i64@mstr_discrete.cap(chips)!CAP_0402LF-0.1UF,16V,10%,X7R,AA!C1M1!//jf4cfls225.pdx.intel.com/apd_proj/ppg_lib/epg_masterlib/logical/mstr_discrete/cap/chips/chips.prt!CAP!CAP_0402LF-0.1UF,16V,10%,X7R,A36096-030!CAP!!!F3443!!USB_REAR!!
S!@baseboard_fab2_lib.baseboard_fab2(sch_1):page186_i270@mstr_discrete.cap(chips)!CAP_0402LF-0.1UF,16V,10%,X7R,AA!C1M20!//jf4cfls225.pdx.intel.com/apd_proj/ppg_lib/epg_masterlib/logical/mstr_discrete/cap/chips/chips.prt!CAP!CAP_0402LF-0.1UF,16V,10%,X7R,A36096-030!CAP!!!F3441!!IO_SLOT!!
S!@baseboard_fab2_lib.baseboard_fab2(sch_1):page149_i105@mstr_discrete.cap(chips)!CAP_0402LF-0.1UF,16V,10%,X7R,AA!C9F14!//jf4cfls225.pdx.intel.com/apd_proj/ppg_lib/epg_masterlib/logical/mstr_discrete/cap/chips/chips.prt!CAP!CAP_0402LF-0.1UF,16V,10%,X7R,A36096-030!CAP!!!F3245!!BMC!!
S!@baseboard_fab2_lib.baseboard_fab2(sch_1):page99_i41@mstr_discrete.cap(chips)!CAP_0402LF-0.1UF,16V,10%,X7R,AA!C4G25!//jf4cfls225.pdx.intel.com/apd_proj/ppg_lib/epg_masterlib/logical/mstr_discrete/cap/chips/chips.prt!CAP!CAP_0402LF-0.1UF,16V,10%,X7R,A36096-030!CAP!!!F3308!!MEM!!
S!@baseboard_fab2_lib.baseboard_fab2(sch_1):page99_i47@mstr_discrete.cap(chips)!CAP_0402LF-0.1UF,16V,10%,X7R,AA!C3B4!//jf4cfls225.pdx.intel.com/apd_proj/ppg_lib/epg_masterlib/logical/mstr_discrete/cap/chips/chips.prt!CAP!CAP_0402LF-0.1UF,16V,10%,X7R,A36096-030!CAP!!!F3344!!MEM!!
S!@baseboard_fab2_lib.baseboard_fab2(sch_1):page99_i53@mstr_discrete.cap(chips)!CAP_0402LF-0.1UF,16V,10%,X7R,AA!C3B5!//jf4cfls225.pdx.intel.com/apd_proj/ppg_lib/epg_masterlib/logical/mstr_discrete/cap/chips/chips.prt!CAP!CAP_0402LF-0.1UF,16V,10%,X7R,A36096-030!CAP!!!F3343!!MEM!!
S!@baseboard_fab2_lib.baseboard_fab2(sch_1):page111_i59@mstr_discrete.cap(chips)!CAP_0402LF-0.1UF,16V,10%,X7R,AA!C9A4!//jf4cfls225.pdx.intel.com/apd_proj/ppg_lib/epg_masterlib/logical/mstr_discrete/cap/chips/chips.prt!CAP!CAP_0402LF-0.1UF,16V,10%,X7R,A36096-030!CAP!!!F3254!!DEBUG!!
S!@baseboard_fab2_lib.baseboard_fab2(sch_1):page111_i10@mstr_discrete.cap(chips)!CAP_0402LF-0.1UF,16V,10%,X7R,AA!C9A2!//jf4cfls225.pdx.intel.com/apd_proj/ppg_lib/epg_masterlib/logical/mstr_discrete/cap/chips/chips.prt!CAP!CAP_0402LF-0.1UF,16V,10%,X7R,A36096-030!CAP!!!F3256!!DEBUG!!
S!@baseboard_fab2_lib.baseboard_fab2(sch_1):page111_i12@mstr_discrete.cap(chips)!CAP_0402LF-0.1UF,16V,10%,X7R,AA!C9A5!//jf4cfls225.pdx.intel.com/apd_proj/ppg_lib/epg_masterlib/logical/mstr_discrete/cap/chips/chips.prt!CAP!CAP_0402LF-0.1UF,16V,10%,X7R,A36096-030!CAP!!!F3253!!DEBUG!!
S!@baseboard_fab2_lib.baseboard_fab2(sch_1):page111_i14@mstr_discrete.cap(chips)!CAP_0402LF-0.1UF,16V,10%,X7R,AA!C1L8!//jf4cfls225.pdx.intel.com/apd_proj/ppg_lib/epg_masterlib/logical/mstr_discrete/cap/chips/chips.prt!CAP!CAP_0402LF-0.1UF,16V,10%,X7R,A36096-030!CAP!!!F3447!!DEBUG!!
S!@baseboard_fab2_lib.baseboard_fab2(sch_1):page108_i5@mstr_discrete.cap(chips)!CAP_0402LF-0.1UF,16V,10%,X7R,AA!C2U21!//jf4cfls225.pdx.intel.com/apd_proj/ppg_lib/epg_masterlib/logical/mstr_discrete/cap/chips/chips.prt!CAP!CAP_0402LF-0.1UF,16V,10%,X7R,A36096-030!CAP!!!F3351!!IO_SLOT!!
S!@baseboard_fab2_lib.baseboard_fab2(sch_1):page108_i1@mstr_discrete.cap(chips)!CAP_0402LF-0.1UF,16V,10%,X7R,AA!C2U20!//jf4cfls225.pdx.intel.com/apd_proj/ppg_lib/epg_masterlib/logical/mstr_discrete/cap/chips/chips.prt!CAP!CAP_0402LF-0.1UF,16V,10%,X7R,A36096-030!CAP!!!F3352!!IO_SLOT!!
S!@baseboard_fab2_lib.baseboard_fab2(sch_1):page108_i7@mstr_discrete.cap(chips)!CAP_0402LF-0.1UF,16V,10%,X7R,AA!C2U25!//jf4cfls225.pdx.intel.com/apd_proj/ppg_lib/epg_masterlib/logical/mstr_discrete/cap/chips/chips.prt!CAP!CAP_0402LF-0.1UF,16V,10%,X7R,A36096-030!CAP!!!F3347!!IO_SLOT!!
S!@baseboard_fab2_lib.baseboard_fab2(sch_1):page108_i2@mstr_discrete.cap(chips)!CAP_0402LF-0.1UF,16V,10%,X7R,AA!C2U24!//jf4cfls225.pdx.intel.com/apd_proj/ppg_lib/epg_masterlib/logical/mstr_discrete/cap/chips/chips.prt!CAP!CAP_0402LF-0.1UF,16V,10%,X7R,A36096-030!CAP!!!F3348!!IO_SLOT!!
S!@baseboard_fab2_lib.baseboard_fab2(sch_1):page149_i1@mstr_discrete.cap(chips)!CAP_0402LF-0.1UF,16V,10%,X7R,AA!C1T52!//jf4cfls225.pdx.intel.com/apd_proj/ppg_lib/epg_masterlib/logical/mstr_discrete/cap/chips/chips.prt!CAP!CAP_0402LF-0.1UF,16V,10%,X7R,A36096-030!CAP!!!F3403!!BMC!!
S!@baseboard_fab2_lib.baseboard_fab2(sch_1):page149_i4@mstr_discrete.cap(chips)!CAP_0402LF-0.1UF,16V,10%,X7R,AA!C1U3!//jf4cfls225.pdx.intel.com/apd_proj/ppg_lib/epg_masterlib/logical/mstr_discrete/cap/chips/chips.prt!CAP!CAP_0402LF-0.1UF,16V,10%,X7R,A36096-030!CAP!!!F3400!!BMC!!
S!@baseboard_fab2_lib.baseboard_fab2(sch_1):page149_i5@mstr_discrete.cap(chips)!CAP_0402LF-0.1UF,16V,10%,X7R,AA!C1T29!//jf4cfls225.pdx.intel.com/apd_proj/ppg_lib/epg_masterlib/logical/mstr_discrete/cap/chips/chips.prt!CAP!CAP_0402LF-0.1UF,16V,10%,X7R,A36096-030!CAP!!!F3414!!BMC!!
S!@baseboard_fab2_lib.baseboard_fab2(sch_1):page149_i6@mstr_discrete.cap(chips)!CAP_0402LF-0.1UF,16V,10%,X7R,AA!C1T30!//jf4cfls225.pdx.intel.com/apd_proj/ppg_lib/epg_masterlib/logical/mstr_discrete/cap/chips/chips.prt!CAP!CAP_0402LF-0.1UF,16V,10%,X7R,A36096-030!CAP!!!F3413!!BMC!!
S!@baseboard_fab2_lib.baseboard_fab2(sch_1):page149_i20@mstr_discrete.cap(chips)!CAP_0402LF-0.1UF,16V,10%,X7R,AA!C1T43!//jf4cfls225.pdx.intel.com/apd_proj/ppg_lib/epg_masterlib/logical/mstr_discrete/cap/chips/chips.prt!CAP!CAP_0402LF-0.1UF,16V,10%,X7R,A36096-030!CAP!!!F3408!!BMC!!
S!@baseboard_fab2_lib.baseboard_fab2(sch_1):page149_i21@mstr_discrete.cap(chips)!CAP_0402LF-0.1UF,16V,10%,X7R,AA!C1T45!//jf4cfls225.pdx.intel.com/apd_proj/ppg_lib/epg_masterlib/logical/mstr_discrete/cap/chips/chips.prt!CAP!CAP_0402LF-0.1UF,16V,10%,X7R,A36096-030!CAP!!!F3407!!BMC!!
S!@baseboard_fab2_lib.baseboard_fab2(sch_1):page149_i18@mstr_discrete.cap(chips)!CAP_0402LF-0.1UF,16V,10%,X7R,AA!C1U4!//jf4cfls225.pdx.intel.com/apd_proj/ppg_lib/epg_masterlib/logical/mstr_discrete/cap/chips/chips.prt!CAP!CAP_0402LF-0.1UF,16V,10%,X7R,A36096-030!CAP!!!F3399!!BMC!!
S!@baseboard_fab2_lib.baseboard_fab2(sch_1):page149_i24@mstr_discrete.cap(chips)!CAP_0402LF-0.1UF,16V,10%,X7R,AA!C1T47!//jf4cfls225.pdx.intel.com/apd_proj/ppg_lib/epg_masterlib/logical/mstr_discrete/cap/chips/chips.prt!CAP!CAP_0402LF-0.1UF,16V,10%,X7R,A36096-030!CAP!!!F3406!!BMC!!
S!@baseboard_fab2_lib.baseboard_fab2(sch_1):page149_i25@mstr_discrete.cap(chips)!CAP_0402LF-0.1UF,16V,10%,X7R,AA!C1U11!//jf4cfls225.pdx.intel.com/apd_proj/ppg_lib/epg_masterlib/logical/mstr_discrete/cap/chips/chips.prt!CAP!CAP_0402LF-0.1UF,16V,10%,X7R,A36096-030!CAP!!!F3395!!BMC!!
S!@baseboard_fab2_lib.baseboard_fab2(sch_1):page149_i23@mstr_discrete.cap(chips)!CAP_0402LF-0.1UF,16V,10%,X7R,AA!C1U9!//jf4cfls225.pdx.intel.com/apd_proj/ppg_lib/epg_masterlib/logical/mstr_discrete/cap/chips/chips.prt!CAP!CAP_0402LF-0.1UF,16V,10%,X7R,A36096-030!CAP!!!F3397!!BMC!!
S!@baseboard_fab2_lib.baseboard_fab2(sch_1):page149_i43@mstr_discrete.cap(chips)!CAP_0402LF-0.1UF,16V,10%,X7R,AA!C1T22!//jf4cfls225.pdx.intel.com/apd_proj/ppg_lib/epg_masterlib/logical/mstr_discrete/cap/chips/chips.prt!CAP!CAP_0402LF-0.1UF,16V,10%,X7R,A36096-030!CAP!!!F3418!!BMC!!
S!@baseboard_fab2_lib.baseboard_fab2(sch_1):page149_i41@mstr_discrete.cap(chips)!CAP_0402LF-0.1UF,16V,10%,X7R,AA!C1T50!//jf4cfls225.pdx.intel.com/apd_proj/ppg_lib/epg_masterlib/logical/mstr_discrete/cap/chips/chips.prt!CAP!CAP_0402LF-0.1UF,16V,10%,X7R,A36096-030!CAP!!!F3404!!BMC!!
S!@baseboard_fab2_lib.baseboard_fab2(sch_1):page149_i44@mstr_discrete.cap(chips)!CAP_0402LF-0.1UF,16V,10%,X7R,AA!C1T8!//jf4cfls225.pdx.intel.com/apd_proj/ppg_lib/epg_masterlib/logical/mstr_discrete/cap/chips/chips.prt!CAP!CAP_0402LF-0.1UF,16V,10%,X7R,A36096-030!CAP!!!F3422!!BMC!!
S!@baseboard_fab2_lib.baseboard_fab2(sch_1):page149_i42@mstr_discrete.cap(chips)!CAP_0402LF-0.1UF,16V,10%,X7R,AA!C1T25!//jf4cfls225.pdx.intel.com/apd_proj/ppg_lib/epg_masterlib/logical/mstr_discrete/cap/chips/chips.prt!CAP!CAP_0402LF-0.1UF,16V,10%,X7R,A36096-030!CAP!!!F3416!!BMC!!
S!@baseboard_fab2_lib.baseboard_fab2(sch_1):page149_i49@mstr_discrete.cap(chips)!CAP_0402LF-0.1UF,16V,10%,X7R,AA!C1T14!//jf4cfls225.pdx.intel.com/apd_proj/ppg_lib/epg_masterlib/logical/mstr_discrete/cap/chips/chips.prt!CAP!CAP_0402LF-0.1UF,16V,10%,X7R,A36096-030!CAP!!!F3419!!BMC!!
S!@baseboard_fab2_lib.baseboard_fab2(sch_1):page149_i46@mstr_discrete.cap(chips)!CAP_0402LF-0.1UF,16V,10%,X7R,AA!C1T26!//jf4cfls225.pdx.intel.com/apd_proj/ppg_lib/epg_masterlib/logical/mstr_discrete/cap/chips/chips.prt!CAP!CAP_0402LF-0.1UF,16V,10%,X7R,A36096-030!CAP!!!F3415!!BMC!!
S!@baseboard_fab2_lib.baseboard_fab2(sch_1):page202_i46@mstr_discrete.cap(chips)!CAP_0402LF-0.1UF,16V,10%,X7R,AA!C4D49!//jf4cfls225.pdx.intel.com/apd_proj/ppg_lib/epg_masterlib/logical/mstr_discrete/cap/chips/chips.prt!CAP!CAP_0402LF-0.1UF,16V,10%,X7R,A36096-030!CAP!!!F3313!!PVCCIN_CPU0_PWR_VR!!
S!@baseboard_fab2_lib.baseboard_fab2(sch_1):page202_i35@mstr_discrete.cap(chips)!CAP_0402LF-0.1UF,16V,10%,X7R,AA!C4E20!//jf4cfls225.pdx.intel.com/apd_proj/ppg_lib/epg_masterlib/logical/mstr_discrete/cap/chips/chips.prt!CAP!CAP_0402LF-0.1UF,16V,10%,X7R,A36096-030!CAP!!!F3311!!PVCCIN_CPU0_PWR_VR!!
S!@baseboard_fab2_lib.baseboard_fab2(sch_1):page216_i51@mstr_discrete.cap(chips)!CAP_0402LF-0.1UF,16V,10%,X7R,AA!C7G29!//jf4cfls225.pdx.intel.com/apd_proj/ppg_lib/epg_masterlib/logical/mstr_discrete/cap/chips/chips.prt!CAP!CAP_0402LF-0.1UF,16V,10%,X7R,A36096-030!CAP!!!F3275!!VDDQ_ABC_PWR_VR!!
S!@baseboard_fab2_lib.baseboard_fab2(sch_1):page216_i78@mstr_discrete.cap(chips)!CAP_0402LF-0.1UF,16V,10%,X7R,AA!C7G36!//jf4cfls225.pdx.intel.com/apd_proj/ppg_lib/epg_masterlib/logical/mstr_discrete/cap/chips/chips.prt!CAP!CAP_0402LF-0.1UF,16V,10%,X7R,A36096-030!CAP!!!F3274!!VDDQ_ABC_PWR_VR!!
S!@baseboard_fab2_lib.baseboard_fab2(sch_1):page205_i31@mstr_discrete.cap(chips)!CAP_0402LF-0.1UF,16V,10%,X7R,AA!C4C10!//jf4cfls225.pdx.intel.com/apd_proj/ppg_lib/epg_masterlib/logical/mstr_discrete/cap/chips/chips.prt!CAP!CAP_0402LF-0.1UF,16V,10%,X7R,A36096-030!CAP!!!F3323!!PVSA_CPU0_PWR_VR!!
S!@baseboard_fab2_lib.baseboard_fab2(sch_1):page215_i311@mstr_discrete.cap(chips)!CAP_0402LF-0.1UF,16V,10%,X7R,AA!C7F17!//jf4cfls225.pdx.intel.com/apd_proj/ppg_lib/epg_masterlib/logical/mstr_discrete/cap/chips/chips.prt!CAP!CAP_0402LF-0.1UF,16V,10%,X7R,A36096-030!CAP!!!F3276!!VDDQ_ABC_PWR_VR!!
S!@baseboard_fab2_lib.baseboard_fab2(sch_1):page215_i327@mstr_discrete.cap(chips)!CAP_0402LF-0.1UF,16V,10%,X7R,AA!C7F15!//jf4cfls225.pdx.intel.com/apd_proj/ppg_lib/epg_masterlib/logical/mstr_discrete/cap/chips/chips.prt!CAP!CAP_0402LF-0.1UF,16V,10%,X7R,A36096-030!CAP!!!F3277!!VDDQ_ABC_PWR_VR!!
S!@baseboard_fab2_lib.baseboard_fab2(sch_1):page219_i51@mstr_discrete.cap(chips)!CAP_0402LF-0.1UF,16V,10%,X7R,AA!C7A5!//jf4cfls225.pdx.intel.com/apd_proj/ppg_lib/epg_masterlib/logical/mstr_discrete/cap/chips/chips.prt!CAP!CAP_0402LF-0.1UF,16V,10%,X7R,A36096-030!CAP!!!F3293!!VDDQ_DEF_PWR_VR!!
S!@baseboard_fab2_lib.baseboard_fab2(sch_1):page219_i78@mstr_discrete.cap(chips)!CAP_0402LF-0.1UF,16V,10%,X7R,AA!C7A20!//jf4cfls225.pdx.intel.com/apd_proj/ppg_lib/epg_masterlib/logical/mstr_discrete/cap/chips/chips.prt!CAP!CAP_0402LF-0.1UF,16V,10%,X7R,A36096-030!CAP!!!F3292!!VDDQ_DEF_PWR_VR!!
S!@baseboard_fab2_lib.baseboard_fab2(sch_1):page227_i51@mstr_discrete.cap(chips)!CAP_0402LF-0.1UF,16V,10%,X7R,AA!C1A10!//jf4cfls225.pdx.intel.com/apd_proj/ppg_lib/epg_masterlib/logical/mstr_discrete/cap/chips/chips.prt!CAP!CAP_0402LF-0.1UF,16V,10%,X7R,A36096-030!CAP!!!F3475!!VDDQ_KLM_PWR_VR!!
S!@baseboard_fab2_lib.baseboard_fab2(sch_1):page227_i78@mstr_discrete.cap(chips)!CAP_0402LF-0.1UF,16V,10%,X7R,AA!C1A20!//jf4cfls225.pdx.intel.com/apd_proj/ppg_lib/epg_masterlib/logical/mstr_discrete/cap/chips/chips.prt!CAP!CAP_0402LF-0.1UF,16V,10%,X7R,A36096-030!CAP!!!F3474!!VDDQ_KLM_PWR_VR!!
S!@baseboard_fab2_lib.baseboard_fab2(sch_1):page224_i51@mstr_discrete.cap(chips)!CAP_0402LF-0.1UF,16V,10%,X7R,AA!C1G14!//jf4cfls225.pdx.intel.com/apd_proj/ppg_lib/epg_masterlib/logical/mstr_discrete/cap/chips/chips.prt!CAP!CAP_0402LF-0.1UF,16V,10%,X7R,A36096-030!CAP!!!F3451!!VDDQ_GHJ_PWR_VR!!
S!@baseboard_fab2_lib.baseboard_fab2(sch_1):page224_i78@mstr_discrete.cap(chips)!CAP_0402LF-0.1UF,16V,10%,X7R,AA!C1F28!//jf4cfls225.pdx.intel.com/apd_proj/ppg_lib/epg_masterlib/logical/mstr_discrete/cap/chips/chips.prt!CAP!CAP_0402LF-0.1UF,16V,10%,X7R,A36096-030!CAP!!!F3452!!VDDQ_GHJ_PWR_VR!!
S!@baseboard_fab2_lib.baseboard_fab2(sch_1):page201_i39@mstr_discrete.cap(chips)!CAP_0402LF-0.1UF,16V,10%,X7R,AA!C4D19!//jf4cfls225.pdx.intel.com/apd_proj/ppg_lib/epg_masterlib/logical/mstr_discrete/cap/chips/chips.prt!CAP!CAP_0402LF-0.1UF,16V,10%,X7R,A36096-030!CAP!!!F3320!!PVCCIN_CPU0_VR!!
S!@baseboard_fab2_lib.baseboard_fab2(sch_1):page201_i32@mstr_discrete.cap(chips)!CAP_0402LF-0.1UF,16V,10%,X7R,AA!C4D26!//jf4cfls225.pdx.intel.com/apd_proj/ppg_lib/epg_masterlib/logical/mstr_discrete/cap/chips/chips.prt!CAP!CAP_0402LF-0.1UF,16V,10%,X7R,A36096-030!CAP!!!F3317!!PVCCIN_CPU0_VR!!
S!@baseboard_fab2_lib.baseboard_fab2(sch_1):page206_i42@mstr_discrete.cap(chips)!CAP_0402LF-0.1UF,16V,10%,X7R,AA!C1C9!//jf4cfls225.pdx.intel.com/apd_proj/ppg_lib/epg_masterlib/logical/mstr_discrete/cap/chips/chips.prt!CAP!CAP_0402LF-0.1UF,16V,10%,X7R,A36096-030!CAP!!!F3469!!PVCCIN_CPU1_VR!!
S!@baseboard_fab2_lib.baseboard_fab2(sch_1):page206_i31@mstr_discrete.cap(chips)!CAP_0402LF-0.1UF,16V,10%,X7R,AA!C1C14!//jf4cfls225.pdx.intel.com/apd_proj/ppg_lib/epg_masterlib/logical/mstr_discrete/cap/chips/chips.prt!CAP!CAP_0402LF-0.1UF,16V,10%,X7R,A36096-030!CAP!!!F3468!!PVCCIN_CPU1_VR!!
S!@baseboard_fab2_lib.baseboard_fab2(sch_1):page186_i10@mstr_discrete.cap(chips)!CAP_0402LF-0.1UF,16V,10%,X7R,AA!C1M24!//jf4cfls225.pdx.intel.com/apd_proj/ppg_lib/epg_masterlib/logical/mstr_discrete/cap/chips/chips.prt!CAP!CAP_0402LF-0.1UF,16V,10%,X7R,A36096-030!CAP!!!F3438!!IO_SLOT!!
S!@baseboard_fab2_lib.baseboard_fab2(sch_1):page186_i7@mstr_discrete.cap(chips)!CAP_0402LF-0.1UF,16V,10%,X7R,AA!C1M23!//jf4cfls225.pdx.intel.com/apd_proj/ppg_lib/epg_masterlib/logical/mstr_discrete/cap/chips/chips.prt!CAP!CAP_0402LF-0.1UF,16V,10%,X7R,A36096-030!CAP!!!F3439!!IO_SLOT!!
S!@baseboard_fab2_lib.baseboard_fab2(sch_1):page186_i8@mstr_discrete.cap(chips)!CAP_0402LF-0.1UF,16V,10%,X7R,AA!C1M22!//jf4cfls225.pdx.intel.com/apd_proj/ppg_lib/epg_masterlib/logical/mstr_discrete/cap/chips/chips.prt!CAP!CAP_0402LF-0.1UF,16V,10%,X7R,A36096-030!CAP!!!F3440!!IO_SLOT!!
S!@baseboard_fab2_lib.baseboard_fab2(sch_1):page199_i7@mstr_discrete.cap(chips)!CAP_0402LF-0.1UF,16V,10%,X7R,AA!C1D27!//jf4cfls225.pdx.intel.com/apd_proj/ppg_lib/epg_masterlib/logical/mstr_discrete/cap/chips/chips.prt!CAP!CAP_0402LF-0.1UF,16V,10%,X7R,A36096-030!CAP!!!F3460!!HOT_SWAP!!
S!@baseboard_fab2_lib.baseboard_fab2(sch_1):page207_i33@mstr_discrete.cap(chips)!CAP_0402LF-0.1UF,16V,10%,X7R,AA!C1E14!//jf4cfls225.pdx.intel.com/apd_proj/ppg_lib/epg_masterlib/logical/mstr_discrete/cap/chips/chips.prt!CAP!CAP_0402LF-0.1UF,16V,10%,X7R,A36096-030!CAP!!!F3457!!PVCCIN_CPU1_PWR_VR!!
S!@baseboard_fab2_lib.baseboard_fab2(sch_1):page207_i41@mstr_discrete.cap(chips)!CAP_0402LF-0.1UF,16V,10%,X7R,AA!C1D34!//jf4cfls225.pdx.intel.com/apd_proj/ppg_lib/epg_masterlib/logical/mstr_discrete/cap/chips/chips.prt!CAP!CAP_0402LF-0.1UF,16V,10%,X7R,A36096-030!CAP!!!F3458!!PVCCIN_CPU1_PWR_VR!!
S!@baseboard_fab2_lib.baseboard_fab2(sch_1):page208_i44@mstr_discrete.cap(chips)!CAP_0402LF-0.1UF,16V,10%,X7R,AA!C1D28!//jf4cfls225.pdx.intel.com/apd_proj/ppg_lib/epg_masterlib/logical/mstr_discrete/cap/chips/chips.prt!CAP!CAP_0402LF-0.1UF,16V,10%,X7R,A36096-030!CAP!!!F3459!!PVCCIN_CPU1_PWR_VR!!
S!@baseboard_fab2_lib.baseboard_fab2(sch_1):page208_i51@mstr_discrete.cap(chips)!CAP_0402LF-0.1UF,16V,10%,X7R,AA!C1D13!//jf4cfls225.pdx.intel.com/apd_proj/ppg_lib/epg_masterlib/logical/mstr_discrete/cap/chips/chips.prt!CAP!CAP_0402LF-0.1UF,16V,10%,X7R,A36096-030!CAP!!!F3463!!PVCCIN_CPU1_PWR_VR!!
S!@baseboard_fab2_lib.baseboard_fab2(sch_1):page210_i27@mstr_discrete.cap(chips)!CAP_0402LF-0.1UF,16V,10%,X7R,AA!C1C17!//jf4cfls225.pdx.intel.com/apd_proj/ppg_lib/epg_masterlib/logical/mstr_discrete/cap/chips/chips.prt!CAP!CAP_0402LF-0.1UF,16V,10%,X7R,A36096-030!CAP!!!F3467!!PVSA_CPU1_PWR_VR!!
S!@baseboard_fab2_lib.baseboard_fab2(sch_1):page99_i7@mstr_discrete.cap(chips)!CAP_0402LF-0.1UF,16V,10%,X7R,AA!C6F3!//jf4cfls225.pdx.intel.com/apd_proj/ppg_lib/epg_masterlib/logical/mstr_discrete/cap/chips/chips.prt!CAP!CAP_0402LF-0.1UF,16V,10%,X7R,A36096-030!CAP!!!F3303!!MEM!!
S!@baseboard_fab2_lib.baseboard_fab2(sch_1):page99_i32@mstr_discrete.cap(chips)!CAP_0402LF-0.1UF,16V,10%,X7R,AA!C7E2!//jf4cfls225.pdx.intel.com/apd_proj/ppg_lib/epg_masterlib/logical/mstr_discrete/cap/chips/chips.prt!CAP!CAP_0402LF-0.1UF,16V,10%,X7R,A36096-030!CAP!!!F3284!!MEM!!
S!@baseboard_fab2_lib.baseboard_fab2(sch_1):page99_i2@mstr_discrete.cap(chips)!CAP_0402LF-0.1UF,16V,10%,X7R,AA!C6F2!//jf4cfls225.pdx.intel.com/apd_proj/ppg_lib/epg_masterlib/logical/mstr_discrete/cap/chips/chips.prt!CAP!CAP_0402LF-0.1UF,16V,10%,X7R,A36096-030!CAP!!!F3304!!MEM!!
S!@baseboard_fab2_lib.baseboard_fab2(sch_1):page99_i23@mstr_discrete.cap(chips)!CAP_0402LF-0.1UF,16V,10%,X7R,AA!C7E1!//jf4cfls225.pdx.intel.com/apd_proj/ppg_lib/epg_masterlib/logical/mstr_discrete/cap/chips/chips.prt!CAP!CAP_0402LF-0.1UF,16V,10%,X7R,A36096-030!CAP!!!F3285!!MEM!!
S!@baseboard_fab2_lib.baseboard_fab2(sch_1):page99_i27@mstr_discrete.cap(chips)!CAP_0402LF-0.1UF,16V,10%,X7R,AA!C4G22!//jf4cfls225.pdx.intel.com/apd_proj/ppg_lib/epg_masterlib/logical/mstr_discrete/cap/chips/chips.prt!CAP!CAP_0402LF-0.1UF,16V,10%,X7R,A36096-030!CAP!!!F3309!!MEM!!
S!@baseboard_fab2_lib.baseboard_fab2(sch_1):page199_i53@mstr_discrete.cap(chips)!CAP_0402LF-0.1UF,16V,10%,X7R,AA!C1D11!//jf4cfls225.pdx.intel.com/apd_proj/ppg_lib/epg_masterlib/logical/mstr_discrete/cap/chips/chips.prt!CAP!CAP_0402LF-0.1UF,16V,10%,X7R,A36096-030!CAP!!!F3464!!HOT_SWAP!!
S!@baseboard_fab2_lib.baseboard_fab2(sch_1):page204_i35@mstr_discrete.cap(chips)!CAP_0402LF-0.1UF,16V,10%,X7R,AA!C4C19!//jf4cfls225.pdx.intel.com/apd_proj/ppg_lib/epg_masterlib/logical/mstr_discrete/cap/chips/chips.prt!CAP!CAP_0402LF-0.1UF,16V,10%,X7R,A36096-030!CAP!!!F3322!!PVCCIN_CPU0_PWR_VR!!
S!@baseboard_fab2_lib.baseboard_fab2(sch_1):page195_i36@mstr_discrete.cap(chips)!CAP_0402LF-0.1UF,16V,10%,X7R,AA!C9R12!//jf4cfls225.pdx.intel.com/apd_proj/ppg_lib/epg_masterlib/logical/mstr_discrete/cap/chips/chips.prt!CAP!CAP_0402LF-0.1UF,16V,10%,X7R,A36096-030!CAP!!!F3232!!HOT_SWAP!!
S!@baseboard_fab2_lib.baseboard_fab2(sch_1):page195_i37@mstr_discrete.cap(chips)!CAP_0402LF-0.1UF,16V,10%,X7R,AA!C9R6!//jf4cfls225.pdx.intel.com/apd_proj/ppg_lib/epg_masterlib/logical/mstr_discrete/cap/chips/chips.prt!CAP!CAP_0402LF-0.1UF,16V,10%,X7R,A36096-030!CAP!!!F3233!!HOT_SWAP!!
S!@baseboard_fab2_lib.baseboard_fab2(sch_1):page195_i38@mstr_discrete.cap(chips)!CAP_0402LF-0.1UF,16V,10%,X7R,AA!C1E17!//jf4cfls225.pdx.intel.com/apd_proj/ppg_lib/epg_masterlib/logical/mstr_discrete/cap/chips/chips.prt!CAP!CAP_0402LF-0.1UF,16V,10%,X7R,A36096-030!CAP!!!F3455!!HOT_SWAP!!
S!@baseboard_fab2_lib.baseboard_fab2(sch_1):page195_i39@mstr_discrete.cap(chips)!CAP_0402LF-0.1UF,16V,10%,X7R,AA!C1E16!//jf4cfls225.pdx.intel.com/apd_proj/ppg_lib/epg_masterlib/logical/mstr_discrete/cap/chips/chips.prt!CAP!CAP_0402LF-0.1UF,16V,10%,X7R,A36096-030!CAP!!!F3456!!HOT_SWAP!!
S!@baseboard_fab2_lib.baseboard_fab2(sch_1):page149_i17@mstr_discrete.cap(chips)!CAP_0402LF-0.1UF,16V,10%,X7R,AA!C1U5!//jf4cfls225.pdx.intel.com/apd_proj/ppg_lib/epg_masterlib/logical/mstr_discrete/cap/chips/chips.prt!CAP!CAP_0402LF-0.1UF,16V,10%,X7R,A36096-030!CAP!!!F3398!!BMC!!
S!@baseboard_fab2_lib.baseboard_fab2(sch_1):page149_i22@mstr_discrete.cap(chips)!CAP_0402LF-0.1UF,16V,10%,X7R,AA!C1T38!//jf4cfls225.pdx.intel.com/apd_proj/ppg_lib/epg_masterlib/logical/mstr_discrete/cap/chips/chips.prt!CAP!CAP_0402LF-0.1UF,16V,10%,X7R,A36096-030!CAP!!!F3410!!BMC!!
S!@baseboard_fab2_lib.baseboard_fab2(sch_1):page92_i37@mstr_discrete.cap(chips)!CAP_0402LF-0.1UF,16V,10%,X7R,AA!C3P49!//jf4cfls225.pdx.intel.com/apd_proj/ppg_lib/epg_masterlib/logical/mstr_discrete/cap/chips/chips.prt!CAP!CAP_0402LF-0.1UF,16V,10%,X7R,A36096-030!CAP!!!F3332!!PROC_SIDEBAND!!
S!@baseboard_fab2_lib.baseboard_fab2(sch_1):page92_i52@mstr_discrete.cap(chips)!CAP_0402LF-0.1UF,16V,10%,X7R,AA!C7D5!//jf4cfls225.pdx.intel.com/apd_proj/ppg_lib/epg_masterlib/logical/mstr_discrete/cap/chips/chips.prt!CAP!CAP_0402LF-0.1UF,16V,10%,X7R,A36096-030!CAP!!!F3286!!PROC_SIDEBAND!!
S!@baseboard_fab2_lib.baseboard_fab2(sch_1):page143_i336@mstr_discrete.cap(chips)!CAP_0402LF-0.1UF,16V,10%,X7R,AA!C1T37!//jf4cfls225.pdx.intel.com/apd_proj/ppg_lib/epg_masterlib/logical/mstr_discrete/cap/chips/chips.prt!CAP!CAP_0402LF-0.1UF,16V,10%,X7R,A36096-030!CAP!!!F3411!!BMC!!
S!@baseboard_fab2_lib.baseboard_fab2(sch_1):page169_i108@mstr_discrete.cap(chips)!CAP_0402LF-10.0PF,50V,5%,COG,AA!C9G22!//jf4cfls225.pdx.intel.com/apd_proj/ppg_lib/epg_masterlib/logical/mstr_discrete/cap/chips/chips.prt!CAP!CAP_0402LF-10.0PF,50V,5%,COG,A36094-025!CAP!!!F3212!!BMC_VOLT_MONITOR!!
S!@baseboard_fab2_lib.baseboard_fab2(sch_1):page234_i212@mstr_discrete.cap(chips)!CAP_0402LF-100.0PF,50V,5%,COG,A!C4B4!//jf4cfls225.pdx.intel.com/apd_proj/ppg_lib/epg_masterlib/logical/mstr_discrete/cap/chips/chips.prt!CAP!CAP_0402LF-100.0PF,50V,5%,COG,A36095-026!CAP!!!F3208!!PVPP_KLM_VR!!
S!@baseboard_fab2_lib.baseboard_fab2(sch_1):page233_i273@mstr_discrete.cap(chips)!CAP_0402LF-100.0PF,50V,5%,COG,A!C4G6!//jf4cfls225.pdx.intel.com/apd_proj/ppg_lib/epg_masterlib/logical/mstr_discrete/cap/chips/chips.prt!CAP!CAP_0402LF-100.0PF,50V,5%,COG,A36095-026!CAP!!!F3207!!PVPP_KLM_VR!!
S!@baseboard_fab2_lib.baseboard_fab2(sch_1):page232_i301@mstr_discrete.cap(chips)!CAP_0402LF-100.0PF,50V,5%,COG,A!C7B10!//jf4cfls225.pdx.intel.com/apd_proj/ppg_lib/epg_masterlib/logical/mstr_discrete/cap/chips/chips.prt!CAP!CAP_0402LF-100.0PF,50V,5%,COG,A36095-026!CAP!!!F3206!!PVPP_KLM_VR!!
S!@baseboard_fab2_lib.baseboard_fab2(sch_1):page231_i199@mstr_discrete.cap(chips)!CAP_0402LF-100.0PF,50V,5%,COG,A!C7F9!//jf4cfls225.pdx.intel.com/apd_proj/ppg_lib/epg_masterlib/logical/mstr_discrete/cap/chips/chips.prt!CAP!CAP_0402LF-100.0PF,50V,5%,COG,A36095-026!CAP!!!F3205!!PVPP_KLM_VR!!
S!@baseboard_fab2_lib.baseboard_fab2(sch_1):page149_i142@mstr_discrete.cap(chips)!CAP_0402LF-100.0PF,50V,5%,COG,A!C1U17!//jf4cfls225.pdx.intel.com/apd_proj/ppg_lib/epg_masterlib/logical/mstr_discrete/cap/chips/chips.prt!CAP!CAP_0402LF-100.0PF,50V,5%,COG,A36095-026!CAP!!!F3209!!BMC!!
S!@baseboard_fab2_lib.baseboard_fab2(sch_1):page148_i26@mstr_discrete.cap(chips)!CAP_0402LF-100.0PF,50V,5%,COG,A!C1U2!//jf4cfls225.pdx.intel.com/apd_proj/ppg_lib/epg_masterlib/logical/mstr_discrete/cap/chips/chips.prt!CAP!CAP_0402LF-100.0PF,50V,5%,COG,A36095-026!CAP!!!F3210!!BMC!!
S!@baseboard_fab2_lib.baseboard_fab2(sch_1):page149_i119@mstr_discrete.cap(chips)!CAP_0402LF-100.0PF,50V,5%,COG,A!C1T20!//jf4cfls225.pdx.intel.com/apd_proj/ppg_lib/epg_masterlib/logical/mstr_discrete/cap/chips/chips.prt!CAP!CAP_0402LF-100.0PF,50V,5%,COG,A36095-026!CAP!!!F3211!!BMC!!
S!@baseboard_fab2_lib.baseboard_fab2(sch_1):page149_i104@mstr_discrete.cap(chips)!CAP_0402LF-100.0PF,50V,5%,COG,A!C9F18!//jf4cfls225.pdx.intel.com/apd_proj/ppg_lib/epg_masterlib/logical/mstr_discrete/cap/chips/chips.prt!CAP!CAP_0402LF-100.0PF,50V,5%,COG,A36095-026!CAP!!!F3204!!BMC!!
S!@baseboard_fab2_lib.baseboard_fab2(sch_1):page232_i185@mstr_discrete.cap(chips)!CAP_0402LF-1000PF,50V,10%,EMPTA!C7B9!//jf4cfls225.pdx.intel.com/apd_proj/ppg_lib/epg_masterlib/logical/mstr_discrete/cap/chips/chips.prt!CAP!CAP_0402LF-1000PF,50V,10%,EMPTY,A36096-046!CAP!!!F3197!!PVPP_KLM_VR!!
S!@baseboard_fab2_lib.baseboard_fab2(sch_1):page233_i183@mstr_discrete.cap(chips)!CAP_0402LF-1000PF,50V,10%,EMPTA!C4G7!//jf4cfls225.pdx.intel.com/apd_proj/ppg_lib/epg_masterlib/logical/mstr_discrete/cap/chips/chips.prt!CAP!CAP_0402LF-1000PF,50V,10%,EMPTY,A36096-046!CAP!!!F3200!!PVPP_KLM_VR!!
S!@baseboard_fab2_lib.baseboard_fab2(sch_1):page234_i129@mstr_discrete.cap(chips)!CAP_0402LF-1000PF,50V,10%,EMPTA!C4B5!//jf4cfls225.pdx.intel.com/apd_proj/ppg_lib/epg_masterlib/logical/mstr_discrete/cap/chips/chips.prt!CAP!CAP_0402LF-1000PF,50V,10%,EMPTY,A36096-046!CAP!!!F3201!!PVPP_KLM_VR!!
S!@baseboard_fab2_lib.baseboard_fab2(sch_1):page231_i140@mstr_discrete.cap(chips)!CAP_0402LF-1000PF,50V,10%,EMPTA!C7F8!//jf4cfls225.pdx.intel.com/apd_proj/ppg_lib/epg_masterlib/logical/mstr_discrete/cap/chips/chips.prt!CAP!CAP_0402LF-1000PF,50V,10%,EMPTY,A36096-046!CAP!!!F3196!!PVPP_KLM_VR!!
S!@baseboard_fab2_lib.baseboard_fab2(sch_1):page240_i113@mstr_discrete.cap(chips)!CAP_0402LF-1000PF,50V,10%,EMPTA!C8E17!//jf4cfls225.pdx.intel.com/apd_proj/ppg_lib/epg_masterlib/logical/mstr_discrete/cap/chips/chips.prt!CAP!CAP_0402LF-1000PF,50V,10%,EMPTY,A36096-046!CAP!!!F3193!!P3V3_STBY_VR!!
S!@baseboard_fab2_lib.baseboard_fab2(sch_1):page237_i55@mstr_discrete.cap(chips)!CAP_0402LF-1000PF,50V,10%,EMPTA!C8A10!//jf4cfls225.pdx.intel.com/apd_proj/ppg_lib/epg_masterlib/logical/mstr_discrete/cap/chips/chips.prt!CAP!CAP_0402LF-1000PF,50V,10%,EMPTY,A36096-046!CAP!!!F3195!!P1V8_PCH_STBY_VR!!
S!@baseboard_fab2_lib.baseboard_fab2(sch_1):page221_i39@mstr_discrete.cap(chips)!CAP_0402LF-1000PF,50V,10%,EMPTA!C4G23!//jf4cfls225.pdx.intel.com/apd_proj/ppg_lib/epg_masterlib/logical/mstr_discrete/cap/chips/chips.prt!CAP!CAP_0402LF-1000PF,50V,10%,EMPTY,A36096-046!CAP!!!F3198!!VTT_ABC_PWR_VR!!
S!@baseboard_fab2_lib.baseboard_fab2(sch_1):page222_i40@mstr_discrete.cap(chips)!CAP_0402LF-1000PF,50V,10%,EMPTA!C4A2!//jf4cfls225.pdx.intel.com/apd_proj/ppg_lib/epg_masterlib/logical/mstr_discrete/cap/chips/chips.prt!CAP!CAP_0402LF-1000PF,50V,10%,EMPTY,A36096-046!CAP!!!F3203!!VTT_DEF_PWR_VR!!
S!@baseboard_fab2_lib.baseboard_fab2(sch_1):page229_i36@mstr_discrete.cap(chips)!CAP_0402LF-1000PF,50V,10%,EMPTA!C4G12!//jf4cfls225.pdx.intel.com/apd_proj/ppg_lib/epg_masterlib/logical/mstr_discrete/cap/chips/chips.prt!CAP!CAP_0402LF-1000PF,50V,10%,EMPTY,A36096-046!CAP!!!F3199!!VTT_GHJ_PWR_VR!!
S!@baseboard_fab2_lib.baseboard_fab2(sch_1):page230_i39@mstr_discrete.cap(chips)!CAP_0402LF-1000PF,50V,10%,EMPTA!C4A6!//jf4cfls225.pdx.intel.com/apd_proj/ppg_lib/epg_masterlib/logical/mstr_discrete/cap/chips/chips.prt!CAP!CAP_0402LF-1000PF,50V,10%,EMPTY,A36096-046!CAP!!!F3202!!VTT_KLM_PWR_VR!!
S!@baseboard_fab2_lib.baseboard_fab2(sch_1):page241_i41@mstr_discrete.cap(chips)!CAP_0402LF-1000PF,50V,10%,EMPTA!C8E13!//jf4cfls225.pdx.intel.com/apd_proj/ppg_lib/epg_masterlib/logical/mstr_discrete/cap/chips/chips.prt!CAP!CAP_0402LF-1000PF,50V,10%,EMPTY,A36096-046!CAP!!!F3194!!P5V_STBY_VR!!
S!@baseboard_fab2_lib.baseboard_fab2(sch_1):page238_i5@mstr_discrete.cap(chips)!CAP_0402LF-1000PF,50V,10%,EMPTA!C9F9!//jf4cfls225.pdx.intel.com/apd_proj/ppg_lib/epg_masterlib/logical/mstr_discrete/cap/chips/chips.prt!CAP!CAP_0402LF-1000PF,50V,10%,EMPTY,A36096-046!CAP!!!F3191!!P1V26_BMC_STBY_VR!!
S!@baseboard_fab2_lib.baseboard_fab2(sch_1):page239_i30@mstr_discrete.cap(chips)!CAP_0402LF-1000PF,50V,10%,EMPTA!C9F6!//jf4cfls225.pdx.intel.com/apd_proj/ppg_lib/epg_masterlib/logical/mstr_discrete/cap/chips/chips.prt!CAP!CAP_0402LF-1000PF,50V,10%,EMPTY,A36096-046!CAP!!!F3192!!P1V538_BMC_STBY_VR!!
S!@baseboard_fab2_lib.baseboard_fab2(sch_1):page201_i125@mstr_discrete.cap(chips)!CAP_0402LF-1000PF,50V,10%,X7R,A!C4D42!//jf4cfls225.pdx.intel.com/apd_proj/ppg_lib/epg_masterlib/logical/mstr_discrete/cap/chips/chips.prt!CAP!CAP_0402LF-1000PF,50V,10%,X7R,A36096-046!CAP!!!F3176!!PVCCIN_CPU0_VR!!
S!@baseboard_fab2_lib.baseboard_fab2(sch_1):page206_i114@mstr_discrete.cap(chips)!CAP_0402LF-1000PF,50V,10%,X7R,A!C1C23!//jf4cfls225.pdx.intel.com/apd_proj/ppg_lib/epg_masterlib/logical/mstr_discrete/cap/chips/chips.prt!CAP!CAP_0402LF-1000PF,50V,10%,X7R,A36096-046!CAP!!!F3187!!PVCCIN_CPU1_VR!!
S!@baseboard_fab2_lib.baseboard_fab2(sch_1):page211_i71@mstr_discrete.cap(chips)!CAP_0402LF-1000PF,50V,10%,X7R,A!C3P6!//jf4cfls225.pdx.intel.com/apd_proj/ppg_lib/epg_masterlib/logical/mstr_discrete/cap/chips/chips.prt!CAP!CAP_0402LF-1000PF,50V,10%,X7R,A36096-046!CAP!!!F3183!!PVCCIO_CPU0_VR!!
S!@baseboard_fab2_lib.baseboard_fab2(sch_1):page213_i73@mstr_discrete.cap(chips)!CAP_0402LF-1000PF,50V,10%,X7R,A!C4D33!//jf4cfls225.pdx.intel.com/apd_proj/ppg_lib/epg_masterlib/logical/mstr_discrete/cap/chips/chips.prt!CAP!CAP_0402LF-1000PF,50V,10%,X7R,A36096-046!CAP!!!F3178!!PVCCIO_CPU1_VR!!
S!@baseboard_fab2_lib.baseboard_fab2(sch_1):page235_i218@mstr_discrete.cap(chips)!CAP_0402LF-1000PF,50V,10%,X7R,A!C8A9!//jf4cfls225.pdx.intel.com/apd_proj/ppg_lib/epg_masterlib/logical/mstr_discrete/cap/chips/chips.prt!CAP!CAP_0402LF-1000PF,50V,10%,X7R,A36096-046!CAP!!!F3164!!PVNN_PCH_STBY!!
S!@baseboard_fab2_lib.baseboard_fab2(sch_1):page215_i305@mstr_discrete.cap(chips)!CAP_0402LF-1000PF,50V,10%,X7R,A!C7F14!//jf4cfls225.pdx.intel.com/apd_proj/ppg_lib/epg_masterlib/logical/mstr_discrete/cap/chips/chips.prt!CAP!CAP_0402LF-1000PF,50V,10%,X7R,A36096-046!CAP!!!F3167!!VDDQ_ABC_PWR_VR!!
S!@baseboard_fab2_lib.baseboard_fab2(sch_1):page218_i26@mstr_discrete.cap(chips)!CAP_0402LF-1000PF,50V,10%,X7R,A!C7B3!//jf4cfls225.pdx.intel.com/apd_proj/ppg_lib/epg_masterlib/logical/mstr_discrete/cap/chips/chips.prt!CAP!CAP_0402LF-1000PF,50V,10%,X7R,A36096-046!CAP!!!F3171!!VDDQ_DEF_PWR_VR!!
S!@baseboard_fab2_lib.baseboard_fab2(sch_1):page223_i80@mstr_discrete.cap(chips)!CAP_0402LF-1000PF,50V,10%,X7R,A!C1G21!//jf4cfls225.pdx.intel.com/apd_proj/ppg_lib/epg_masterlib/logical/mstr_discrete/cap/chips/chips.prt!CAP!CAP_0402LF-1000PF,50V,10%,X7R,A36096-046!CAP!!!F3186!!VDDQ_GHJ_PWR_VR!!
S!@baseboard_fab2_lib.baseboard_fab2(sch_1):page226_i80@mstr_discrete.cap(chips)!CAP_0402LF-1000PF,50V,10%,X7R,A!C1B4!//jf4cfls225.pdx.intel.com/apd_proj/ppg_lib/epg_masterlib/logical/mstr_discrete/cap/chips/chips.prt!CAP!CAP_0402LF-1000PF,50V,10%,X7R,A36096-046!CAP!!!F3190!!VDDQ_KLM_PWR_VR!!
S!@baseboard_fab2_lib.baseboard_fab2(sch_1):page232_i209@mstr_discrete.cap(chips)!CAP_0402LF-1000PF,50V,10%,X7R,A!C7B12!//jf4cfls225.pdx.intel.com/apd_proj/ppg_lib/epg_masterlib/logical/mstr_discrete/cap/chips/chips.prt!CAP!CAP_0402LF-1000PF,50V,10%,X7R,A36096-046!CAP!!!F3170!!PVPP_KLM_VR!!
S!@baseboard_fab2_lib.baseboard_fab2(sch_1):page233_i201@mstr_discrete.cap(chips)!CAP_0402LF-1000PF,50V,10%,X7R,A!C4G9!//jf4cfls225.pdx.intel.com/apd_proj/ppg_lib/epg_masterlib/logical/mstr_discrete/cap/chips/chips.prt!CAP!CAP_0402LF-1000PF,50V,10%,X7R,A36096-046!CAP!!!F3175!!PVPP_KLM_VR!!
S!@baseboard_fab2_lib.baseboard_fab2(sch_1):page234_i139@mstr_discrete.cap(chips)!CAP_0402LF-1000PF,50V,10%,X7R,A!C4B8!//jf4cfls225.pdx.intel.com/apd_proj/ppg_lib/epg_masterlib/logical/mstr_discrete/cap/chips/chips.prt!CAP!CAP_0402LF-1000PF,50V,10%,X7R,A36096-046!CAP!!!F3180!!PVPP_KLM_VR!!
S!@baseboard_fab2_lib.baseboard_fab2(sch_1):page231_i142@mstr_discrete.cap(chips)!CAP_0402LF-1000PF,50V,10%,X7R,A!C7F11!//jf4cfls225.pdx.intel.com/apd_proj/ppg_lib/epg_masterlib/logical/mstr_discrete/cap/chips/chips.prt!CAP!CAP_0402LF-1000PF,50V,10%,X7R,A36096-046!CAP!!!F3168!!PVPP_KLM_VR!!
S!@baseboard_fab2_lib.baseboard_fab2(sch_1):page240_i116@mstr_discrete.cap(chips)!CAP_0402LF-1000PF,50V,10%,X7R,A!C8F2!//jf4cfls225.pdx.intel.com/apd_proj/ppg_lib/epg_masterlib/logical/mstr_discrete/cap/chips/chips.prt!CAP!CAP_0402LF-1000PF,50V,10%,X7R,A36096-046!CAP!!!F3162!!P3V3_STBY_VR!!
S!@baseboard_fab2_lib.baseboard_fab2(sch_1):page221_i15@mstr_discrete.cap(chips)!CAP_0402LF-1000PF,50V,10%,X7R,A!C4G14!//jf4cfls225.pdx.intel.com/apd_proj/ppg_lib/epg_masterlib/logical/mstr_discrete/cap/chips/chips.prt!CAP!CAP_0402LF-1000PF,50V,10%,X7R,A36096-046!CAP!!!F3173!!VTT_ABC_PWR_VR!!
S!@baseboard_fab2_lib.baseboard_fab2(sch_1):page222_i12@mstr_discrete.cap(chips)!CAP_0402LF-1000PF,50V,10%,X7R,A!C4A12!//jf4cfls225.pdx.intel.com/apd_proj/ppg_lib/epg_masterlib/logical/mstr_discrete/cap/chips/chips.prt!CAP!CAP_0402LF-1000PF,50V,10%,X7R,A36096-046!CAP!!!F3181!!VTT_DEF_PWR_VR!!
S!@baseboard_fab2_lib.baseboard_fab2(sch_1):page229_i15@mstr_discrete.cap(chips)!CAP_0402LF-1000PF,50V,10%,X7R,A!C4G13!//jf4cfls225.pdx.intel.com/apd_proj/ppg_lib/epg_masterlib/logical/mstr_discrete/cap/chips/chips.prt!CAP!CAP_0402LF-1000PF,50V,10%,X7R,A36096-046!CAP!!!F3174!!VTT_GHJ_PWR_VR!!
S!@baseboard_fab2_lib.baseboard_fab2(sch_1):page230_i16@mstr_discrete.cap(chips)!CAP_0402LF-1000PF,50V,10%,X7R,A!C4A3!//jf4cfls225.pdx.intel.com/apd_proj/ppg_lib/epg_masterlib/logical/mstr_discrete/cap/chips/chips.prt!CAP!CAP_0402LF-1000PF,50V,10%,X7R,A36096-046!CAP!!!F3182!!VTT_KLM_PWR_VR!!
S!@baseboard_fab2_lib.baseboard_fab2(sch_1):page237_i5@mstr_discrete.cap(chips)!CAP_0402LF-1000PF,50V,10%,X7R,A!C8A11!//jf4cfls225.pdx.intel.com/apd_proj/ppg_lib/epg_masterlib/logical/mstr_discrete/cap/chips/chips.prt!CAP!CAP_0402LF-1000PF,50V,10%,X7R,A36096-046!CAP!!!F3163!!P1V8_PCH_STBY_VR!!
S!@baseboard_fab2_lib.baseboard_fab2(sch_1):page235_i167@mstr_discrete.cap(chips)!CAP_0402LF-1000PF,50V,10%,X7R,A!C8A3!//jf4cfls225.pdx.intel.com/apd_proj/ppg_lib/epg_masterlib/logical/mstr_discrete/cap/chips/chips.prt!CAP!CAP_0402LF-1000PF,50V,10%,X7R,A36096-046!CAP!!!F3165!!PVNN_PCH_STBY!!
S!@baseboard_fab2_lib.baseboard_fab2(sch_1):page211_i33@mstr_discrete.cap(chips)!CAP_0402LF-1000PF,50V,10%,X7R,A!C3P2!//jf4cfls225.pdx.intel.com/apd_proj/ppg_lib/epg_masterlib/logical/mstr_discrete/cap/chips/chips.prt!CAP!CAP_0402LF-1000PF,50V,10%,X7R,A36096-046!CAP!!!F3184!!PVCCIO_CPU0!!
S!@baseboard_fab2_lib.baseboard_fab2(sch_1):page213_i33@mstr_discrete.cap(chips)!CAP_0402LF-1000PF,50V,10%,X7R,A!C4D40!//jf4cfls225.pdx.intel.com/apd_proj/ppg_lib/epg_masterlib/logical/mstr_discrete/cap/chips/chips.prt!CAP!CAP_0402LF-1000PF,50V,10%,X7R,A36096-046!CAP!!!F3177!!PVCCIO_CPU1!!
S!@baseboard_fab2_lib.baseboard_fab2(sch_1):page218_i55@mstr_discrete.cap(chips)!CAP_0402LF-1000PF,50V,10%,X7R,A!C7A35!//jf4cfls225.pdx.intel.com/apd_proj/ppg_lib/epg_masterlib/logical/mstr_discrete/cap/chips/chips.prt!CAP!CAP_0402LF-1000PF,50V,10%,X7R,A36096-046!CAP!!!F3172!!VDDQ_DEF_PWR_VR!!
S!@baseboard_fab2_lib.baseboard_fab2(sch_1):page223_i59@mstr_discrete.cap(chips)!CAP_0402LF-1000PF,50V,10%,X7R,A!C1G26!//jf4cfls225.pdx.intel.com/apd_proj/ppg_lib/epg_masterlib/logical/mstr_discrete/cap/chips/chips.prt!CAP!CAP_0402LF-1000PF,50V,10%,X7R,A36096-046!CAP!!!F3185!!VDDQ_GHJ_PWR_VR!!
S!@baseboard_fab2_lib.baseboard_fab2(sch_1):page226_i59@mstr_discrete.cap(chips)!CAP_0402LF-1000PF,50V,10%,X7R,A!C1B8!//jf4cfls225.pdx.intel.com/apd_proj/ppg_lib/epg_masterlib/logical/mstr_discrete/cap/chips/chips.prt!CAP!CAP_0402LF-1000PF,50V,10%,X7R,A36096-046!CAP!!!F3189!!VDDQ_KLM_PWR_VR!!
S!@baseboard_fab2_lib.baseboard_fab2(sch_1):page241_i14@mstr_discrete.cap(chips)!CAP_0402LF-1000PF,50V,10%,X7R,A!C7E10!//jf4cfls225.pdx.intel.com/apd_proj/ppg_lib/epg_masterlib/logical/mstr_discrete/cap/chips/chips.prt!CAP!CAP_0402LF-1000PF,50V,10%,X7R,A36096-046!CAP!!!F3169!!P5V_STBY_VR!!
S!@baseboard_fab2_lib.baseboard_fab2(sch_1):page238_i19@mstr_discrete.cap(chips)!CAP_0402LF-1000PF,50V,10%,X7R,A!C9F8!//jf4cfls225.pdx.intel.com/apd_proj/ppg_lib/epg_masterlib/logical/mstr_discrete/cap/chips/chips.prt!CAP!CAP_0402LF-1000PF,50V,10%,X7R,A36096-046!CAP!!!F3161!!P1V26_BMC_STBY_VR!!
S!@baseboard_fab2_lib.baseboard_fab2(sch_1):page239_i4@mstr_discrete.cap(chips)!CAP_0402LF-1000PF,50V,10%,X7R,A!C9F10!//jf4cfls225.pdx.intel.com/apd_proj/ppg_lib/epg_masterlib/logical/mstr_discrete/cap/chips/chips.prt!CAP!CAP_0402LF-1000PF,50V,10%,X7R,A36096-046!CAP!!!F3160!!P1V538_BMC_STBY_VR!!
S!@baseboard_fab2_lib.baseboard_fab2(sch_1):page215_i339@mstr_discrete.cap(chips)!CAP_0402LF-1000PF,50V,10%,X7R,A!C7G1!//jf4cfls225.pdx.intel.com/apd_proj/ppg_lib/epg_masterlib/logical/mstr_discrete/cap/chips/chips.prt!CAP!CAP_0402LF-1000PF,50V,10%,X7R,A36096-046!CAP!!!F3166!!VDDQ_ABC_PWR_VR!!
S!@baseboard_fab2_lib.baseboard_fab2(sch_1):page201_i60@mstr_discrete.cap(chips)!CAP_0402LF-1000PF,50V,10%,X7R,A!C4D20!//jf4cfls225.pdx.intel.com/apd_proj/ppg_lib/epg_masterlib/logical/mstr_discrete/cap/chips/chips.prt!CAP!CAP_0402LF-1000PF,50V,10%,X7R,A36096-046!CAP!!!F3179!!PVCCIN_CPU0_VR!!
S!@baseboard_fab2_lib.baseboard_fab2(sch_1):page206_i73@mstr_discrete.cap(chips)!CAP_0402LF-1000PF,50V,10%,X7R,A!C1C8!//jf4cfls225.pdx.intel.com/apd_proj/ppg_lib/epg_masterlib/logical/mstr_discrete/cap/chips/chips.prt!CAP!CAP_0402LF-1000PF,50V,10%,X7R,A36096-046!CAP!!!F3188!!PVCCIN_CPU1_VR!!
S!@baseboard_fab2_lib.baseboard_fab2(sch_1):page114_i56@mstr_discrete.cap(chips)!CAP_0402LF-18PF,50V,5%,C0G,A36A!C7C13!//jf4cfls225.pdx.intel.com/apd_proj/ppg_lib/epg_masterlib/logical/mstr_discrete/cap/chips/chips.prt!CAP!CAP_0402LF-18PF,50V,5%,C0G,A36095-042!CAP!!!F3155!!SB!!
S!@baseboard_fab2_lib.baseboard_fab2(sch_1):page114_i46@mstr_discrete.cap(chips)!CAP_0402LF-18PF,50V,5%,C0G,A36A!C7C15!//jf4cfls225.pdx.intel.com/apd_proj/ppg_lib/epg_masterlib/logical/mstr_discrete/cap/chips/chips.prt!CAP!CAP_0402LF-18PF,50V,5%,C0G,A36095-042!CAP!!!F3154!!SB!!
S!@baseboard_fab2_lib.baseboard_fab2(sch_1):page139_i112@mstr_discrete.cap(chips)!CAP_0402LF-22.0PF,50V,5%,COG,AA!C9E9!//jf4cfls225.pdx.intel.com/apd_proj/ppg_lib/epg_masterlib/logical/mstr_discrete/cap/chips/chips.prt!CAP!CAP_0402LF-22.0PF,50V,5%,COG,A36095-030!CAP!!!F3152!!NIC_SPRV!!
S!@baseboard_fab2_lib.baseboard_fab2(sch_1):page139_i111@mstr_discrete.cap(chips)!CAP_0402LF-22.0PF,50V,5%,COG,AA!C9E8!//jf4cfls225.pdx.intel.com/apd_proj/ppg_lib/epg_masterlib/logical/mstr_discrete/cap/chips/chips.prt!CAP!CAP_0402LF-22.0PF,50V,5%,COG,A36095-030!CAP!!!F3153!!NIC_SPRV!!
S!@baseboard_fab2_lib.baseboard_fab2(sch_1):page232_i306@mstr_discrete.cap(chips)!CAP_0402LF-2200PF,50V,10%,X7R,A!C7B14!//jf4cfls225.pdx.intel.com/apd_proj/ppg_lib/epg_masterlib/logical/mstr_discrete/cap/chips/chips.prt!CAP!CAP_0402LF-2200PF,50V,10%,X7R,A36096-075!CAP!!!F3146!!PVPP_KLM_VR!!
S!@baseboard_fab2_lib.baseboard_fab2(sch_1):page234_i218@mstr_discrete.cap(chips)!CAP_0402LF-2200PF,50V,10%,X7R,A!C4B7!//jf4cfls225.pdx.intel.com/apd_proj/ppg_lib/epg_masterlib/logical/mstr_discrete/cap/chips/chips.prt!CAP!CAP_0402LF-2200PF,50V,10%,X7R,A36096-075!CAP!!!F3151!!PVPP_KLM_VR!!
S!@baseboard_fab2_lib.baseboard_fab2(sch_1):page234_i211@mstr_discrete.cap(chips)!CAP_0402LF-2200PF,50V,10%,X7R,A!C4B9!//jf4cfls225.pdx.intel.com/apd_proj/ppg_lib/epg_masterlib/logical/mstr_discrete/cap/chips/chips.prt!CAP!CAP_0402LF-2200PF,50V,10%,X7R,A36096-075!CAP!!!F3150!!PVPP_KLM_VR!!
S!@baseboard_fab2_lib.baseboard_fab2(sch_1):page233_i274@mstr_discrete.cap(chips)!CAP_0402LF-2200PF,50V,10%,X7R,A!C4G10!//jf4cfls225.pdx.intel.com/apd_proj/ppg_lib/epg_masterlib/logical/mstr_discrete/cap/chips/chips.prt!CAP!CAP_0402LF-2200PF,50V,10%,X7R,A36096-075!CAP!!!F3149!!PVPP_KLM_VR!!
S!@baseboard_fab2_lib.baseboard_fab2(sch_1):page233_i267@mstr_discrete.cap(chips)!CAP_0402LF-2200PF,50V,10%,X7R,A!C4G11!//jf4cfls225.pdx.intel.com/apd_proj/ppg_lib/epg_masterlib/logical/mstr_discrete/cap/chips/chips.prt!CAP!CAP_0402LF-2200PF,50V,10%,X7R,A36096-075!CAP!!!F3148!!PVPP_KLM_VR!!
S!@baseboard_fab2_lib.baseboard_fab2(sch_1):page232_i302@mstr_discrete.cap(chips)!CAP_0402LF-2200PF,50V,10%,X7R,A!C7B13!//jf4cfls225.pdx.intel.com/apd_proj/ppg_lib/epg_masterlib/logical/mstr_discrete/cap/chips/chips.prt!CAP!CAP_0402LF-2200PF,50V,10%,X7R,A36096-075!CAP!!!F3147!!PVPP_KLM_VR!!
S!@baseboard_fab2_lib.baseboard_fab2(sch_1):page231_i200@mstr_discrete.cap(chips)!CAP_0402LF-2200PF,50V,10%,X7R,A!C7F12!//jf4cfls225.pdx.intel.com/apd_proj/ppg_lib/epg_masterlib/logical/mstr_discrete/cap/chips/chips.prt!CAP!CAP_0402LF-2200PF,50V,10%,X7R,A36096-075!CAP!!!F3145!!PVPP_KLM_VR!!
S!@baseboard_fab2_lib.baseboard_fab2(sch_1):page231_i219@mstr_discrete.cap(chips)!CAP_0402LF-2200PF,50V,10%,X7R,A!C7F13!//jf4cfls225.pdx.intel.com/apd_proj/ppg_lib/epg_masterlib/logical/mstr_discrete/cap/chips/chips.prt!CAP!CAP_0402LF-2200PF,50V,10%,X7R,A36096-075!CAP!!!F3144!!PVPP_KLM_VR!!
S!@baseboard_fab2_lib.baseboard_fab2(sch_1):page241_i57@mstr_discrete.cap(chips)!CAP_0402LF-2200PF,50V,10%,X7R,A!C8F1!//jf4cfls225.pdx.intel.com/apd_proj/ppg_lib/epg_masterlib/logical/mstr_discrete/cap/chips/chips.prt!CAP!CAP_0402LF-2200PF,50V,10%,X7R,A36096-075!CAP!!!F3143!!P5V_STBY_VR!!
S!@baseboard_fab2_lib.baseboard_fab2(sch_1):page235_i153@mstr_discrete.cap(chips)!CAP_0402LF-220PF,50V,10%,X7R,AA!C2L2!//jf4cfls225.pdx.intel.com/apd_proj/ppg_lib/epg_masterlib/logical/mstr_discrete/cap/chips/chips.prt!CAP!CAP_0402LF-220PF,50V,10%,X7R,A36096-050!CAP!!!F3134!!PVNN_PCH_STBY!!
S!@baseboard_fab2_lib.baseboard_fab2(sch_1):page235_i209@mstr_discrete.cap(chips)!CAP_0402LF-220PF,50V,10%,X7R,AA!C8A2!//jf4cfls225.pdx.intel.com/apd_proj/ppg_lib/epg_masterlib/logical/mstr_discrete/cap/chips/chips.prt!CAP!CAP_0402LF-220PF,50V,10%,X7R,A36096-050!CAP!!!F3123!!PVNN_PCH_STBY!!
S!@baseboard_fab2_lib.baseboard_fab2(sch_1):page211_i83@mstr_discrete.cap(chips)!CAP_0402LF-220PF,50V,10%,X7R,AA!C3N39!//jf4cfls225.pdx.intel.com/apd_proj/ppg_lib/epg_masterlib/logical/mstr_discrete/cap/chips/chips.prt!CAP!CAP_0402LF-220PF,50V,10%,X7R,A36096-050!CAP!!!F3133!!PVCCIO_CPU0!!
S!@baseboard_fab2_lib.baseboard_fab2(sch_1):page213_i83@mstr_discrete.cap(chips)!CAP_0402LF-220PF,50V,10%,X7R,AA!C4D44!//jf4cfls225.pdx.intel.com/apd_proj/ppg_lib/epg_masterlib/logical/mstr_discrete/cap/chips/chips.prt!CAP!CAP_0402LF-220PF,50V,10%,X7R,A36096-050!CAP!!!F3129!!PVCCIO_CPU1!!
S!@baseboard_fab2_lib.baseboard_fab2(sch_1):page218_i39@mstr_discrete.cap(chips)!CAP_0402LF-220PF,50V,10%,X7R,AA!C7A29!//jf4cfls225.pdx.intel.com/apd_proj/ppg_lib/epg_masterlib/logical/mstr_discrete/cap/chips/chips.prt!CAP!CAP_0402LF-220PF,50V,10%,X7R,A36096-050!CAP!!!F3126!!VDDQ_DEF_PWR_VR!!
S!@baseboard_fab2_lib.baseboard_fab2(sch_1):page218_i61@mstr_discrete.cap(chips)!CAP_0402LF-220PF,50V,10%,X7R,AA!C7A28!//jf4cfls225.pdx.intel.com/apd_proj/ppg_lib/epg_masterlib/logical/mstr_discrete/cap/chips/chips.prt!CAP!CAP_0402LF-220PF,50V,10%,X7R,A36096-050!CAP!!!F3127!!VDDQ_DEF_PWR_VR!!
S!@baseboard_fab2_lib.baseboard_fab2(sch_1):page223_i36@mstr_discrete.cap(chips)!CAP_0402LF-220PF,50V,10%,X7R,AA!C1G24!//jf4cfls225.pdx.intel.com/apd_proj/ppg_lib/epg_masterlib/logical/mstr_discrete/cap/chips/chips.prt!CAP!CAP_0402LF-220PF,50V,10%,X7R,A36096-050!CAP!!!F3135!!VDDQ_GHJ_PWR_VR!!
S!@baseboard_fab2_lib.baseboard_fab2(sch_1):page223_i39@mstr_discrete.cap(chips)!CAP_0402LF-220PF,50V,10%,X7R,AA!C1G16!//jf4cfls225.pdx.intel.com/apd_proj/ppg_lib/epg_masterlib/logical/mstr_discrete/cap/chips/chips.prt!CAP!CAP_0402LF-220PF,50V,10%,X7R,A36096-050!CAP!!!F3136!!VDDQ_GHJ_PWR_VR!!
S!@baseboard_fab2_lib.baseboard_fab2(sch_1):page226_i36@mstr_discrete.cap(chips)!CAP_0402LF-220PF,50V,10%,X7R,AA!C1B11!//jf4cfls225.pdx.intel.com/apd_proj/ppg_lib/epg_masterlib/logical/mstr_discrete/cap/chips/chips.prt!CAP!CAP_0402LF-220PF,50V,10%,X7R,A36096-050!CAP!!!F3142!!VDDQ_KLM_PWR_VR!!
S!@baseboard_fab2_lib.baseboard_fab2(sch_1):page226_i39@mstr_discrete.cap(chips)!CAP_0402LF-220PF,50V,10%,X7R,AA!C1B12!//jf4cfls225.pdx.intel.com/apd_proj/ppg_lib/epg_masterlib/logical/mstr_discrete/cap/chips/chips.prt!CAP!CAP_0402LF-220PF,50V,10%,X7R,A36096-050!CAP!!!F3141!!VDDQ_KLM_PWR_VR!!
S!@baseboard_fab2_lib.baseboard_fab2(sch_1):page215_i342@mstr_discrete.cap(chips)!CAP_0402LF-220PF,50V,10%,X7R,AA!C7G4!//jf4cfls225.pdx.intel.com/apd_proj/ppg_lib/epg_masterlib/logical/mstr_discrete/cap/chips/chips.prt!CAP!CAP_0402LF-220PF,50V,10%,X7R,A36096-050!CAP!!!F3124!!VDDQ_ABC_PWR_VR!!
S!@baseboard_fab2_lib.baseboard_fab2(sch_1):page215_i320@mstr_discrete.cap(chips)!CAP_0402LF-220PF,50V,10%,X7R,AA!C7G3!//jf4cfls225.pdx.intel.com/apd_proj/ppg_lib/epg_masterlib/logical/mstr_discrete/cap/chips/chips.prt!CAP!CAP_0402LF-220PF,50V,10%,X7R,A36096-050!CAP!!!F3125!!VDDQ_ABC_PWR_VR!!
S!@baseboard_fab2_lib.baseboard_fab2(sch_1):page201_i70@mstr_discrete.cap(chips)!CAP_0402LF-220PF,50V,10%,X7R,AA!C4D45!//jf4cfls225.pdx.intel.com/apd_proj/ppg_lib/epg_masterlib/logical/mstr_discrete/cap/chips/chips.prt!CAP!CAP_0402LF-220PF,50V,10%,X7R,A36096-050!CAP!!!F3128!!PVCCIN_CPU0_VR!!
S!@baseboard_fab2_lib.baseboard_fab2(sch_1):page201_i68@mstr_discrete.cap(chips)!CAP_0402LF-220PF,50V,10%,X7R,AA!C4D18!//jf4cfls225.pdx.intel.com/apd_proj/ppg_lib/epg_masterlib/logical/mstr_discrete/cap/chips/chips.prt!CAP!CAP_0402LF-220PF,50V,10%,X7R,A36096-050!CAP!!!F3131!!PVCCIN_CPU0_VR!!
S!@baseboard_fab2_lib.baseboard_fab2(sch_1):page201_i66@mstr_discrete.cap(chips)!CAP_0402LF-220PF,50V,10%,X7R,AA!C4D17!//jf4cfls225.pdx.intel.com/apd_proj/ppg_lib/epg_masterlib/logical/mstr_discrete/cap/chips/chips.prt!CAP!CAP_0402LF-220PF,50V,10%,X7R,A36096-050!CAP!!!F3132!!PVCCIN_CPU0_VR!!
S!@baseboard_fab2_lib.baseboard_fab2(sch_1):page201_i64@mstr_discrete.cap(chips)!CAP_0402LF-220PF,50V,10%,X7R,AA!C4D29!//jf4cfls225.pdx.intel.com/apd_proj/ppg_lib/epg_masterlib/logical/mstr_discrete/cap/chips/chips.prt!CAP!CAP_0402LF-220PF,50V,10%,X7R,A36096-050!CAP!!!F3130!!PVCCIN_CPU0_VR!!
S!@baseboard_fab2_lib.baseboard_fab2(sch_1):page206_i78@mstr_discrete.cap(chips)!CAP_0402LF-220PF,50V,10%,X7R,AA!C1D1!//jf4cfls225.pdx.intel.com/apd_proj/ppg_lib/epg_masterlib/logical/mstr_discrete/cap/chips/chips.prt!CAP!CAP_0402LF-220PF,50V,10%,X7R,A36096-050!CAP!!!F3137!!PVCCIN_CPU1_VR!!
S!@baseboard_fab2_lib.baseboard_fab2(sch_1):page206_i71@mstr_discrete.cap(chips)!CAP_0402LF-220PF,50V,10%,X7R,AA!C1C11!//jf4cfls225.pdx.intel.com/apd_proj/ppg_lib/epg_masterlib/logical/mstr_discrete/cap/chips/chips.prt!CAP!CAP_0402LF-220PF,50V,10%,X7R,A36096-050!CAP!!!F3139!!PVCCIN_CPU1_VR!!
S!@baseboard_fab2_lib.baseboard_fab2(sch_1):page206_i69@mstr_discrete.cap(chips)!CAP_0402LF-220PF,50V,10%,X7R,AA!C1C10!//jf4cfls225.pdx.intel.com/apd_proj/ppg_lib/epg_masterlib/logical/mstr_discrete/cap/chips/chips.prt!CAP!CAP_0402LF-220PF,50V,10%,X7R,A36096-050!CAP!!!F3140!!PVCCIN_CPU1_VR!!
S!@baseboard_fab2_lib.baseboard_fab2(sch_1):page206_i68@mstr_discrete.cap(chips)!CAP_0402LF-220PF,50V,10%,X7R,AA!C1C16!//jf4cfls225.pdx.intel.com/apd_proj/ppg_lib/epg_masterlib/logical/mstr_discrete/cap/chips/chips.prt!CAP!CAP_0402LF-220PF,50V,10%,X7R,A36096-050!CAP!!!F3138!!PVCCIN_CPU1_VR!!
S!@baseboard_fab2_lib.baseboard_fab2(sch_1):page101_i53@mstr_discrete.cap(chips)!CAP_0402LF-27.0PF,50V,5%,COG,AA!C8F19!//jf4cfls225.pdx.intel.com/apd_proj/ppg_lib/epg_masterlib/logical/mstr_discrete/cap/chips/chips.prt!CAP!CAP_0402LF-27.0PF,50V,5%,COG,A36095-038!CAP!!!F3121!!SYS_CLOCK!!
S!@baseboard_fab2_lib.baseboard_fab2(sch_1):page101_i49@mstr_discrete.cap(chips)!CAP_0402LF-27.0PF,50V,5%,COG,AA!C8F18!//jf4cfls225.pdx.intel.com/apd_proj/ppg_lib/epg_masterlib/logical/mstr_discrete/cap/chips/chips.prt!CAP!CAP_0402LF-27.0PF,50V,5%,COG,A36095-038!CAP!!!F3122!!SYS_CLOCK!!
S!@baseboard_fab2_lib.baseboard_fab2(sch_1):page241_i53@mstr_discrete.cap(chips)!CAP_0402LF-270PF,50V,10%,X7R,AA!C8E16!//jf4cfls225.pdx.intel.com/apd_proj/ppg_lib/epg_masterlib/logical/mstr_discrete/cap/chips/chips.prt!CAP!CAP_0402LF-270PF,50V,10%,X7R,A36096-065!CAP!!!F3120!!P5V_STBY_VR!!
S!@baseboard_fab2_lib.baseboard_fab2(sch_1):page232_i220@mstr_discrete.cap(chips)!CAP_0402LF-3300PF,50V,10%,EMPTA!C7A34!//jf4cfls225.pdx.intel.com/apd_proj/ppg_lib/epg_masterlib/logical/mstr_discrete/cap/chips/chips.prt!CAP!CAP_0402LF-3300PF,50V,10%,EMPTY,A36096-091!CAP!!!F3115!!PVPP_KLM_VR!!
S!@baseboard_fab2_lib.baseboard_fab2(sch_1):page233_i209@mstr_discrete.cap(chips)!CAP_0402LF-3300PF,50V,10%,EMPTA!C4F12!//jf4cfls225.pdx.intel.com/apd_proj/ppg_lib/epg_masterlib/logical/mstr_discrete/cap/chips/chips.prt!CAP!CAP_0402LF-3300PF,50V,10%,EMPTY,A36096-091!CAP!!!F3116!!PVPP_KLM_VR!!
S!@baseboard_fab2_lib.baseboard_fab2(sch_1):page234_i163@mstr_discrete.cap(chips)!CAP_0402LF-3300PF,50V,10%,EMPTA!C4A16!//jf4cfls225.pdx.intel.com/apd_proj/ppg_lib/epg_masterlib/logical/mstr_discrete/cap/chips/chips.prt!CAP!CAP_0402LF-3300PF,50V,10%,EMPTY,A36096-091!CAP!!!F3117!!PVPP_KLM_VR!!
S!@baseboard_fab2_lib.baseboard_fab2(sch_1):page231_i175@mstr_discrete.cap(chips)!CAP_0402LF-3300PF,50V,10%,EMPTA!C7F3!//jf4cfls225.pdx.intel.com/apd_proj/ppg_lib/epg_masterlib/logical/mstr_discrete/cap/chips/chips.prt!CAP!CAP_0402LF-3300PF,50V,10%,EMPTY,A36096-091!CAP!!!F3114!!PVPP_KLM_VR!!
S!@baseboard_fab2_lib.baseboard_fab2(sch_1):page240_i163@mstr_discrete.cap(chips)!CAP_0402LF-3300PF,50V,10%,EMPTA!C8F3!//jf4cfls225.pdx.intel.com/apd_proj/ppg_lib/epg_masterlib/logical/mstr_discrete/cap/chips/chips.prt!CAP!CAP_0402LF-3300PF,50V,10%,EMPTY,A36096-091!CAP!!!F3113!!P3V3_STBY_VR!!
S!@baseboard_fab2_lib.baseboard_fab2(sch_1):page169_i153@mstr_discrete.cap(chips)!CAP_0402LF-47.0PF,50V,5%,COG,AA!C9G18!//jf4cfls225.pdx.intel.com/apd_proj/ppg_lib/epg_masterlib/logical/mstr_discrete/cap/chips/chips.prt!CAP!CAP_0402LF-47.0PF,50V,5%,COG,A36095-025!CAP!!!F3108!!BMC_VOLT_MONITOR!!
S!@baseboard_fab2_lib.baseboard_fab2(sch_1):page169_i139@mstr_discrete.cap(chips)!CAP_0402LF-47.0PF,50V,5%,COG,AA!C9G15!//jf4cfls225.pdx.intel.com/apd_proj/ppg_lib/epg_masterlib/logical/mstr_discrete/cap/chips/chips.prt!CAP!CAP_0402LF-47.0PF,50V,5%,COG,A36095-025!CAP!!!F3110!!BMC_VOLT_MONITOR!!
S!@baseboard_fab2_lib.baseboard_fab2(sch_1):page169_i146@mstr_discrete.cap(chips)!CAP_0402LF-47.0PF,50V,5%,COG,AA!C9G14!//jf4cfls225.pdx.intel.com/apd_proj/ppg_lib/epg_masterlib/logical/mstr_discrete/cap/chips/chips.prt!CAP!CAP_0402LF-47.0PF,50V,5%,COG,A36095-025!CAP!!!F3111!!BMC_VOLT_MONITOR!!
S!@baseboard_fab2_lib.baseboard_fab2(sch_1):page169_i56@mstr_discrete.cap(chips)!CAP_0402LF-47.0PF,50V,5%,COG,AA!C1U21!//jf4cfls225.pdx.intel.com/apd_proj/ppg_lib/epg_masterlib/logical/mstr_discrete/cap/chips/chips.prt!CAP!CAP_0402LF-47.0PF,50V,5%,COG,A36095-025!CAP!!!F3112!!BMC_VOLT_MONITOR!!
S!@baseboard_fab2_lib.baseboard_fab2(sch_1):page169_i68@mstr_discrete.cap(chips)!CAP_0402LF-47.0PF,50V,5%,COG,AA!C9G21!//jf4cfls225.pdx.intel.com/apd_proj/ppg_lib/epg_masterlib/logical/mstr_discrete/cap/chips/chips.prt!CAP!CAP_0402LF-47.0PF,50V,5%,COG,A36095-025!CAP!!!F3106!!BMC_VOLT_MONITOR!!
S!@baseboard_fab2_lib.baseboard_fab2(sch_1):page169_i80@mstr_discrete.cap(chips)!CAP_0402LF-47.0PF,50V,5%,COG,AA!C9G17!//jf4cfls225.pdx.intel.com/apd_proj/ppg_lib/epg_masterlib/logical/mstr_discrete/cap/chips/chips.prt!CAP!CAP_0402LF-47.0PF,50V,5%,COG,A36095-025!CAP!!!F3109!!BMC_VOLT_MONITOR!!
S!@baseboard_fab2_lib.baseboard_fab2(sch_1):page169_i86@mstr_discrete.cap(chips)!CAP_0402LF-47.0PF,50V,5%,COG,AA!C9G20!//jf4cfls225.pdx.intel.com/apd_proj/ppg_lib/epg_masterlib/logical/mstr_discrete/cap/chips/chips.prt!CAP!CAP_0402LF-47.0PF,50V,5%,COG,A36095-025!CAP!!!F3107!!BMC_VOLT_MONITOR!!
S!@baseboard_fab2_lib.baseboard_fab2(sch_1):page141_i60@mstr_discrete.cap(chips)!CAP_0402LF-470PF,50V,10%,X7R,AA!C9F22!//jf4cfls225.pdx.intel.com/apd_proj/ppg_lib/epg_masterlib/logical/mstr_discrete/cap/chips/chips.prt!CAP!CAP_0402LF-470PF,50V,10%,X7R,A36096-049!CAP!!!F3097!!NIC_SPRV!!
S!@baseboard_fab2_lib.baseboard_fab2(sch_1):page141_i58@mstr_discrete.cap(chips)!CAP_0402LF-470PF,50V,10%,X7R,AA!C9G1!//jf4cfls225.pdx.intel.com/apd_proj/ppg_lib/epg_masterlib/logical/mstr_discrete/cap/chips/chips.prt!CAP!CAP_0402LF-470PF,50V,10%,X7R,A36096-049!CAP!!!F3096!!NIC_SPRV!!
S!@baseboard_fab2_lib.baseboard_fab2(sch_1):page141_i59@mstr_discrete.cap(chips)!CAP_0402LF-470PF,50V,10%,X7R,AA!C9G3!//jf4cfls225.pdx.intel.com/apd_proj/ppg_lib/epg_masterlib/logical/mstr_discrete/cap/chips/chips.prt!CAP!CAP_0402LF-470PF,50V,10%,X7R,A36096-049!CAP!!!F3094!!NIC_SPRV!!
S!@baseboard_fab2_lib.baseboard_fab2(sch_1):page141_i36@mstr_discrete.cap(chips)!CAP_0402LF-470PF,50V,10%,X7R,AA!C9G2!//jf4cfls225.pdx.intel.com/apd_proj/ppg_lib/epg_masterlib/logical/mstr_discrete/cap/chips/chips.prt!CAP!CAP_0402LF-470PF,50V,10%,X7R,A36096-049!CAP!!!F3095!!NIC_SPRV!!
S!@baseboard_fab2_lib.baseboard_fab2(sch_1):page149_i85@mstr_discrete.cap(chips)!CAP_0603-0.47UF,16V,10%,X7R,20A!C1T42!//jf4cfls225.pdx.intel.com/apd_proj/ppg_lib/epg_masterlib/logical/mstr_discrete/cap/chips/chips.prt!CAP!CAP_0603-0.47UF,16V,10%,X7R,202297-006!CAP!!!F3093!!BMC!!
S!@baseboard_fab2_lib.baseboard_fab2(sch_1):page237_i29@mstr_discrete.cap(chips)!CAP_0603-10UF,6.3V,20%,X6S,E15A!C8A6!//jf4cfls225.pdx.intel.com/apd_proj/ppg_lib/epg_masterlib/logical/mstr_discrete/cap/chips/chips.prt!CAP!CAP_0603-10UF,6.3V,20%,X6S,E15431-002!CAP!!!F3075!!P1V8_PCH_STBY_VR!!
S!@baseboard_fab2_lib.baseboard_fab2(sch_1):page130_i25@mstr_discrete.cap(chips)!CAP_0603-10UF,6.3V,20%,X6S,E15A!C2N14!//jf4cfls225.pdx.intel.com/apd_proj/ppg_lib/epg_masterlib/logical/mstr_discrete/cap/chips/chips.prt!CAP!CAP_0603-10UF,6.3V,20%,X6S,E15431-002!CAP!!!F3082!!SB_DECOUPLING!!
S!@baseboard_fab2_lib.baseboard_fab2(sch_1):page130_i22@mstr_discrete.cap(chips)!CAP_0603-10UF,6.3V,20%,X6S,E15A!C8C6!//jf4cfls225.pdx.intel.com/apd_proj/ppg_lib/epg_masterlib/logical/mstr_discrete/cap/chips/chips.prt!CAP!CAP_0603-10UF,6.3V,20%,X6S,E15431-002!CAP!!!F3071!!SB_DECOUPLING!!
S!@baseboard_fab2_lib.baseboard_fab2(sch_1):page130_i24@mstr_discrete.cap(chips)!CAP_0603-10UF,6.3V,20%,X6S,E15A!C2N23!//jf4cfls225.pdx.intel.com/apd_proj/ppg_lib/epg_masterlib/logical/mstr_discrete/cap/chips/chips.prt!CAP!CAP_0603-10UF,6.3V,20%,X6S,E15431-002!CAP!!!F3078!!SB_DECOUPLING!!
S!@baseboard_fab2_lib.baseboard_fab2(sch_1):page130_i21@mstr_discrete.cap(chips)!CAP_0603-10UF,6.3V,20%,X6S,E15A!C8C5!//jf4cfls225.pdx.intel.com/apd_proj/ppg_lib/epg_masterlib/logical/mstr_discrete/cap/chips/chips.prt!CAP!CAP_0603-10UF,6.3V,20%,X6S,E15431-002!CAP!!!F3072!!SB_DECOUPLING!!
S!@baseboard_fab2_lib.baseboard_fab2(sch_1):page130_i20@mstr_discrete.cap(chips)!CAP_0603-10UF,6.3V,20%,X6S,E15A!C8C4!//jf4cfls225.pdx.intel.com/apd_proj/ppg_lib/epg_masterlib/logical/mstr_discrete/cap/chips/chips.prt!CAP!CAP_0603-10UF,6.3V,20%,X6S,E15431-002!CAP!!!F3073!!SB_DECOUPLING!!
S!@baseboard_fab2_lib.baseboard_fab2(sch_1):page130_i19@mstr_discrete.cap(chips)!CAP_0603-10UF,6.3V,20%,X6S,E15A!C8C3!//jf4cfls225.pdx.intel.com/apd_proj/ppg_lib/epg_masterlib/logical/mstr_discrete/cap/chips/chips.prt!CAP!CAP_0603-10UF,6.3V,20%,X6S,E15431-002!CAP!!!F3074!!SB_DECOUPLING!!
S!@baseboard_fab2_lib.baseboard_fab2(sch_1):page130_i2@mstr_discrete.cap(chips)!CAP_0603-10UF,6.3V,20%,X6S,E15A!C7D2!//jf4cfls225.pdx.intel.com/apd_proj/ppg_lib/epg_masterlib/logical/mstr_discrete/cap/chips/chips.prt!CAP!CAP_0603-10UF,6.3V,20%,X6S,E15431-002!CAP!!!F3076!!SB_DECOUPLING!!
S!@baseboard_fab2_lib.baseboard_fab2(sch_1):page130_i15@mstr_discrete.cap(chips)!CAP_0603-10UF,6.3V,20%,X6S,E15A!C2N21!//jf4cfls225.pdx.intel.com/apd_proj/ppg_lib/epg_masterlib/logical/mstr_discrete/cap/chips/chips.prt!CAP!CAP_0603-10UF,6.3V,20%,X6S,E15431-002!CAP!!!F3080!!SB_DECOUPLING!!
S!@baseboard_fab2_lib.baseboard_fab2(sch_1):page130_i9@mstr_discrete.cap(chips)!CAP_0603-10UF,6.3V,20%,X6S,E15A!C2N22!//jf4cfls225.pdx.intel.com/apd_proj/ppg_lib/epg_masterlib/logical/mstr_discrete/cap/chips/chips.prt!CAP!CAP_0603-10UF,6.3V,20%,X6S,E15431-002!CAP!!!F3079!!SB_DECOUPLING!!
S!@baseboard_fab2_lib.baseboard_fab2(sch_1):page130_i8@mstr_discrete.cap(chips)!CAP_0603-10UF,6.3V,20%,X6S,E15A!C2N24!//jf4cfls225.pdx.intel.com/apd_proj/ppg_lib/epg_masterlib/logical/mstr_discrete/cap/chips/chips.prt!CAP!CAP_0603-10UF,6.3V,20%,X6S,E15431-002!CAP!!!F3077!!SB_DECOUPLING!!
S!@baseboard_fab2_lib.baseboard_fab2(sch_1):page130_i28@mstr_discrete.cap(chips)!CAP_0603-10UF,6.3V,20%,X6S,E15A!C2N17!//jf4cfls225.pdx.intel.com/apd_proj/ppg_lib/epg_masterlib/logical/mstr_discrete/cap/chips/chips.prt!CAP!CAP_0603-10UF,6.3V,20%,X6S,E15431-002!CAP!!!F3081!!SB_DECOUPLING!!
S!@baseboard_fab2_lib.baseboard_fab2(sch_1):page238_i7@mstr_discrete.cap(chips)!CAP_0603-10UF,6.3V,20%,X6S,E15A!C9F3!//jf4cfls225.pdx.intel.com/apd_proj/ppg_lib/epg_masterlib/logical/mstr_discrete/cap/chips/chips.prt!CAP!CAP_0603-10UF,6.3V,20%,X6S,E15431-002!CAP!!!F3069!!P1V26_BMC_STBY_VR!!
S!@baseboard_fab2_lib.baseboard_fab2(sch_1):page238_i23@mstr_discrete.cap(chips)!CAP_0603-10UF,6.3V,20%,X6S,E15A!C9E10!//jf4cfls225.pdx.intel.com/apd_proj/ppg_lib/epg_masterlib/logical/mstr_discrete/cap/chips/chips.prt!CAP!CAP_0603-10UF,6.3V,20%,X6S,E15431-002!CAP!!!F3070!!P1V26_BMC_STBY_VR!!
S!@baseboard_fab2_lib.baseboard_fab2(sch_1):page239_i22@mstr_discrete.cap(chips)!CAP_0603-10UF,6.3V,20%,X6S,E15A!C1T7!//jf4cfls225.pdx.intel.com/apd_proj/ppg_lib/epg_masterlib/logical/mstr_discrete/cap/chips/chips.prt!CAP!CAP_0603-10UF,6.3V,20%,X6S,E15431-002!CAP!!!F3084!!P1V538_BMC_STBY_VR!!
S!@baseboard_fab2_lib.baseboard_fab2(sch_1):page239_i12@mstr_discrete.cap(chips)!CAP_0603-10UF,6.3V,20%,X6S,E15A!C1T15!//jf4cfls225.pdx.intel.com/apd_proj/ppg_lib/epg_masterlib/logical/mstr_discrete/cap/chips/chips.prt!CAP!CAP_0603-10UF,6.3V,20%,X6S,E15431-002!CAP!!!F3083!!P1V538_BMC_STBY_VR!!
S!@baseboard_fab2_lib.baseboard_fab2(sch_1):page139_i136@mstr_discrete.cap(chips)!CAP_0603-10UF,6.3V,20%,X6S,E15A!C1R22!//jf4cfls225.pdx.intel.com/apd_proj/ppg_lib/epg_masterlib/logical/mstr_discrete/cap/chips/chips.prt!CAP!CAP_0603-10UF,6.3V,20%,X6S,E15431-002!CAP!!!F3087!!NIC_SPRV!!
S!@baseboard_fab2_lib.baseboard_fab2(sch_1):page139_i135@mstr_discrete.cap(chips)!CAP_0603-10UF,6.3V,20%,X6S,E15A!C1R30!//jf4cfls225.pdx.intel.com/apd_proj/ppg_lib/epg_masterlib/logical/mstr_discrete/cap/chips/chips.prt!CAP!CAP_0603-10UF,6.3V,20%,X6S,E15431-002!CAP!!!F3086!!NIC_SPRV!!
S!@baseboard_fab2_lib.baseboard_fab2(sch_1):page139_i134@mstr_discrete.cap(chips)!CAP_0603-10UF,6.3V,20%,X6S,E15A!C1T4!//jf4cfls225.pdx.intel.com/apd_proj/ppg_lib/epg_masterlib/logical/mstr_discrete/cap/chips/chips.prt!CAP!CAP_0603-10UF,6.3V,20%,X6S,E15431-002!CAP!!!F3085!!NIC_SPRV!!
S!@baseboard_fab2_lib.baseboard_fab2(sch_1):page139_i142@mstr_discrete.cap(chips)!CAP_0603-10UF,6.3V,20%,X6S,E15A!C1R13!//jf4cfls225.pdx.intel.com/apd_proj/ppg_lib/epg_masterlib/logical/mstr_discrete/cap/chips/chips.prt!CAP!CAP_0603-10UF,6.3V,20%,X6S,E15431-002!CAP!!!F3090!!NIC_SPRV!!
S!@baseboard_fab2_lib.baseboard_fab2(sch_1):page139_i153@mstr_discrete.cap(chips)!CAP_0603-10UF,6.3V,20%,X6S,E15A!C1R17!//jf4cfls225.pdx.intel.com/apd_proj/ppg_lib/epg_masterlib/logical/mstr_discrete/cap/chips/chips.prt!CAP!CAP_0603-10UF,6.3V,20%,X6S,E15431-002!CAP!!!F3088!!NIC_SPRV!!
S!@baseboard_fab2_lib.baseboard_fab2(sch_1):page139_i161@mstr_discrete.cap(chips)!CAP_0603-10UF,6.3V,20%,X6S,E15A!C1R16!//jf4cfls225.pdx.intel.com/apd_proj/ppg_lib/epg_masterlib/logical/mstr_discrete/cap/chips/chips.prt!CAP!CAP_0603-10UF,6.3V,20%,X6S,E15431-002!CAP!!!F3089!!NIC_SPRV!!
S!@baseboard_fab2_lib.baseboard_fab2(sch_1):page240_i109@mstr_discrete.cap(chips)!CAP_0603-4.7UF,6.3V,10%,X6S,E1A!C2R11!//jf4cfls225.pdx.intel.com/apd_proj/ppg_lib/epg_masterlib/logical/mstr_discrete/cap/chips/chips.prt!CAP!CAP_0603-4.7UF,6.3V,10%,X6S,E15431-003!CAP!!!F2746!!P3V3_STBY_VR!!
S!@baseboard_fab2_lib.baseboard_fab2(sch_1):page231_i202@mstr_discrete.cap(chips)!CAP_0603-4.7UF,6.3V,10%,X6S,E1A!C3T11!//jf4cfls225.pdx.intel.com/apd_proj/ppg_lib/epg_masterlib/logical/mstr_discrete/cap/chips/chips.prt!CAP!CAP_0603-4.7UF,6.3V,10%,X6S,E15431-003!CAP!!!F2744!!PVPP_KLM_VR!!
S!@baseboard_fab2_lib.baseboard_fab2(sch_1):page232_i253@mstr_discrete.cap(chips)!CAP_0603-4.7UF,6.3V,10%,X6S,E1A!C3M10!//jf4cfls225.pdx.intel.com/apd_proj/ppg_lib/epg_masterlib/logical/mstr_discrete/cap/chips/chips.prt!CAP!CAP_0603-4.7UF,6.3V,10%,X6S,E15431-003!CAP!!!F2745!!PVPP_KLM_VR!!
S!@baseboard_fab2_lib.baseboard_fab2(sch_1):page233_i187@mstr_discrete.cap(chips)!CAP_0603-4.7UF,6.3V,10%,X6S,E1A!C6U6!//jf4cfls225.pdx.intel.com/apd_proj/ppg_lib/epg_masterlib/logical/mstr_discrete/cap/chips/chips.prt!CAP!CAP_0603-4.7UF,6.3V,10%,X6S,E15431-003!CAP!!!F2740!!PVPP_KLM_VR!!
S!@baseboard_fab2_lib.baseboard_fab2(sch_1):page234_i144@mstr_discrete.cap(chips)!CAP_0603-4.7UF,6.3V,10%,X6S,E1A!C6L12!//jf4cfls225.pdx.intel.com/apd_proj/ppg_lib/epg_masterlib/logical/mstr_discrete/cap/chips/chips.prt!CAP!CAP_0603-4.7UF,6.3V,10%,X6S,E15431-003!CAP!!!F2741!!PVPP_KLM_VR!!
S!@baseboard_fab2_lib.baseboard_fab2(sch_1):page221_i49@mstr_discrete.cap(chips)!CAP_0603-4.7UF,6.3V,10%,X6S,E1A!C6U12!//jf4cfls225.pdx.intel.com/apd_proj/ppg_lib/epg_masterlib/logical/mstr_discrete/cap/chips/chips.prt!CAP!CAP_0603-4.7UF,6.3V,10%,X6S,E15431-003!CAP!!!F2738!!VTT_ABC_PWR_VR!!
S!@baseboard_fab2_lib.baseboard_fab2(sch_1):page222_i46@mstr_discrete.cap(chips)!CAP_0603-4.7UF,6.3V,10%,X6S,E1A!C4A11!//jf4cfls225.pdx.intel.com/apd_proj/ppg_lib/epg_masterlib/logical/mstr_discrete/cap/chips/chips.prt!CAP!CAP_0603-4.7UF,6.3V,10%,X6S,E15431-003!CAP!!!F2742!!VTT_DEF_PWR_VR!!
S!@baseboard_fab2_lib.baseboard_fab2(sch_1):page229_i46@mstr_discrete.cap(chips)!CAP_0603-4.7UF,6.3V,10%,X6S,E1A!C6U11!//jf4cfls225.pdx.intel.com/apd_proj/ppg_lib/epg_masterlib/logical/mstr_discrete/cap/chips/chips.prt!CAP!CAP_0603-4.7UF,6.3V,10%,X6S,E15431-003!CAP!!!F2739!!VTT_GHJ_PWR_VR!!
S!@baseboard_fab2_lib.baseboard_fab2(sch_1):page230_i46@mstr_discrete.cap(chips)!CAP_0603-4.7UF,6.3V,10%,X6S,E1A!C4A7!//jf4cfls225.pdx.intel.com/apd_proj/ppg_lib/epg_masterlib/logical/mstr_discrete/cap/chips/chips.prt!CAP!CAP_0603-4.7UF,6.3V,10%,X6S,E15431-003!CAP!!!F2743!!VTT_KLM_PWR_VR!!
S!@baseboard_fab2_lib.baseboard_fab2(sch_1):page148_i25@mstr_discrete.cap(chips)!CAP_0603-4.7UF,6.3V,10%,X6S,E1A!C1T44!//jf4cfls225.pdx.intel.com/apd_proj/ppg_lib/epg_masterlib/logical/mstr_discrete/cap/chips/chips.prt!CAP!CAP_0603-4.7UF,6.3V,10%,X6S,E15431-003!CAP!!!F2747!!BMC!!
S!@baseboard_fab2_lib.baseboard_fab2(sch_1):page199_i24@mstr_discrete.cap(chips)!CAP_0603LF-0.033UF,50V,10%,X7RA!C9P14!//jf4cfls225.pdx.intel.com/apd_proj/ppg_lib/epg_masterlib/logical/mstr_discrete/cap/chips/chips.prt!CAP!CAP_0603LF-0.033UF,50V,10%,X7R,603269-064!CAP!!!F2685!!HOT_SWAP!!
S!@baseboard_fab2_lib.baseboard_fab2(sch_1):page232_i241@mstr_discrete.cap(chips)!CAP_0603LF-0.1UF,25V,10%,X7R,6A!C7B30!//jf4cfls225.pdx.intel.com/apd_proj/ppg_lib/epg_masterlib/logical/mstr_discrete/cap/chips/chips.prt!CAP!CAP_0603LF-0.1UF,25V,10%,X7R,602433-020!CAP!!!F2684!!PVPP_KLM_VR!!
S!@baseboard_fab2_lib.baseboard_fab2(sch_1):page233_i224@mstr_discrete.cap(chips)!CAP_0603LF-0.1UF,25V,10%,X7R,6A!C4G26!//jf4cfls225.pdx.intel.com/apd_proj/ppg_lib/epg_masterlib/logical/mstr_discrete/cap/chips/chips.prt!CAP!CAP_0603LF-0.1UF,25V,10%,X7R,602433-020!CAP!!!F2682!!PVPP_KLM_VR!!
S!@baseboard_fab2_lib.baseboard_fab2(sch_1):page234_i182@mstr_discrete.cap(chips)!CAP_0603LF-0.1UF,25V,10%,X7R,6A!C4B15!//jf4cfls225.pdx.intel.com/apd_proj/ppg_lib/epg_masterlib/logical/mstr_discrete/cap/chips/chips.prt!CAP!CAP_0603LF-0.1UF,25V,10%,X7R,602433-020!CAP!!!F2683!!PVPP_KLM_VR!!
S!@baseboard_fab2_lib.baseboard_fab2(sch_1):page231_i159@mstr_discrete.cap(chips)!CAP_0603LF-0.1UF,25V,10%,X7R,6A!C7F4!//jf4cfls225.pdx.intel.com/apd_proj/ppg_lib/epg_masterlib/logical/mstr_discrete/cap/chips/chips.prt!CAP!CAP_0603LF-0.1UF,25V,10%,X7R,602433-020!CAP!!!F2681!!PVPP_KLM_VR!!
S!@baseboard_fab2_lib.baseboard_fab2(sch_1):page240_i129@mstr_discrete.cap(chips)!CAP_0603LF-0.1UF,25V,10%,X7R,6A!C8E12!//jf4cfls225.pdx.intel.com/apd_proj/ppg_lib/epg_masterlib/logical/mstr_discrete/cap/chips/chips.prt!CAP!CAP_0603LF-0.1UF,25V,10%,X7R,602433-020!CAP!!!F2678!!P3V3_STBY_VR!!
S!@baseboard_fab2_lib.baseboard_fab2(sch_1):page237_i31@mstr_discrete.cap(chips)!CAP_0603LF-0.1UF,25V,10%,X7R,6A!C8A4!//jf4cfls225.pdx.intel.com/apd_proj/ppg_lib/epg_masterlib/logical/mstr_discrete/cap/chips/chips.prt!CAP!CAP_0603LF-0.1UF,25V,10%,X7R,602433-020!CAP!!!F2680!!P1V8_PCH_STBY_VR!!
S!@baseboard_fab2_lib.baseboard_fab2(sch_1):page241_i12@mstr_discrete.cap(chips)!CAP_0603LF-0.1UF,25V,10%,X7R,6A!C8E6!//jf4cfls225.pdx.intel.com/apd_proj/ppg_lib/epg_masterlib/logical/mstr_discrete/cap/chips/chips.prt!CAP!CAP_0603LF-0.1UF,25V,10%,X7R,602433-020!CAP!!!F2679!!P5V_STBY_VR!!
S!@baseboard_fab2_lib.baseboard_fab2(sch_1):page231_i149@mstr_discrete.cap(chips)!CAP_0603LF-10UF,4V,20%,X6S,E15A!C6F5!//jf4cfls225.pdx.intel.com/apd_proj/ppg_lib/epg_masterlib/logical/mstr_discrete/cap/chips/chips.prt!CAP!CAP_0603LF-10UF,4V,20%,X6S,E15431-001!CAP!!!F2613!!PVPP_KLM_VR!!
S!@baseboard_fab2_lib.baseboard_fab2(sch_1):page232_i129@mstr_discrete.cap(chips)!CAP_0603LF-10UF,4V,20%,X6S,E15A!C4L1!//jf4cfls225.pdx.intel.com/apd_proj/ppg_lib/epg_masterlib/logical/mstr_discrete/cap/chips/chips.prt!CAP!CAP_0603LF-10UF,4V,20%,X6S,E15431-001!CAP!!!F2644!!PVPP_KLM_VR!!
S!@baseboard_fab2_lib.baseboard_fab2(sch_1):page233_i136@mstr_discrete.cap(chips)!CAP_0603LF-10UF,4V,20%,X6S,E15A!C7U3!//jf4cfls225.pdx.intel.com/apd_proj/ppg_lib/epg_masterlib/logical/mstr_discrete/cap/chips/chips.prt!CAP!CAP_0603LF-10UF,4V,20%,X6S,E15431-001!CAP!!!F2592!!PVPP_KLM_VR!!
S!@baseboard_fab2_lib.baseboard_fab2(sch_1):page231_i122@mstr_discrete.cap(chips)!CAP_0603LF-10UF,4V,20%,X6S,E15A!C6F6!//jf4cfls225.pdx.intel.com/apd_proj/ppg_lib/epg_masterlib/logical/mstr_discrete/cap/chips/chips.prt!CAP!CAP_0603LF-10UF,4V,20%,X6S,E15431-001!CAP!!!F2612!!PVPP_KLM_VR!!
S!@baseboard_fab2_lib.baseboard_fab2(sch_1):page231_i124@mstr_discrete.cap(chips)!CAP_0603LF-10UF,4V,20%,X6S,E15A!C4T6!//jf4cfls225.pdx.intel.com/apd_proj/ppg_lib/epg_masterlib/logical/mstr_discrete/cap/chips/chips.prt!CAP!CAP_0603LF-10UF,4V,20%,X6S,E15431-001!CAP!!!F2637!!PVPP_KLM_VR!!
S!@baseboard_fab2_lib.baseboard_fab2(sch_1):page231_i125@mstr_discrete.cap(chips)!CAP_0603LF-10UF,4V,20%,X6S,E15A!C4T5!//jf4cfls225.pdx.intel.com/apd_proj/ppg_lib/epg_masterlib/logical/mstr_discrete/cap/chips/chips.prt!CAP!CAP_0603LF-10UF,4V,20%,X6S,E15431-001!CAP!!!F2638!!PVPP_KLM_VR!!
S!@baseboard_fab2_lib.baseboard_fab2(sch_1):page231_i126@mstr_discrete.cap(chips)!CAP_0603LF-10UF,4V,20%,X6S,E15A!C6G1!//jf4cfls225.pdx.intel.com/apd_proj/ppg_lib/epg_masterlib/logical/mstr_discrete/cap/chips/chips.prt!CAP!CAP_0603LF-10UF,4V,20%,X6S,E15431-001!CAP!!!F2611!!PVPP_KLM_VR!!
S!@baseboard_fab2_lib.baseboard_fab2(sch_1):page231_i128@mstr_discrete.cap(chips)!CAP_0603LF-10UF,4V,20%,X6S,E15A!C6G2!//jf4cfls225.pdx.intel.com/apd_proj/ppg_lib/epg_masterlib/logical/mstr_discrete/cap/chips/chips.prt!CAP!CAP_0603LF-10UF,4V,20%,X6S,E15431-001!CAP!!!F2610!!PVPP_KLM_VR!!
S!@baseboard_fab2_lib.baseboard_fab2(sch_1):page231_i129@mstr_discrete.cap(chips)!CAP_0603LF-10UF,4V,20%,X6S,E15A!C4U2!//jf4cfls225.pdx.intel.com/apd_proj/ppg_lib/epg_masterlib/logical/mstr_discrete/cap/chips/chips.prt!CAP!CAP_0603LF-10UF,4V,20%,X6S,E15431-001!CAP!!!F2635!!PVPP_KLM_VR!!
S!@baseboard_fab2_lib.baseboard_fab2(sch_1):page231_i130@mstr_discrete.cap(chips)!CAP_0603LF-10UF,4V,20%,X6S,E15A!C4U1!//jf4cfls225.pdx.intel.com/apd_proj/ppg_lib/epg_masterlib/logical/mstr_discrete/cap/chips/chips.prt!CAP!CAP_0603LF-10UF,4V,20%,X6S,E15431-001!CAP!!!F2636!!PVPP_KLM_VR!!
S!@baseboard_fab2_lib.baseboard_fab2(sch_1):page231_i131@mstr_discrete.cap(chips)!CAP_0603LF-10UF,4V,20%,X6S,E15A!C6G4!//jf4cfls225.pdx.intel.com/apd_proj/ppg_lib/epg_masterlib/logical/mstr_discrete/cap/chips/chips.prt!CAP!CAP_0603LF-10UF,4V,20%,X6S,E15431-001!CAP!!!F2609!!PVPP_KLM_VR!!
S!@baseboard_fab2_lib.baseboard_fab2(sch_1):page231_i145@mstr_discrete.cap(chips)!CAP_0603LF-10UF,4V,20%,X6S,E15A!C6G5!//jf4cfls225.pdx.intel.com/apd_proj/ppg_lib/epg_masterlib/logical/mstr_discrete/cap/chips/chips.prt!CAP!CAP_0603LF-10UF,4V,20%,X6S,E15431-001!CAP!!!F2608!!PVPP_KLM_VR!!
S!@baseboard_fab2_lib.baseboard_fab2(sch_1):page231_i146@mstr_discrete.cap(chips)!CAP_0603LF-10UF,4V,20%,X6S,E15A!C4U4!//jf4cfls225.pdx.intel.com/apd_proj/ppg_lib/epg_masterlib/logical/mstr_discrete/cap/chips/chips.prt!CAP!CAP_0603LF-10UF,4V,20%,X6S,E15431-001!CAP!!!F2633!!PVPP_KLM_VR!!
S!@baseboard_fab2_lib.baseboard_fab2(sch_1):page231_i148@mstr_discrete.cap(chips)!CAP_0603LF-10UF,4V,20%,X6S,E15A!C4U3!//jf4cfls225.pdx.intel.com/apd_proj/ppg_lib/epg_masterlib/logical/mstr_discrete/cap/chips/chips.prt!CAP!CAP_0603LF-10UF,4V,20%,X6S,E15431-001!CAP!!!F2634!!PVPP_KLM_VR!!
S!@baseboard_fab2_lib.baseboard_fab2(sch_1):page232_i102@mstr_discrete.cap(chips)!CAP_0603LF-10UF,4V,20%,X6S,E15A!C4L2!//jf4cfls225.pdx.intel.com/apd_proj/ppg_lib/epg_masterlib/logical/mstr_discrete/cap/chips/chips.prt!CAP!CAP_0603LF-10UF,4V,20%,X6S,E15431-001!CAP!!!F2643!!PVPP_KLM_VR!!
S!@baseboard_fab2_lib.baseboard_fab2(sch_1):page232_i104@mstr_discrete.cap(chips)!CAP_0603LF-10UF,4V,20%,X6S,E15A!C6A3!//jf4cfls225.pdx.intel.com/apd_proj/ppg_lib/epg_masterlib/logical/mstr_discrete/cap/chips/chips.prt!CAP!CAP_0603LF-10UF,4V,20%,X6S,E15431-001!CAP!!!F2619!!PVPP_KLM_VR!!
S!@baseboard_fab2_lib.baseboard_fab2(sch_1):page232_i105@mstr_discrete.cap(chips)!CAP_0603LF-10UF,4V,20%,X6S,E15A!C6A2!//jf4cfls225.pdx.intel.com/apd_proj/ppg_lib/epg_masterlib/logical/mstr_discrete/cap/chips/chips.prt!CAP!CAP_0603LF-10UF,4V,20%,X6S,E15431-001!CAP!!!F2620!!PVPP_KLM_VR!!
S!@baseboard_fab2_lib.baseboard_fab2(sch_1):page232_i106@mstr_discrete.cap(chips)!CAP_0603LF-10UF,4V,20%,X6S,E15A!C4L3!//jf4cfls225.pdx.intel.com/apd_proj/ppg_lib/epg_masterlib/logical/mstr_discrete/cap/chips/chips.prt!CAP!CAP_0603LF-10UF,4V,20%,X6S,E15431-001!CAP!!!F2642!!PVPP_KLM_VR!!
S!@baseboard_fab2_lib.baseboard_fab2(sch_1):page232_i108@mstr_discrete.cap(chips)!CAP_0603LF-10UF,4V,20%,X6S,E15A!C4L4!//jf4cfls225.pdx.intel.com/apd_proj/ppg_lib/epg_masterlib/logical/mstr_discrete/cap/chips/chips.prt!CAP!CAP_0603LF-10UF,4V,20%,X6S,E15431-001!CAP!!!F2641!!PVPP_KLM_VR!!
S!@baseboard_fab2_lib.baseboard_fab2(sch_1):page232_i109@mstr_discrete.cap(chips)!CAP_0603LF-10UF,4V,20%,X6S,E15A!C6A7!//jf4cfls225.pdx.intel.com/apd_proj/ppg_lib/epg_masterlib/logical/mstr_discrete/cap/chips/chips.prt!CAP!CAP_0603LF-10UF,4V,20%,X6S,E15431-001!CAP!!!F2617!!PVPP_KLM_VR!!
S!@baseboard_fab2_lib.baseboard_fab2(sch_1):page232_i110@mstr_discrete.cap(chips)!CAP_0603LF-10UF,4V,20%,X6S,E15A!C6A6!//jf4cfls225.pdx.intel.com/apd_proj/ppg_lib/epg_masterlib/logical/mstr_discrete/cap/chips/chips.prt!CAP!CAP_0603LF-10UF,4V,20%,X6S,E15431-001!CAP!!!F2618!!PVPP_KLM_VR!!
S!@baseboard_fab2_lib.baseboard_fab2(sch_1):page232_i111@mstr_discrete.cap(chips)!CAP_0603LF-10UF,4V,20%,X6S,E15A!C4M3!//jf4cfls225.pdx.intel.com/apd_proj/ppg_lib/epg_masterlib/logical/mstr_discrete/cap/chips/chips.prt!CAP!CAP_0603LF-10UF,4V,20%,X6S,E15431-001!CAP!!!F2640!!PVPP_KLM_VR!!
S!@baseboard_fab2_lib.baseboard_fab2(sch_1):page232_i125@mstr_discrete.cap(chips)!CAP_0603LF-10UF,4V,20%,X6S,E15A!C4M4!//jf4cfls225.pdx.intel.com/apd_proj/ppg_lib/epg_masterlib/logical/mstr_discrete/cap/chips/chips.prt!CAP!CAP_0603LF-10UF,4V,20%,X6S,E15431-001!CAP!!!F2639!!PVPP_KLM_VR!!
S!@baseboard_fab2_lib.baseboard_fab2(sch_1):page232_i126@mstr_discrete.cap(chips)!CAP_0603LF-10UF,4V,20%,X6S,E15A!C6B2!//jf4cfls225.pdx.intel.com/apd_proj/ppg_lib/epg_masterlib/logical/mstr_discrete/cap/chips/chips.prt!CAP!CAP_0603LF-10UF,4V,20%,X6S,E15431-001!CAP!!!F2615!!PVPP_KLM_VR!!
S!@baseboard_fab2_lib.baseboard_fab2(sch_1):page232_i128@mstr_discrete.cap(chips)!CAP_0603LF-10UF,4V,20%,X6S,E15A!C6B1!//jf4cfls225.pdx.intel.com/apd_proj/ppg_lib/epg_masterlib/logical/mstr_discrete/cap/chips/chips.prt!CAP!CAP_0603LF-10UF,4V,20%,X6S,E15431-001!CAP!!!F2616!!PVPP_KLM_VR!!
S!@baseboard_fab2_lib.baseboard_fab2(sch_1):page233_i109@mstr_discrete.cap(chips)!CAP_0603LF-10UF,4V,20%,X6S,E15A!C7U4!//jf4cfls225.pdx.intel.com/apd_proj/ppg_lib/epg_masterlib/logical/mstr_discrete/cap/chips/chips.prt!CAP!CAP_0603LF-10UF,4V,20%,X6S,E15431-001!CAP!!!F2591!!PVPP_KLM_VR!!
S!@baseboard_fab2_lib.baseboard_fab2(sch_1):page233_i111@mstr_discrete.cap(chips)!CAP_0603LF-10UF,4V,20%,X6S,E15A!C7U5!//jf4cfls225.pdx.intel.com/apd_proj/ppg_lib/epg_masterlib/logical/mstr_discrete/cap/chips/chips.prt!CAP!CAP_0603LF-10UF,4V,20%,X6S,E15431-001!CAP!!!F2590!!PVPP_KLM_VR!!
S!@baseboard_fab2_lib.baseboard_fab2(sch_1):page233_i112@mstr_discrete.cap(chips)!CAP_0603LF-10UF,4V,20%,X6S,E15A!C7T2!//jf4cfls225.pdx.intel.com/apd_proj/ppg_lib/epg_masterlib/logical/mstr_discrete/cap/chips/chips.prt!CAP!CAP_0603LF-10UF,4V,20%,X6S,E15431-001!CAP!!!F2594!!PVPP_KLM_VR!!
S!@baseboard_fab2_lib.baseboard_fab2(sch_1):page233_i113@mstr_discrete.cap(chips)!CAP_0603LF-10UF,4V,20%,X6S,E15A!C7T3!//jf4cfls225.pdx.intel.com/apd_proj/ppg_lib/epg_masterlib/logical/mstr_discrete/cap/chips/chips.prt!CAP!CAP_0603LF-10UF,4V,20%,X6S,E15431-001!CAP!!!F2593!!PVPP_KLM_VR!!
S!@baseboard_fab2_lib.baseboard_fab2(sch_1):page233_i115@mstr_discrete.cap(chips)!CAP_0603LF-10UF,4V,20%,X6S,E15A!C7U6!//jf4cfls225.pdx.intel.com/apd_proj/ppg_lib/epg_masterlib/logical/mstr_discrete/cap/chips/chips.prt!CAP!CAP_0603LF-10UF,4V,20%,X6S,E15431-001!CAP!!!F2589!!PVPP_KLM_VR!!
S!@baseboard_fab2_lib.baseboard_fab2(sch_1):page233_i116@mstr_discrete.cap(chips)!CAP_0603LF-10UF,4V,20%,X6S,E15A!C3F3!//jf4cfls225.pdx.intel.com/apd_proj/ppg_lib/epg_masterlib/logical/mstr_discrete/cap/chips/chips.prt!CAP!CAP_0603LF-10UF,4V,20%,X6S,E15431-001!CAP!!!F2655!!PVPP_KLM_VR!!
S!@baseboard_fab2_lib.baseboard_fab2(sch_1):page233_i117@mstr_discrete.cap(chips)!CAP_0603LF-10UF,4V,20%,X6S,E15A!C3F4!//jf4cfls225.pdx.intel.com/apd_proj/ppg_lib/epg_masterlib/logical/mstr_discrete/cap/chips/chips.prt!CAP!CAP_0603LF-10UF,4V,20%,X6S,E15431-001!CAP!!!F2654!!PVPP_KLM_VR!!
S!@baseboard_fab2_lib.baseboard_fab2(sch_1):page233_i118@mstr_discrete.cap(chips)!CAP_0603LF-10UF,4V,20%,X6S,E15A!C3G3!//jf4cfls225.pdx.intel.com/apd_proj/ppg_lib/epg_masterlib/logical/mstr_discrete/cap/chips/chips.prt!CAP!CAP_0603LF-10UF,4V,20%,X6S,E15431-001!CAP!!!F2653!!PVPP_KLM_VR!!
S!@baseboard_fab2_lib.baseboard_fab2(sch_1):page233_i132@mstr_discrete.cap(chips)!CAP_0603LF-10UF,4V,20%,X6S,E15A!C3G7!//jf4cfls225.pdx.intel.com/apd_proj/ppg_lib/epg_masterlib/logical/mstr_discrete/cap/chips/chips.prt!CAP!CAP_0603LF-10UF,4V,20%,X6S,E15431-001!CAP!!!F2651!!PVPP_KLM_VR!!
S!@baseboard_fab2_lib.baseboard_fab2(sch_1):page233_i133@mstr_discrete.cap(chips)!CAP_0603LF-10UF,4V,20%,X6S,E15A!C3G4!//jf4cfls225.pdx.intel.com/apd_proj/ppg_lib/epg_masterlib/logical/mstr_discrete/cap/chips/chips.prt!CAP!CAP_0603LF-10UF,4V,20%,X6S,E15431-001!CAP!!!F2652!!PVPP_KLM_VR!!
S!@baseboard_fab2_lib.baseboard_fab2(sch_1):page233_i135@mstr_discrete.cap(chips)!CAP_0603LF-10UF,4V,20%,X6S,E15A!C3G8!//jf4cfls225.pdx.intel.com/apd_proj/ppg_lib/epg_masterlib/logical/mstr_discrete/cap/chips/chips.prt!CAP!CAP_0603LF-10UF,4V,20%,X6S,E15431-001!CAP!!!F2650!!PVPP_KLM_VR!!
S!@baseboard_fab2_lib.baseboard_fab2(sch_1):page234_i97@mstr_discrete.cap(chips)!CAP_0603LF-10UF,4V,20%,X6S,E15A!C3A3!//jf4cfls225.pdx.intel.com/apd_proj/ppg_lib/epg_masterlib/logical/mstr_discrete/cap/chips/chips.prt!CAP!CAP_0603LF-10UF,4V,20%,X6S,E15431-001!CAP!!!F2662!!PVPP_KLM_VR!!
S!@baseboard_fab2_lib.baseboard_fab2(sch_1):page234_i95@mstr_discrete.cap(chips)!CAP_0603LF-10UF,4V,20%,X6S,E15A!C3A7!//jf4cfls225.pdx.intel.com/apd_proj/ppg_lib/epg_masterlib/logical/mstr_discrete/cap/chips/chips.prt!CAP!CAP_0603LF-10UF,4V,20%,X6S,E15431-001!CAP!!!F2660!!PVPP_KLM_VR!!
S!@baseboard_fab2_lib.baseboard_fab2(sch_1):page234_i94@mstr_discrete.cap(chips)!CAP_0603LF-10UF,4V,20%,X6S,E15A!C3B1!//jf4cfls225.pdx.intel.com/apd_proj/ppg_lib/epg_masterlib/logical/mstr_discrete/cap/chips/chips.prt!CAP!CAP_0603LF-10UF,4V,20%,X6S,E15431-001!CAP!!!F2658!!PVPP_KLM_VR!!
S!@baseboard_fab2_lib.baseboard_fab2(sch_1):page234_i93@mstr_discrete.cap(chips)!CAP_0603LF-10UF,4V,20%,X6S,E15A!C3A4!//jf4cfls225.pdx.intel.com/apd_proj/ppg_lib/epg_masterlib/logical/mstr_discrete/cap/chips/chips.prt!CAP!CAP_0603LF-10UF,4V,20%,X6S,E15431-001!CAP!!!F2661!!PVPP_KLM_VR!!
S!@baseboard_fab2_lib.baseboard_fab2(sch_1):page234_i92@mstr_discrete.cap(chips)!CAP_0603LF-10UF,4V,20%,X6S,E15A!C7M3!//jf4cfls225.pdx.intel.com/apd_proj/ppg_lib/epg_masterlib/logical/mstr_discrete/cap/chips/chips.prt!CAP!CAP_0603LF-10UF,4V,20%,X6S,E15431-001!CAP!!!F2596!!PVPP_KLM_VR!!
S!@baseboard_fab2_lib.baseboard_fab2(sch_1):page234_i91@mstr_discrete.cap(chips)!CAP_0603LF-10UF,4V,20%,X6S,E15A!C7M4!//jf4cfls225.pdx.intel.com/apd_proj/ppg_lib/epg_masterlib/logical/mstr_discrete/cap/chips/chips.prt!CAP!CAP_0603LF-10UF,4V,20%,X6S,E15431-001!CAP!!!F2595!!PVPP_KLM_VR!!
S!@baseboard_fab2_lib.baseboard_fab2(sch_1):page234_i90@mstr_discrete.cap(chips)!CAP_0603LF-10UF,4V,20%,X6S,E15A!C7L6!//jf4cfls225.pdx.intel.com/apd_proj/ppg_lib/epg_masterlib/logical/mstr_discrete/cap/chips/chips.prt!CAP!CAP_0603LF-10UF,4V,20%,X6S,E15431-001!CAP!!!F2598!!PVPP_KLM_VR!!
S!@baseboard_fab2_lib.baseboard_fab2(sch_1):page234_i89@mstr_discrete.cap(chips)!CAP_0603LF-10UF,4V,20%,X6S,E15A!C7L7!//jf4cfls225.pdx.intel.com/apd_proj/ppg_lib/epg_masterlib/logical/mstr_discrete/cap/chips/chips.prt!CAP!CAP_0603LF-10UF,4V,20%,X6S,E15431-001!CAP!!!F2597!!PVPP_KLM_VR!!
S!@baseboard_fab2_lib.baseboard_fab2(sch_1):page234_i88@mstr_discrete.cap(chips)!CAP_0603LF-10UF,4V,20%,X6S,E15A!C7L2!//jf4cfls225.pdx.intel.com/apd_proj/ppg_lib/epg_masterlib/logical/mstr_discrete/cap/chips/chips.prt!CAP!CAP_0603LF-10UF,4V,20%,X6S,E15431-001!CAP!!!F2600!!PVPP_KLM_VR!!
S!@baseboard_fab2_lib.baseboard_fab2(sch_1):page234_i87@mstr_discrete.cap(chips)!CAP_0603LF-10UF,4V,20%,X6S,E15A!C7L3!//jf4cfls225.pdx.intel.com/apd_proj/ppg_lib/epg_masterlib/logical/mstr_discrete/cap/chips/chips.prt!CAP!CAP_0603LF-10UF,4V,20%,X6S,E15431-001!CAP!!!F2599!!PVPP_KLM_VR!!
S!@baseboard_fab2_lib.baseboard_fab2(sch_1):page234_i86@mstr_discrete.cap(chips)!CAP_0603LF-10UF,4V,20%,X6S,E15A!C3A8!//jf4cfls225.pdx.intel.com/apd_proj/ppg_lib/epg_masterlib/logical/mstr_discrete/cap/chips/chips.prt!CAP!CAP_0603LF-10UF,4V,20%,X6S,E15431-001!CAP!!!F2659!!PVPP_KLM_VR!!
S!@baseboard_fab2_lib.baseboard_fab2(sch_1):page234_i84@mstr_discrete.cap(chips)!CAP_0603LF-10UF,4V,20%,X6S,E15A!C3B2!//jf4cfls225.pdx.intel.com/apd_proj/ppg_lib/epg_masterlib/logical/mstr_discrete/cap/chips/chips.prt!CAP!CAP_0603LF-10UF,4V,20%,X6S,E15431-001!CAP!!!F2657!!PVPP_KLM_VR!!
S!@baseboard_fab2_lib.baseboard_fab2(sch_1):page127_i54@mstr_discrete.cap(chips)!CAP_0603LF-10UF,4V,20%,X6S,E15A!C3M24!//jf4cfls225.pdx.intel.com/apd_proj/ppg_lib/epg_masterlib/logical/mstr_discrete/cap/chips/chips.prt!CAP!CAP_0603LF-10UF,4V,20%,X6S,E15431-001!CAP!!!F2646!!SB_FILTER_ISCLK!!
S!@baseboard_fab2_lib.baseboard_fab2(sch_1):page127_i64@mstr_discrete.cap(chips)!CAP_0603LF-10UF,4V,20%,X6S,E15A!C2N6!//jf4cfls225.pdx.intel.com/apd_proj/ppg_lib/epg_masterlib/logical/mstr_discrete/cap/chips/chips.prt!CAP!CAP_0603LF-10UF,4V,20%,X6S,E15431-001!CAP!!!F2663!!SB_FILTER_KR_PLL!!
S!@baseboard_fab2_lib.baseboard_fab2(sch_1):page127_i43@mstr_discrete.cap(chips)!CAP_0603LF-10UF,4V,20%,X6S,E15A!C2M5!//jf4cfls225.pdx.intel.com/apd_proj/ppg_lib/epg_masterlib/logical/mstr_discrete/cap/chips/chips.prt!CAP!CAP_0603LF-10UF,4V,20%,X6S,E15431-001!CAP!!!F2665!!SB_FILTER_VM20!!
S!@baseboard_fab2_lib.baseboard_fab2(sch_1):page127_i49@mstr_discrete.cap(chips)!CAP_0603LF-10UF,4V,20%,X6S,E15A!C2M10!//jf4cfls225.pdx.intel.com/apd_proj/ppg_lib/epg_masterlib/logical/mstr_discrete/cap/chips/chips.prt!CAP!CAP_0603LF-10UF,4V,20%,X6S,E15431-001!CAP!!!F2664!!SB_FILTER_VM26!!
S!@baseboard_fab2_lib.baseboard_fab2(sch_1):page127_i3@mstr_discrete.cap(chips)!CAP_0603LF-10UF,4V,20%,X6S,E15A!C3M17!//jf4cfls225.pdx.intel.com/apd_proj/ppg_lib/epg_masterlib/logical/mstr_discrete/cap/chips/chips.prt!CAP!CAP_0603LF-10UF,4V,20%,X6S,E15431-001!CAP!!!F2649!!SB_FILTER_PLL0!!
S!@baseboard_fab2_lib.baseboard_fab2(sch_1):page127_i10@mstr_discrete.cap(chips)!CAP_0603LF-10UF,4V,20%,X6S,E15A!C3M18!//jf4cfls225.pdx.intel.com/apd_proj/ppg_lib/epg_masterlib/logical/mstr_discrete/cap/chips/chips.prt!CAP!CAP_0603LF-10UF,4V,20%,X6S,E15431-001!CAP!!!F2648!!SB_FILTER_PLL1!!
S!@baseboard_fab2_lib.baseboard_fab2(sch_1):page127_i19@mstr_discrete.cap(chips)!CAP_0603LF-10UF,4V,20%,X6S,E15A!C3M23!//jf4cfls225.pdx.intel.com/apd_proj/ppg_lib/epg_masterlib/logical/mstr_discrete/cap/chips/chips.prt!CAP!CAP_0603LF-10UF,4V,20%,X6S,E15431-001!CAP!!!F2647!!SB_FILTER_XTAL!!
S!@baseboard_fab2_lib.baseboard_fab2(sch_1):page221_i26@mstr_discrete.cap(chips)!CAP_0603LF-10UF,4V,20%,X6S,E15A!C6U15!//jf4cfls225.pdx.intel.com/apd_proj/ppg_lib/epg_masterlib/logical/mstr_discrete/cap/chips/chips.prt!CAP!CAP_0603LF-10UF,4V,20%,X6S,E15431-001!CAP!!!F2602!!VTT_ABC_PWR_VR!!
S!@baseboard_fab2_lib.baseboard_fab2(sch_1):page221_i22@mstr_discrete.cap(chips)!CAP_0603LF-10UF,4V,20%,X6S,E15A!C6U16!//jf4cfls225.pdx.intel.com/apd_proj/ppg_lib/epg_masterlib/logical/mstr_discrete/cap/chips/chips.prt!CAP!CAP_0603LF-10UF,4V,20%,X6S,E15431-001!CAP!!!F2601!!VTT_ABC_PWR_VR!!
S!@baseboard_fab2_lib.baseboard_fab2(sch_1):page222_i26@mstr_discrete.cap(chips)!CAP_0603LF-10UF,4V,20%,X6S,E15A!C6L4!//jf4cfls225.pdx.intel.com/apd_proj/ppg_lib/epg_masterlib/logical/mstr_discrete/cap/chips/chips.prt!CAP!CAP_0603LF-10UF,4V,20%,X6S,E15431-001!CAP!!!F2606!!VTT_DEF_PWR_VR!!
S!@baseboard_fab2_lib.baseboard_fab2(sch_1):page229_i29@mstr_discrete.cap(chips)!CAP_0603LF-10UF,4V,20%,X6S,E15A!C6U13!//jf4cfls225.pdx.intel.com/apd_proj/ppg_lib/epg_masterlib/logical/mstr_discrete/cap/chips/chips.prt!CAP!CAP_0603LF-10UF,4V,20%,X6S,E15431-001!CAP!!!F2604!!VTT_GHJ_PWR_VR!!
S!@baseboard_fab2_lib.baseboard_fab2(sch_1):page230_i26@mstr_discrete.cap(chips)!CAP_0603LF-10UF,4V,20%,X6S,E15A!C6L5!//jf4cfls225.pdx.intel.com/apd_proj/ppg_lib/epg_masterlib/logical/mstr_discrete/cap/chips/chips.prt!CAP!CAP_0603LF-10UF,4V,20%,X6S,E15431-001!CAP!!!F2605!!VTT_KLM_PWR_VR!!
S!@baseboard_fab2_lib.baseboard_fab2(sch_1):page222_i24@mstr_discrete.cap(chips)!CAP_0603LF-10UF,4V,20%,X6S,E15A!C6L3!//jf4cfls225.pdx.intel.com/apd_proj/ppg_lib/epg_masterlib/logical/mstr_discrete/cap/chips/chips.prt!CAP!CAP_0603LF-10UF,4V,20%,X6S,E15431-001!CAP!!!F2607!!VTT_DEF_PWR_VR!!
S!@baseboard_fab2_lib.baseboard_fab2(sch_1):page229_i25@mstr_discrete.cap(chips)!CAP_0603LF-10UF,4V,20%,X6S,E15A!C6U14!//jf4cfls225.pdx.intel.com/apd_proj/ppg_lib/epg_masterlib/logical/mstr_discrete/cap/chips/chips.prt!CAP!CAP_0603LF-10UF,4V,20%,X6S,E15431-001!CAP!!!F2603!!VTT_GHJ_PWR_VR!!
S!@baseboard_fab2_lib.baseboard_fab2(sch_1):page230_i25@mstr_discrete.cap(chips)!CAP_0603LF-10UF,4V,20%,X6S,E15A!C4A15!//jf4cfls225.pdx.intel.com/apd_proj/ppg_lib/epg_masterlib/logical/mstr_discrete/cap/chips/chips.prt!CAP!CAP_0603LF-10UF,4V,20%,X6S,E15431-001!CAP!!!F2645!!VTT_KLM_PWR_VR!!
S!@baseboard_fab2_lib.baseboard_fab2(sch_1):page217_i190@mstr_discrete.cap(chips)!CAP_0603LF-10UF,4V,20%,X6S,E15A!C5D54!//jf4cfls225.pdx.intel.com/apd_proj/ppg_lib/epg_masterlib/logical/mstr_discrete/cap/chips/chips.prt!CAP!CAP_0603LF-10UF,4V,20%,X6S,E15431-001!CAP!!!F2624!!VDDQ_ABC_CPU0!!
S!@baseboard_fab2_lib.baseboard_fab2(sch_1):page217_i189@mstr_discrete.cap(chips)!CAP_0603LF-10UF,4V,20%,X6S,E15A!C5D55!//jf4cfls225.pdx.intel.com/apd_proj/ppg_lib/epg_masterlib/logical/mstr_discrete/cap/chips/chips.prt!CAP!CAP_0603LF-10UF,4V,20%,X6S,E15431-001!CAP!!!F2623!!VDDQ_ABC_CPU0!!
S!@baseboard_fab2_lib.baseboard_fab2(sch_1):page217_i188@mstr_discrete.cap(chips)!CAP_0603LF-10UF,4V,20%,X6S,E15A!C5D56!//jf4cfls225.pdx.intel.com/apd_proj/ppg_lib/epg_masterlib/logical/mstr_discrete/cap/chips/chips.prt!CAP!CAP_0603LF-10UF,4V,20%,X6S,E15431-001!CAP!!!F2622!!VDDQ_ABC_CPU0!!
S!@baseboard_fab2_lib.baseboard_fab2(sch_1):page217_i186@mstr_discrete.cap(chips)!CAP_0603LF-10UF,4V,20%,X6S,E15A!C5D57!//jf4cfls225.pdx.intel.com/apd_proj/ppg_lib/epg_masterlib/logical/mstr_discrete/cap/chips/chips.prt!CAP!CAP_0603LF-10UF,4V,20%,X6S,E15431-001!CAP!!!F2621!!VDDQ_ABC_CPU0!!
S!@baseboard_fab2_lib.baseboard_fab2(sch_1):page220_i180@mstr_discrete.cap(chips)!CAP_0603LF-10UF,4V,20%,X6S,E15A!C5D9!//jf4cfls225.pdx.intel.com/apd_proj/ppg_lib/epg_masterlib/logical/mstr_discrete/cap/chips/chips.prt!CAP!CAP_0603LF-10UF,4V,20%,X6S,E15431-001!CAP!!!F2629!!VDDQ_DEF_CPU0!!
S!@baseboard_fab2_lib.baseboard_fab2(sch_1):page220_i182@mstr_discrete.cap(chips)!CAP_0603LF-10UF,4V,20%,X6S,E15A!C5D6!//jf4cfls225.pdx.intel.com/apd_proj/ppg_lib/epg_masterlib/logical/mstr_discrete/cap/chips/chips.prt!CAP!CAP_0603LF-10UF,4V,20%,X6S,E15431-001!CAP!!!F2632!!VDDQ_DEF_CPU0!!
S!@baseboard_fab2_lib.baseboard_fab2(sch_1):page220_i183@mstr_discrete.cap(chips)!CAP_0603LF-10UF,4V,20%,X6S,E15A!C5D7!//jf4cfls225.pdx.intel.com/apd_proj/ppg_lib/epg_masterlib/logical/mstr_discrete/cap/chips/chips.prt!CAP!CAP_0603LF-10UF,4V,20%,X6S,E15431-001!CAP!!!F2631!!VDDQ_DEF_CPU0!!
S!@baseboard_fab2_lib.baseboard_fab2(sch_1):page220_i184@mstr_discrete.cap(chips)!CAP_0603LF-10UF,4V,20%,X6S,E15A!C5D8!//jf4cfls225.pdx.intel.com/apd_proj/ppg_lib/epg_masterlib/logical/mstr_discrete/cap/chips/chips.prt!CAP!CAP_0603LF-10UF,4V,20%,X6S,E15431-001!CAP!!!F2630!!VDDQ_DEF_CPU0!!
S!@baseboard_fab2_lib.baseboard_fab2(sch_1):page225_i179@mstr_discrete.cap(chips)!CAP_0603LF-10UF,4V,20%,X6S,E15A!C2D43!//jf4cfls225.pdx.intel.com/apd_proj/ppg_lib/epg_masterlib/logical/mstr_discrete/cap/chips/chips.prt!CAP!CAP_0603LF-10UF,4V,20%,X6S,E15431-001!CAP!!!F2667!!VDDQ_GHJ_CPU1!!
S!@baseboard_fab2_lib.baseboard_fab2(sch_1):page225_i180@mstr_discrete.cap(chips)!CAP_0603LF-10UF,4V,20%,X6S,E15A!C2D41!//jf4cfls225.pdx.intel.com/apd_proj/ppg_lib/epg_masterlib/logical/mstr_discrete/cap/chips/chips.prt!CAP!CAP_0603LF-10UF,4V,20%,X6S,E15431-001!CAP!!!F2669!!VDDQ_GHJ_CPU1!!
S!@baseboard_fab2_lib.baseboard_fab2(sch_1):page225_i181@mstr_discrete.cap(chips)!CAP_0603LF-10UF,4V,20%,X6S,E15A!C2D44!//jf4cfls225.pdx.intel.com/apd_proj/ppg_lib/epg_masterlib/logical/mstr_discrete/cap/chips/chips.prt!CAP!CAP_0603LF-10UF,4V,20%,X6S,E15431-001!CAP!!!F2666!!VDDQ_GHJ_CPU1!!
S!@baseboard_fab2_lib.baseboard_fab2(sch_1):page225_i183@mstr_discrete.cap(chips)!CAP_0603LF-10UF,4V,20%,X6S,E15A!C2D42!//jf4cfls225.pdx.intel.com/apd_proj/ppg_lib/epg_masterlib/logical/mstr_discrete/cap/chips/chips.prt!CAP!CAP_0603LF-10UF,4V,20%,X6S,E15431-001!CAP!!!F2668!!VDDQ_GHJ_CPU1!!
S!@baseboard_fab2_lib.baseboard_fab2(sch_1):page228_i186@mstr_discrete.cap(chips)!CAP_0603LF-10UF,4V,20%,X6S,E15A!C2D7!//jf4cfls225.pdx.intel.com/apd_proj/ppg_lib/epg_masterlib/logical/mstr_discrete/cap/chips/chips.prt!CAP!CAP_0603LF-10UF,4V,20%,X6S,E15431-001!CAP!!!F2674!!VDDQ_KLM_CPU1!!
S!@baseboard_fab2_lib.baseboard_fab2(sch_1):page228_i187@mstr_discrete.cap(chips)!CAP_0603LF-10UF,4V,20%,X6S,E15A!C2D4!//jf4cfls225.pdx.intel.com/apd_proj/ppg_lib/epg_masterlib/logical/mstr_discrete/cap/chips/chips.prt!CAP!CAP_0603LF-10UF,4V,20%,X6S,E15431-001!CAP!!!F2677!!VDDQ_KLM_CPU1!!
S!@baseboard_fab2_lib.baseboard_fab2(sch_1):page228_i188@mstr_discrete.cap(chips)!CAP_0603LF-10UF,4V,20%,X6S,E15A!C2D5!//jf4cfls225.pdx.intel.com/apd_proj/ppg_lib/epg_masterlib/logical/mstr_discrete/cap/chips/chips.prt!CAP!CAP_0603LF-10UF,4V,20%,X6S,E15431-001!CAP!!!F2676!!VDDQ_KLM_CPU1!!
S!@baseboard_fab2_lib.baseboard_fab2(sch_1):page228_i190@mstr_discrete.cap(chips)!CAP_0603LF-10UF,4V,20%,X6S,E15A!C2D6!//jf4cfls225.pdx.intel.com/apd_proj/ppg_lib/epg_masterlib/logical/mstr_discrete/cap/chips/chips.prt!CAP!CAP_0603LF-10UF,4V,20%,X6S,E15431-001!CAP!!!F2675!!VDDQ_KLM_CPU1!!
S!@baseboard_fab2_lib.baseboard_fab2(sch_1):page42_i108@mstr_discrete.cap(chips)!CAP_0603LF-10UF,4V,20%,X6S,E15A!C5D10!//jf4cfls225.pdx.intel.com/apd_proj/ppg_lib/epg_masterlib/logical/mstr_discrete/cap/chips/chips.prt!CAP!CAP_0603LF-10UF,4V,20%,X6S,E15431-001!CAP!!!F2628!!PVCCIN_CPU0_DECAP_VR!!
S!@baseboard_fab2_lib.baseboard_fab2(sch_1):page42_i94@mstr_discrete.cap(chips)!CAP_0603LF-10UF,4V,20%,X6S,E15A!C5D12!//jf4cfls225.pdx.intel.com/apd_proj/ppg_lib/epg_masterlib/logical/mstr_discrete/cap/chips/chips.prt!CAP!CAP_0603LF-10UF,4V,20%,X6S,E15431-001!CAP!!!F2626!!PVCCIN_CPU0_DECAP_VR!!
S!@baseboard_fab2_lib.baseboard_fab2(sch_1):page42_i93@mstr_discrete.cap(chips)!CAP_0603LF-10UF,4V,20%,X6S,E15A!C5D11!//jf4cfls225.pdx.intel.com/apd_proj/ppg_lib/epg_masterlib/logical/mstr_discrete/cap/chips/chips.prt!CAP!CAP_0603LF-10UF,4V,20%,X6S,E15431-001!CAP!!!F2627!!PVCCIN_CPU0_DECAP_VR!!
S!@baseboard_fab2_lib.baseboard_fab2(sch_1):page42_i91@mstr_discrete.cap(chips)!CAP_0603LF-10UF,4V,20%,X6S,E15A!C5D13!//jf4cfls225.pdx.intel.com/apd_proj/ppg_lib/epg_masterlib/logical/mstr_discrete/cap/chips/chips.prt!CAP!CAP_0603LF-10UF,4V,20%,X6S,E15431-001!CAP!!!F2625!!PVCCIN_CPU0_DECAP_VR!!
S!@baseboard_fab2_lib.baseboard_fab2(sch_1):page76_i43@mstr_discrete.cap(chips)!CAP_0603LF-10UF,4V,20%,X6S,E15A!C2D9!//jf4cfls225.pdx.intel.com/apd_proj/ppg_lib/epg_masterlib/logical/mstr_discrete/cap/chips/chips.prt!CAP!CAP_0603LF-10UF,4V,20%,X6S,E15431-001!CAP!!!F2672!!PVCCIN_CPU1_DECAP_VR!!
S!@baseboard_fab2_lib.baseboard_fab2(sch_1):page76_i42@mstr_discrete.cap(chips)!CAP_0603LF-10UF,4V,20%,X6S,E15A!C2D11!//jf4cfls225.pdx.intel.com/apd_proj/ppg_lib/epg_masterlib/logical/mstr_discrete/cap/chips/chips.prt!CAP!CAP_0603LF-10UF,4V,20%,X6S,E15431-001!CAP!!!F2670!!PVCCIN_CPU1_DECAP_VR!!
S!@baseboard_fab2_lib.baseboard_fab2(sch_1):page76_i37@mstr_discrete.cap(chips)!CAP_0603LF-10UF,4V,20%,X6S,E15A!C2D10!//jf4cfls225.pdx.intel.com/apd_proj/ppg_lib/epg_masterlib/logical/mstr_discrete/cap/chips/chips.prt!CAP!CAP_0603LF-10UF,4V,20%,X6S,E15431-001!CAP!!!F2671!!PVCCIN_CPU1_DECAP_VR!!
S!@baseboard_fab2_lib.baseboard_fab2(sch_1):page76_i33@mstr_discrete.cap(chips)!CAP_0603LF-10UF,4V,20%,X6S,E15A!C2D8!//jf4cfls225.pdx.intel.com/apd_proj/ppg_lib/epg_masterlib/logical/mstr_discrete/cap/chips/chips.prt!CAP!CAP_0603LF-10UF,4V,20%,X6S,E15431-001!CAP!!!F2673!!PVCCIN_CPU1_DECAP_VR!!
S!@baseboard_fab2_lib.baseboard_fab2(sch_1):page72_i25@mstr_discrete.cap(chips)!CAP_0603LF-10UF,4V,20%,X6S,E15A!C3D3!//jf4cfls225.pdx.intel.com/apd_proj/ppg_lib/epg_masterlib/logical/mstr_discrete/cap/chips/chips.prt!CAP!CAP_0603LF-10UF,4V,20%,X6S,E15431-001!CAP!!!F2656!!CPU1!!
S!@baseboard_fab2_lib.baseboard_fab2(sch_1):page38_i19@mstr_discrete.cap(chips)!CAP_0603LF-10UF,4V,20%,X6S,E15A!C6D1!//jf4cfls225.pdx.intel.com/apd_proj/ppg_lib/epg_masterlib/logical/mstr_discrete/cap/chips/chips.prt!CAP!CAP_0603LF-10UF,4V,20%,X6S,E15431-001!CAP!!!F2614!!CPU0!!
S!@baseboard_fab2_lib.baseboard_fab2(sch_1):page172_i39@mstr_discrete.cap(chips)!CAP_0805-10UF,16V,10%,X6S,C953A!C9B1!//jf4cfls225.pdx.intel.com/apd_proj/ppg_lib/epg_masterlib/logical/mstr_discrete/cap/chips/chips.prt!CAP!CAP_0805-10UF,16V,10%,X6S,C95333-007!CAP!!!F2483!!ST_SATA!!
S!@baseboard_fab2_lib.baseboard_fab2(sch_1):page172_i36@mstr_discrete.cap(chips)!CAP_0805-10UF,16V,10%,X6S,C953A!C9B2!//jf4cfls225.pdx.intel.com/apd_proj/ppg_lib/epg_masterlib/logical/mstr_discrete/cap/chips/chips.prt!CAP!CAP_0805-10UF,16V,10%,X6S,C95333-007!CAP!!!F2482!!ST_SATA!!
S!@baseboard_fab2_lib.baseboard_fab2(sch_1):page101_i113@mstr_discrete.cap(chips)!CAP_0805-10UF,16V,10%,X6S,C953A!C2T22!//jf4cfls225.pdx.intel.com/apd_proj/ppg_lib/epg_masterlib/logical/mstr_discrete/cap/chips/chips.prt!CAP!CAP_0805-10UF,16V,10%,X6S,C95333-007!CAP!!!F2548!!SYS_CLOCK!!
S!@baseboard_fab2_lib.baseboard_fab2(sch_1):page231_i209@mstr_discrete.cap(chips)!CAP_0805-10UF,16V,10%,X6S,C953A!C7F5!//jf4cfls225.pdx.intel.com/apd_proj/ppg_lib/epg_masterlib/logical/mstr_discrete/cap/chips/chips.prt!CAP!CAP_0805-10UF,16V,10%,X6S,C95333-007!CAP!!!F2486!!!!
S!@baseboard_fab2_lib.baseboard_fab2(sch_1):page231_i210@mstr_discrete.cap(chips)!CAP_0805-10UF,16V,10%,X6S,C953A!C3T8!//jf4cfls225.pdx.intel.com/apd_proj/ppg_lib/epg_masterlib/logical/mstr_discrete/cap/chips/chips.prt!CAP!CAP_0805-10UF,16V,10%,X6S,C95333-007!CAP!!!F2527!!!!
S!@baseboard_fab2_lib.baseboard_fab2(sch_1):page231_i211@mstr_discrete.cap(chips)!CAP_0805-10UF,16V,10%,X6S,C953A!C3T14!//jf4cfls225.pdx.intel.com/apd_proj/ppg_lib/epg_masterlib/logical/mstr_discrete/cap/chips/chips.prt!CAP!CAP_0805-10UF,16V,10%,X6S,C95333-007!CAP!!!F2525!!!!
S!@baseboard_fab2_lib.baseboard_fab2(sch_1):page231_i215@mstr_discrete.cap(chips)!CAP_0805-10UF,16V,10%,X6S,C953A!C3T12!//jf4cfls225.pdx.intel.com/apd_proj/ppg_lib/epg_masterlib/logical/mstr_discrete/cap/chips/chips.prt!CAP!CAP_0805-10UF,16V,10%,X6S,C95333-007!CAP!!!F2526!!!!
S!@baseboard_fab2_lib.baseboard_fab2(sch_1):page232_i259@mstr_discrete.cap(chips)!CAP_0805-10UF,16V,10%,X6S,C953A!C3M8!//jf4cfls225.pdx.intel.com/apd_proj/ppg_lib/epg_masterlib/logical/mstr_discrete/cap/chips/chips.prt!CAP!CAP_0805-10UF,16V,10%,X6S,C95333-007!CAP!!!F2533!!!!
S!@baseboard_fab2_lib.baseboard_fab2(sch_1):page232_i260@mstr_discrete.cap(chips)!CAP_0805-10UF,16V,10%,X6S,C953A!C3M15!//jf4cfls225.pdx.intel.com/apd_proj/ppg_lib/epg_masterlib/logical/mstr_discrete/cap/chips/chips.prt!CAP!CAP_0805-10UF,16V,10%,X6S,C95333-007!CAP!!!F2532!!!!
S!@baseboard_fab2_lib.baseboard_fab2(sch_1):page232_i261@mstr_discrete.cap(chips)!CAP_0805-10UF,16V,10%,X6S,C953A!C3M16!//jf4cfls225.pdx.intel.com/apd_proj/ppg_lib/epg_masterlib/logical/mstr_discrete/cap/chips/chips.prt!CAP!CAP_0805-10UF,16V,10%,X6S,C95333-007!CAP!!!F2531!!!!
S!@baseboard_fab2_lib.baseboard_fab2(sch_1):page232_i262@mstr_discrete.cap(chips)!CAP_0805-10UF,16V,10%,X6S,C953A!C7B5!//jf4cfls225.pdx.intel.com/apd_proj/ppg_lib/epg_masterlib/logical/mstr_discrete/cap/chips/chips.prt!CAP!CAP_0805-10UF,16V,10%,X6S,C95333-007!CAP!!!F2489!!!!
S!@baseboard_fab2_lib.baseboard_fab2(sch_1):page233_i248@mstr_discrete.cap(chips)!CAP_0805-10UF,16V,10%,X6S,C953A!C6U4!//jf4cfls225.pdx.intel.com/apd_proj/ppg_lib/epg_masterlib/logical/mstr_discrete/cap/chips/chips.prt!CAP!CAP_0805-10UF,16V,10%,X6S,C95333-007!CAP!!!F2492!!!!
S!@baseboard_fab2_lib.baseboard_fab2(sch_1):page233_i253@mstr_discrete.cap(chips)!CAP_0805-10UF,16V,10%,X6S,C953A!C4G2!//jf4cfls225.pdx.intel.com/apd_proj/ppg_lib/epg_masterlib/logical/mstr_discrete/cap/chips/chips.prt!CAP!CAP_0805-10UF,16V,10%,X6S,C95333-007!CAP!!!F2517!!!!
S!@baseboard_fab2_lib.baseboard_fab2(sch_1):page233_i254@mstr_discrete.cap(chips)!CAP_0805-10UF,16V,10%,X6S,C953A!C6U7!//jf4cfls225.pdx.intel.com/apd_proj/ppg_lib/epg_masterlib/logical/mstr_discrete/cap/chips/chips.prt!CAP!CAP_0805-10UF,16V,10%,X6S,C95333-007!CAP!!!F2491!!!!
S!@baseboard_fab2_lib.baseboard_fab2(sch_1):page233_i255@mstr_discrete.cap(chips)!CAP_0805-10UF,16V,10%,X6S,C953A!C6U8!//jf4cfls225.pdx.intel.com/apd_proj/ppg_lib/epg_masterlib/logical/mstr_discrete/cap/chips/chips.prt!CAP!CAP_0805-10UF,16V,10%,X6S,C95333-007!CAP!!!F2490!!!!
S!@baseboard_fab2_lib.baseboard_fab2(sch_1):page234_i202@mstr_discrete.cap(chips)!CAP_0805-10UF,16V,10%,X6S,C953A!C6L10!//jf4cfls225.pdx.intel.com/apd_proj/ppg_lib/epg_masterlib/logical/mstr_discrete/cap/chips/chips.prt!CAP!CAP_0805-10UF,16V,10%,X6S,C95333-007!CAP!!!F2516!!!!
S!@baseboard_fab2_lib.baseboard_fab2(sch_1):page234_i203@mstr_discrete.cap(chips)!CAP_0805-10UF,16V,10%,X6S,C953A!C6M3!//jf4cfls225.pdx.intel.com/apd_proj/ppg_lib/epg_masterlib/logical/mstr_discrete/cap/chips/chips.prt!CAP!CAP_0805-10UF,16V,10%,X6S,C95333-007!CAP!!!F2515!!!!
S!@baseboard_fab2_lib.baseboard_fab2(sch_1):page234_i204@mstr_discrete.cap(chips)!CAP_0805-10UF,16V,10%,X6S,C953A!C6M5!//jf4cfls225.pdx.intel.com/apd_proj/ppg_lib/epg_masterlib/logical/mstr_discrete/cap/chips/chips.prt!CAP!CAP_0805-10UF,16V,10%,X6S,C95333-007!CAP!!!F2514!!!!
S!@baseboard_fab2_lib.baseboard_fab2(sch_1):page234_i205@mstr_discrete.cap(chips)!CAP_0805-10UF,16V,10%,X6S,C953A!C4A19!//jf4cfls225.pdx.intel.com/apd_proj/ppg_lib/epg_masterlib/logical/mstr_discrete/cap/chips/chips.prt!CAP!CAP_0805-10UF,16V,10%,X6S,C95333-007!CAP!!!F2518!!!!
S!@baseboard_fab2_lib.baseboard_fab2(sch_1):page198_i61@mstr_discrete.cap(chips)!CAP_0805-10UF,16V,10%,X6S,C953A!C1B18!//jf4cfls225.pdx.intel.com/apd_proj/ppg_lib/epg_masterlib/logical/mstr_discrete/cap/chips/chips.prt!CAP!CAP_0805-10UF,16V,10%,X6S,C95333-007!CAP!!!F2556!!P12V_FAN_PWR_SWITCH!!
S!@baseboard_fab2_lib.baseboard_fab2(sch_1):page198_i74@mstr_discrete.cap(chips)!CAP_0805-10UF,16V,10%,X6S,C953A!C9M10!//jf4cfls225.pdx.intel.com/apd_proj/ppg_lib/epg_masterlib/logical/mstr_discrete/cap/chips/chips.prt!CAP!CAP_0805-10UF,16V,10%,X6S,C95333-007!CAP!!!F2474!!P12V_FAN_PWR_SWITCH!!
S!@baseboard_fab2_lib.baseboard_fab2(sch_1):page236_i31@mstr_discrete.cap(chips)!CAP_0805-10UF,16V,10%,X6S,C953A!C3L7!//jf4cfls225.pdx.intel.com/apd_proj/ppg_lib/epg_masterlib/logical/mstr_discrete/cap/chips/chips.prt!CAP!CAP_0805-10UF,16V,10%,X6S,C95333-007!CAP!!!F2543!!P1V05_PCH_STBY_VR!!
S!@baseboard_fab2_lib.baseboard_fab2(sch_1):page236_i24@mstr_discrete.cap(chips)!CAP_0805-10UF,16V,10%,X6S,C953A!C3L11!//jf4cfls225.pdx.intel.com/apd_proj/ppg_lib/epg_masterlib/logical/mstr_discrete/cap/chips/chips.prt!CAP!CAP_0805-10UF,16V,10%,X6S,C95333-007!CAP!!!F2539!!PVNN_PCH_STBY!!
S!@baseboard_fab2_lib.baseboard_fab2(sch_1):page236_i29@mstr_discrete.cap(chips)!CAP_0805-10UF,16V,10%,X6S,C953A!C3L9!//jf4cfls225.pdx.intel.com/apd_proj/ppg_lib/epg_masterlib/logical/mstr_discrete/cap/chips/chips.prt!CAP!CAP_0805-10UF,16V,10%,X6S,C95333-007!CAP!!!F2541!!P1V05_PCH_STBY_VR!!
S!@baseboard_fab2_lib.baseboard_fab2(sch_1):page236_i26@mstr_discrete.cap(chips)!CAP_0805-10UF,16V,10%,X6S,C953A!C3L8!//jf4cfls225.pdx.intel.com/apd_proj/ppg_lib/epg_masterlib/logical/mstr_discrete/cap/chips/chips.prt!CAP!CAP_0805-10UF,16V,10%,X6S,C95333-007!CAP!!!F2542!!PVNN_PCH_STBY!!
S!@baseboard_fab2_lib.baseboard_fab2(sch_1):page236_i32@mstr_discrete.cap(chips)!CAP_0805-10UF,16V,10%,X6S,C953A!C3L10!//jf4cfls225.pdx.intel.com/apd_proj/ppg_lib/epg_masterlib/logical/mstr_discrete/cap/chips/chips.prt!CAP!CAP_0805-10UF,16V,10%,X6S,C95333-007!CAP!!!F2540!!P1V05_PCH_STBY_VR!!
S!@baseboard_fab2_lib.baseboard_fab2(sch_1):page236_i23@mstr_discrete.cap(chips)!CAP_0805-10UF,16V,10%,X6S,C953A!C3L12!//jf4cfls225.pdx.intel.com/apd_proj/ppg_lib/epg_masterlib/logical/mstr_discrete/cap/chips/chips.prt!CAP!CAP_0805-10UF,16V,10%,X6S,C95333-007!CAP!!!F2538!!PVNN_PCH_STBY!!
S!@baseboard_fab2_lib.baseboard_fab2(sch_1):page212_i43@mstr_discrete.cap(chips)!CAP_0805-10UF,16V,10%,X6S,C953A!C3N34!//jf4cfls225.pdx.intel.com/apd_proj/ppg_lib/epg_masterlib/logical/mstr_discrete/cap/chips/chips.prt!CAP!CAP_0805-10UF,16V,10%,X6S,C95333-007!CAP!!!F2529!!PVCCIO_CPU0!!
S!@baseboard_fab2_lib.baseboard_fab2(sch_1):page212_i40@mstr_discrete.cap(chips)!CAP_0805-10UF,16V,10%,X6S,C953A!C3N36!//jf4cfls225.pdx.intel.com/apd_proj/ppg_lib/epg_masterlib/logical/mstr_discrete/cap/chips/chips.prt!CAP!CAP_0805-10UF,16V,10%,X6S,C95333-007!CAP!!!F2528!!PVCCIO_CPU0!!
S!@baseboard_fab2_lib.baseboard_fab2(sch_1):page214_i83@mstr_discrete.cap(chips)!CAP_0805-10UF,16V,10%,X6S,C953A!C6R8!//jf4cfls225.pdx.intel.com/apd_proj/ppg_lib/epg_masterlib/logical/mstr_discrete/cap/chips/chips.prt!CAP!CAP_0805-10UF,16V,10%,X6S,C95333-007!CAP!!!F2497!!PVCCIO_CPU1!!
S!@baseboard_fab2_lib.baseboard_fab2(sch_1):page214_i81@mstr_discrete.cap(chips)!CAP_0805-10UF,16V,10%,X6S,C953A!C6R10!//jf4cfls225.pdx.intel.com/apd_proj/ppg_lib/epg_masterlib/logical/mstr_discrete/cap/chips/chips.prt!CAP!CAP_0805-10UF,16V,10%,X6S,C95333-007!CAP!!!F2496!!PVCCIO_CPU1!!
S!@baseboard_fab2_lib.baseboard_fab2(sch_1):page214_i80@mstr_discrete.cap(chips)!CAP_0805-10UF,16V,10%,X6S,C953A!C6R14!//jf4cfls225.pdx.intel.com/apd_proj/ppg_lib/epg_masterlib/logical/mstr_discrete/cap/chips/chips.prt!CAP!CAP_0805-10UF,16V,10%,X6S,C95333-007!CAP!!!F2493!!PVCCIO_CPU1!!
S!@baseboard_fab2_lib.baseboard_fab2(sch_1):page203_i1@mstr_discrete.cap(chips)!CAP_0805-10UF,16V,10%,X6S,C953A!C6P24!//jf4cfls225.pdx.intel.com/apd_proj/ppg_lib/epg_masterlib/logical/mstr_discrete/cap/chips/chips.prt!CAP!CAP_0805-10UF,16V,10%,X6S,C95333-007!CAP!!!F2500!!PVCCIN_CPU0_PWR_VR!!
S!@baseboard_fab2_lib.baseboard_fab2(sch_1):page203_i2@mstr_discrete.cap(chips)!CAP_0805-10UF,16V,10%,X6S,C953A!C6R6!//jf4cfls225.pdx.intel.com/apd_proj/ppg_lib/epg_masterlib/logical/mstr_discrete/cap/chips/chips.prt!CAP!CAP_0805-10UF,16V,10%,X6S,C95333-007!CAP!!!F2498!!PVCCIN_CPU0_PWR_VR!!
S!@baseboard_fab2_lib.baseboard_fab2(sch_1):page203_i54@mstr_discrete.cap(chips)!CAP_0805-10UF,16V,10%,X6S,C953A!C6P19!//jf4cfls225.pdx.intel.com/apd_proj/ppg_lib/epg_masterlib/logical/mstr_discrete/cap/chips/chips.prt!CAP!CAP_0805-10UF,16V,10%,X6S,C95333-007!CAP!!!F2503!!PVCCIN_CPU0_PWR_VR!!
S!@baseboard_fab2_lib.baseboard_fab2(sch_1):page203_i59@mstr_discrete.cap(chips)!CAP_0805-10UF,16V,10%,X6S,C953A!C6P7!//jf4cfls225.pdx.intel.com/apd_proj/ppg_lib/epg_masterlib/logical/mstr_discrete/cap/chips/chips.prt!CAP!CAP_0805-10UF,16V,10%,X6S,C95333-007!CAP!!!F2507!!PVCCIN_CPU0_PWR_VR!!
S!@baseboard_fab2_lib.baseboard_fab2(sch_1):page203_i58@mstr_discrete.cap(chips)!CAP_0805-10UF,16V,10%,X6S,C953A!C6P15!//jf4cfls225.pdx.intel.com/apd_proj/ppg_lib/epg_masterlib/logical/mstr_discrete/cap/chips/chips.prt!CAP!CAP_0805-10UF,16V,10%,X6S,C95333-007!CAP!!!F2505!!PVCCIN_CPU0_PWR_VR!!
S!@baseboard_fab2_lib.baseboard_fab2(sch_1):page203_i57@mstr_discrete.cap(chips)!CAP_0805-10UF,16V,10%,X6S,C953A!C6P20!//jf4cfls225.pdx.intel.com/apd_proj/ppg_lib/epg_masterlib/logical/mstr_discrete/cap/chips/chips.prt!CAP!CAP_0805-10UF,16V,10%,X6S,C95333-007!CAP!!!F2502!!PVCCIN_CPU0_PWR_VR!!
S!@baseboard_fab2_lib.baseboard_fab2(sch_1):page161_i3@mstr_discrete.cap(chips)!CAP_0805-10UF,16V,10%,X6S,C953A!C1E21!//jf4cfls225.pdx.intel.com/apd_proj/ppg_lib/epg_masterlib/logical/mstr_discrete/cap/chips/chips.prt!CAP!CAP_0805-10UF,16V,10%,X6S,C95333-007!CAP!!!F2553!!CPU_FANS!!
S!@baseboard_fab2_lib.baseboard_fab2(sch_1):page161_i27@mstr_discrete.cap(chips)!CAP_0805-10UF,16V,10%,X6S,C953A!C9M4!//jf4cfls225.pdx.intel.com/apd_proj/ppg_lib/epg_masterlib/logical/mstr_discrete/cap/chips/chips.prt!CAP!CAP_0805-10UF,16V,10%,X6S,C95333-007!CAP!!!F2475!!CPU_FANS!!
S!@baseboard_fab2_lib.baseboard_fab2(sch_1):page198_i53@mstr_discrete.cap(chips)!CAP_0805-10UF,16V,10%,X6S,C953A!C7E6!//jf4cfls225.pdx.intel.com/apd_proj/ppg_lib/epg_masterlib/logical/mstr_discrete/cap/chips/chips.prt!CAP!CAP_0805-10UF,16V,10%,X6S,C95333-007!CAP!!!F2488!!P12V_PWR_SWITCH!!
S!@baseboard_fab2_lib.baseboard_fab2(sch_1):page198_i50@mstr_discrete.cap(chips)!CAP_0805-10UF,16V,10%,X6S,C953A!C7E8!//jf4cfls225.pdx.intel.com/apd_proj/ppg_lib/epg_masterlib/logical/mstr_discrete/cap/chips/chips.prt!CAP!CAP_0805-10UF,16V,10%,X6S,C95333-007!CAP!!!F2487!!P12V_PWR_SWITCH!!
S!@baseboard_fab2_lib.baseboard_fab2(sch_1):page198_i44@mstr_discrete.cap(chips)!CAP_0805-10UF,16V,10%,X6S,C953A!C2U1!//jf4cfls225.pdx.intel.com/apd_proj/ppg_lib/epg_masterlib/logical/mstr_discrete/cap/chips/chips.prt!CAP!CAP_0805-10UF,16V,10%,X6S,C95333-007!CAP!!!F2547!!P3V3_PWR_SWITCH!!
S!@baseboard_fab2_lib.baseboard_fab2(sch_1):page198_i47@mstr_discrete.cap(chips)!CAP_0805-10UF,16V,10%,X6S,C953A!C2U2!//jf4cfls225.pdx.intel.com/apd_proj/ppg_lib/epg_masterlib/logical/mstr_discrete/cap/chips/chips.prt!CAP!CAP_0805-10UF,16V,10%,X6S,C95333-007!CAP!!!F2546!!P3V3_PWR_SWITCH!!
S!@baseboard_fab2_lib.baseboard_fab2(sch_1):page198_i38@mstr_discrete.cap(chips)!CAP_0805-10UF,16V,10%,X6S,C953A!C8B12!//jf4cfls225.pdx.intel.com/apd_proj/ppg_lib/epg_masterlib/logical/mstr_discrete/cap/chips/chips.prt!CAP!CAP_0805-10UF,16V,10%,X6S,C95333-007!CAP!!!F2484!!P5V_PWR_SWITCH!!
S!@baseboard_fab2_lib.baseboard_fab2(sch_1):page198_i40@mstr_discrete.cap(chips)!CAP_0805-10UF,16V,10%,X6S,C953A!C8B6!//jf4cfls225.pdx.intel.com/apd_proj/ppg_lib/epg_masterlib/logical/mstr_discrete/cap/chips/chips.prt!CAP!CAP_0805-10UF,16V,10%,X6S,C95333-007!CAP!!!F2485!!P5V_PWR_SWITCH!!
S!@baseboard_fab2_lib.baseboard_fab2(sch_1):page195_i31@mstr_discrete.cap(chips)!CAP_0805-10UF,16V,10%,X6S,C953A!C9R5!//jf4cfls225.pdx.intel.com/apd_proj/ppg_lib/epg_masterlib/logical/mstr_discrete/cap/chips/chips.prt!CAP!CAP_0805-10UF,16V,10%,X6S,C95333-007!CAP!!!F2458!!HOT_SWAP!!
S!@baseboard_fab2_lib.baseboard_fab2(sch_1):page195_i32@mstr_discrete.cap(chips)!CAP_0805-10UF,16V,10%,X6S,C953A!C1E12!//jf4cfls225.pdx.intel.com/apd_proj/ppg_lib/epg_masterlib/logical/mstr_discrete/cap/chips/chips.prt!CAP!CAP_0805-10UF,16V,10%,X6S,C95333-007!CAP!!!F2555!!HOT_SWAP!!
S!@baseboard_fab2_lib.baseboard_fab2(sch_1):page212_i41@mstr_discrete.cap(chips)!CAP_0805-10UF,16V,10%,X6S,C953A!C3N33!//jf4cfls225.pdx.intel.com/apd_proj/ppg_lib/epg_masterlib/logical/mstr_discrete/cap/chips/chips.prt!CAP!CAP_0805-10UF,16V,10%,X6S,C95333-007!CAP!!!F2530!!PVCCIO_CPU0!!
S!@baseboard_fab2_lib.baseboard_fab2(sch_1):page209_i5@mstr_discrete.cap(chips)!CAP_0805-10UF,16V,10%,X6S,C953A!C9N27!//jf4cfls225.pdx.intel.com/apd_proj/ppg_lib/epg_masterlib/logical/mstr_discrete/cap/chips/chips.prt!CAP!CAP_0805-10UF,16V,10%,X6S,C95333-007!CAP!!!F2462!!PVCCIN_CPU1_PWR_VR!!
S!@baseboard_fab2_lib.baseboard_fab2(sch_1):page209_i7@mstr_discrete.cap(chips)!CAP_0805-10UF,16V,10%,X6S,C953A!C9N26!//jf4cfls225.pdx.intel.com/apd_proj/ppg_lib/epg_masterlib/logical/mstr_discrete/cap/chips/chips.prt!CAP!CAP_0805-10UF,16V,10%,X6S,C95333-007!CAP!!!F2463!!PVCCIN_CPU1_PWR_VR!!
S!@baseboard_fab2_lib.baseboard_fab2(sch_1):page209_i8@mstr_discrete.cap(chips)!CAP_0805-10UF,16V,10%,X6S,C953A!C9N25!//jf4cfls225.pdx.intel.com/apd_proj/ppg_lib/epg_masterlib/logical/mstr_discrete/cap/chips/chips.prt!CAP!CAP_0805-10UF,16V,10%,X6S,C95333-007!CAP!!!F2464!!PVCCIN_CPU1_PWR_VR!!
S!@baseboard_fab2_lib.baseboard_fab2(sch_1):page186_i3@mstr_discrete.cap(chips)!CAP_0805-10UF,16V,10%,X6S,C953A!C1M27!//jf4cfls225.pdx.intel.com/apd_proj/ppg_lib/epg_masterlib/logical/mstr_discrete/cap/chips/chips.prt!CAP!CAP_0805-10UF,16V,10%,X6S,C95333-007!CAP!!!F2551!!IO_SLOT!!
S!@baseboard_fab2_lib.baseboard_fab2(sch_1):page186_i6@mstr_discrete.cap(chips)!CAP_0805-10UF,16V,10%,X6S,C953A!C1M26!//jf4cfls225.pdx.intel.com/apd_proj/ppg_lib/epg_masterlib/logical/mstr_discrete/cap/chips/chips.prt!CAP!CAP_0805-10UF,16V,10%,X6S,C95333-007!CAP!!!F2552!!IO_SLOT!!
S!@baseboard_fab2_lib.baseboard_fab2(sch_1):page149_i88@mstr_discrete.cap(chips)!CAP_0805-10UF,16V,10%,X6S,C953A!C1U12!//jf4cfls225.pdx.intel.com/apd_proj/ppg_lib/epg_masterlib/logical/mstr_discrete/cap/chips/chips.prt!CAP!CAP_0805-10UF,16V,10%,X6S,C95333-007!CAP!!!F2549!!BMC!!
S!@baseboard_fab2_lib.baseboard_fab2(sch_1):page149_i84@mstr_discrete.cap(chips)!CAP_0805-10UF,16V,10%,X6S,C953A!C1U1!//jf4cfls225.pdx.intel.com/apd_proj/ppg_lib/epg_masterlib/logical/mstr_discrete/cap/chips/chips.prt!CAP!CAP_0805-10UF,16V,10%,X6S,C95333-007!CAP!!!F2550!!BMC!!
S!@baseboard_fab2_lib.baseboard_fab2(sch_1):page202_i38@mstr_discrete.cap(chips)!CAP_0805-10UF,16V,10%,X6S,C953A!C6P13!//jf4cfls225.pdx.intel.com/apd_proj/ppg_lib/epg_masterlib/logical/mstr_discrete/cap/chips/chips.prt!CAP!CAP_0805-10UF,16V,10%,X6S,C95333-007!CAP!!!F2506!!PVCCIN_CPU0_PWR_VR!!
S!@baseboard_fab2_lib.baseboard_fab2(sch_1):page204_i38@mstr_discrete.cap(chips)!CAP_0805-10UF,16V,10%,X6S,C953A!C6P17!//jf4cfls225.pdx.intel.com/apd_proj/ppg_lib/epg_masterlib/logical/mstr_discrete/cap/chips/chips.prt!CAP!CAP_0805-10UF,16V,10%,X6S,C95333-007!CAP!!!F2504!!PVCCIN_CPU0_PWR_VR!!
S!@baseboard_fab2_lib.baseboard_fab2(sch_1):page202_i51@mstr_discrete.cap(chips)!CAP_0805-10UF,16V,10%,X6S,C953A!C6N8!//jf4cfls225.pdx.intel.com/apd_proj/ppg_lib/epg_masterlib/logical/mstr_discrete/cap/chips/chips.prt!CAP!CAP_0805-10UF,16V,10%,X6S,C95333-007!CAP!!!F2510!!PVCCIN_CPU0_PWR_VR!!
S!@baseboard_fab2_lib.baseboard_fab2(sch_1):page202_i42@mstr_discrete.cap(chips)!CAP_0805-10UF,16V,10%,X6S,C953A!C6R13!//jf4cfls225.pdx.intel.com/apd_proj/ppg_lib/epg_masterlib/logical/mstr_discrete/cap/chips/chips.prt!CAP!CAP_0805-10UF,16V,10%,X6S,C95333-007!CAP!!!F2494!!PVCCIN_CPU0_PWR_VR!!
S!@baseboard_fab2_lib.baseboard_fab2(sch_1):page202_i49@mstr_discrete.cap(chips)!CAP_0805-10UF,16V,10%,X6S,C953A!C6P22!//jf4cfls225.pdx.intel.com/apd_proj/ppg_lib/epg_masterlib/logical/mstr_discrete/cap/chips/chips.prt!CAP!CAP_0805-10UF,16V,10%,X6S,C95333-007!CAP!!!F2501!!PVCCIN_CPU0_PWR_VR!!
S!@baseboard_fab2_lib.baseboard_fab2(sch_1):page202_i48@mstr_discrete.cap(chips)!CAP_0805-10UF,16V,10%,X6S,C953A!C6R4!//jf4cfls225.pdx.intel.com/apd_proj/ppg_lib/epg_masterlib/logical/mstr_discrete/cap/chips/chips.prt!CAP!CAP_0805-10UF,16V,10%,X6S,C95333-007!CAP!!!F2499!!PVCCIN_CPU0_PWR_VR!!
S!@baseboard_fab2_lib.baseboard_fab2(sch_1):page202_i37@mstr_discrete.cap(chips)!CAP_0805-10UF,16V,10%,X6S,C953A!C6R11!//jf4cfls225.pdx.intel.com/apd_proj/ppg_lib/epg_masterlib/logical/mstr_discrete/cap/chips/chips.prt!CAP!CAP_0805-10UF,16V,10%,X6S,C95333-007!CAP!!!F2495!!PVCCIN_CPU0_PWR_VR!!
S!@baseboard_fab2_lib.baseboard_fab2(sch_1):page216_i45@mstr_discrete.cap(chips)!CAP_0805-10UF,16V,10%,X6S,C953A!C3U2!//jf4cfls225.pdx.intel.com/apd_proj/ppg_lib/epg_masterlib/logical/mstr_discrete/cap/chips/chips.prt!CAP!CAP_0805-10UF,16V,10%,X6S,C95333-007!CAP!!!F2524!!VDDQ_ABC_PWR_VR!!
S!@baseboard_fab2_lib.baseboard_fab2(sch_1):page216_i84@mstr_discrete.cap(chips)!CAP_0805-10UF,16V,10%,X6S,C953A!C3U6!//jf4cfls225.pdx.intel.com/apd_proj/ppg_lib/epg_masterlib/logical/mstr_discrete/cap/chips/chips.prt!CAP!CAP_0805-10UF,16V,10%,X6S,C95333-007!CAP!!!F2521!!VDDQ_ABC_PWR_VR!!
S!@baseboard_fab2_lib.baseboard_fab2(sch_1):page216_i46@mstr_discrete.cap(chips)!CAP_0805-10UF,16V,10%,X6S,C953A!C3U3!//jf4cfls225.pdx.intel.com/apd_proj/ppg_lib/epg_masterlib/logical/mstr_discrete/cap/chips/chips.prt!CAP!CAP_0805-10UF,16V,10%,X6S,C95333-007!CAP!!!F2523!!VDDQ_ABC_PWR_VR!!
S!@baseboard_fab2_lib.baseboard_fab2(sch_1):page216_i81@mstr_discrete.cap(chips)!CAP_0805-10UF,16V,10%,X6S,C953A!C3U7!//jf4cfls225.pdx.intel.com/apd_proj/ppg_lib/epg_masterlib/logical/mstr_discrete/cap/chips/chips.prt!CAP!CAP_0805-10UF,16V,10%,X6S,C95333-007!CAP!!!F2520!!VDDQ_ABC_PWR_VR!!
S!@baseboard_fab2_lib.baseboard_fab2(sch_1):page216_i47@mstr_discrete.cap(chips)!CAP_0805-10UF,16V,10%,X6S,C953A!C3U4!//jf4cfls225.pdx.intel.com/apd_proj/ppg_lib/epg_masterlib/logical/mstr_discrete/cap/chips/chips.prt!CAP!CAP_0805-10UF,16V,10%,X6S,C95333-007!CAP!!!F2522!!VDDQ_ABC_PWR_VR!!
S!@baseboard_fab2_lib.baseboard_fab2(sch_1):page216_i80@mstr_discrete.cap(chips)!CAP_0805-10UF,16V,10%,X6S,C953A!C3U9!//jf4cfls225.pdx.intel.com/apd_proj/ppg_lib/epg_masterlib/logical/mstr_discrete/cap/chips/chips.prt!CAP!CAP_0805-10UF,16V,10%,X6S,C95333-007!CAP!!!F2519!!VDDQ_ABC_PWR_VR!!
S!@baseboard_fab2_lib.baseboard_fab2(sch_1):page205_i35@mstr_discrete.cap(chips)!CAP_0805-10UF,16V,10%,X6S,C953A!C6N6!//jf4cfls225.pdx.intel.com/apd_proj/ppg_lib/epg_masterlib/logical/mstr_discrete/cap/chips/chips.prt!CAP!CAP_0805-10UF,16V,10%,X6S,C95333-007!CAP!!!F2511!!PVSA_CPU0_PWR_VR!!
S!@baseboard_fab2_lib.baseboard_fab2(sch_1):page205_i34@mstr_discrete.cap(chips)!CAP_0805-10UF,16V,10%,X6S,C953A!C6N3!//jf4cfls225.pdx.intel.com/apd_proj/ppg_lib/epg_masterlib/logical/mstr_discrete/cap/chips/chips.prt!CAP!CAP_0805-10UF,16V,10%,X6S,C95333-007!CAP!!!F2512!!PVSA_CPU0_PWR_VR!!
S!@baseboard_fab2_lib.baseboard_fab2(sch_1):page205_i33@mstr_discrete.cap(chips)!CAP_0805-10UF,16V,10%,X6S,C953A!C6N2!//jf4cfls225.pdx.intel.com/apd_proj/ppg_lib/epg_masterlib/logical/mstr_discrete/cap/chips/chips.prt!CAP!CAP_0805-10UF,16V,10%,X6S,C95333-007!CAP!!!F2513!!PVSA_CPU0_PWR_VR!!
S!@baseboard_fab2_lib.baseboard_fab2(sch_1):page219_i45@mstr_discrete.cap(chips)!CAP_0805-10UF,16V,10%,X6S,C953A!C3L2!//jf4cfls225.pdx.intel.com/apd_proj/ppg_lib/epg_masterlib/logical/mstr_discrete/cap/chips/chips.prt!CAP!CAP_0805-10UF,16V,10%,X6S,C95333-007!CAP!!!F2545!!VDDQ_DEF_PWR_VR!!
S!@baseboard_fab2_lib.baseboard_fab2(sch_1):page219_i84@mstr_discrete.cap(chips)!CAP_0805-10UF,16V,10%,X6S,C953A!C3L15!//jf4cfls225.pdx.intel.com/apd_proj/ppg_lib/epg_masterlib/logical/mstr_discrete/cap/chips/chips.prt!CAP!CAP_0805-10UF,16V,10%,X6S,C95333-007!CAP!!!F2536!!VDDQ_DEF_PWR_VR!!
S!@baseboard_fab2_lib.baseboard_fab2(sch_1):page219_i46@mstr_discrete.cap(chips)!CAP_0805-10UF,16V,10%,X6S,C953A!C3L4!//jf4cfls225.pdx.intel.com/apd_proj/ppg_lib/epg_masterlib/logical/mstr_discrete/cap/chips/chips.prt!CAP!CAP_0805-10UF,16V,10%,X6S,C95333-007!CAP!!!F2544!!VDDQ_DEF_PWR_VR!!
S!@baseboard_fab2_lib.baseboard_fab2(sch_1):page219_i81@mstr_discrete.cap(chips)!CAP_0805-10UF,16V,10%,X6S,C953A!C3L16!//jf4cfls225.pdx.intel.com/apd_proj/ppg_lib/epg_masterlib/logical/mstr_discrete/cap/chips/chips.prt!CAP!CAP_0805-10UF,16V,10%,X6S,C95333-007!CAP!!!F2535!!VDDQ_DEF_PWR_VR!!
S!@baseboard_fab2_lib.baseboard_fab2(sch_1):page219_i47@mstr_discrete.cap(chips)!CAP_0805-10UF,16V,10%,X6S,C953A!C3L13!//jf4cfls225.pdx.intel.com/apd_proj/ppg_lib/epg_masterlib/logical/mstr_discrete/cap/chips/chips.prt!CAP!CAP_0805-10UF,16V,10%,X6S,C95333-007!CAP!!!F2537!!VDDQ_DEF_PWR_VR!!
S!@baseboard_fab2_lib.baseboard_fab2(sch_1):page219_i80@mstr_discrete.cap(chips)!CAP_0805-10UF,16V,10%,X6S,C953A!C3L17!//jf4cfls225.pdx.intel.com/apd_proj/ppg_lib/epg_masterlib/logical/mstr_discrete/cap/chips/chips.prt!CAP!CAP_0805-10UF,16V,10%,X6S,C95333-007!CAP!!!F2534!!VDDQ_DEF_PWR_VR!!
S!@baseboard_fab2_lib.baseboard_fab2(sch_1):page227_i45@mstr_discrete.cap(chips)!CAP_0805-10UF,16V,10%,X6S,C953A!C9L11!//jf4cfls225.pdx.intel.com/apd_proj/ppg_lib/epg_masterlib/logical/mstr_discrete/cap/chips/chips.prt!CAP!CAP_0805-10UF,16V,10%,X6S,C95333-007!CAP!!!F2478!!VDDQ_KLM_PWR_VR!!
S!@baseboard_fab2_lib.baseboard_fab2(sch_1):page227_i84@mstr_discrete.cap(chips)!CAP_0805-10UF,16V,10%,X6S,C953A!C9L14!//jf4cfls225.pdx.intel.com/apd_proj/ppg_lib/epg_masterlib/logical/mstr_discrete/cap/chips/chips.prt!CAP!CAP_0805-10UF,16V,10%,X6S,C95333-007!CAP!!!F2476!!VDDQ_KLM_PWR_VR!!
S!@baseboard_fab2_lib.baseboard_fab2(sch_1):page227_i46@mstr_discrete.cap(chips)!CAP_0805-10UF,16V,10%,X6S,C953A!C9L10!//jf4cfls225.pdx.intel.com/apd_proj/ppg_lib/epg_masterlib/logical/mstr_discrete/cap/chips/chips.prt!CAP!CAP_0805-10UF,16V,10%,X6S,C95333-007!CAP!!!F2479!!VDDQ_KLM_PWR_VR!!
S!@baseboard_fab2_lib.baseboard_fab2(sch_1):page227_i81@mstr_discrete.cap(chips)!CAP_0805-10UF,16V,10%,X6S,C953A!C9L13!//jf4cfls225.pdx.intel.com/apd_proj/ppg_lib/epg_masterlib/logical/mstr_discrete/cap/chips/chips.prt!CAP!CAP_0805-10UF,16V,10%,X6S,C95333-007!CAP!!!F2477!!VDDQ_KLM_PWR_VR!!
S!@baseboard_fab2_lib.baseboard_fab2(sch_1):page227_i47@mstr_discrete.cap(chips)!CAP_0805-10UF,16V,10%,X6S,C953A!C9L6!//jf4cfls225.pdx.intel.com/apd_proj/ppg_lib/epg_masterlib/logical/mstr_discrete/cap/chips/chips.prt!CAP!CAP_0805-10UF,16V,10%,X6S,C95333-007!CAP!!!F2480!!VDDQ_KLM_PWR_VR!!
S!@baseboard_fab2_lib.baseboard_fab2(sch_1):page227_i80@mstr_discrete.cap(chips)!CAP_0805-10UF,16V,10%,X6S,C953A!C9L5!//jf4cfls225.pdx.intel.com/apd_proj/ppg_lib/epg_masterlib/logical/mstr_discrete/cap/chips/chips.prt!CAP!CAP_0805-10UF,16V,10%,X6S,C95333-007!CAP!!!F2481!!VDDQ_KLM_PWR_VR!!
S!@baseboard_fab2_lib.baseboard_fab2(sch_1):page224_i45@mstr_discrete.cap(chips)!CAP_0805-10UF,16V,10%,X6S,C953A!C9U6!//jf4cfls225.pdx.intel.com/apd_proj/ppg_lib/epg_masterlib/logical/mstr_discrete/cap/chips/chips.prt!CAP!CAP_0805-10UF,16V,10%,X6S,C95333-007!CAP!!!F2449!!VDDQ_GHJ_PWR_VR!!
S!@baseboard_fab2_lib.baseboard_fab2(sch_1):page224_i84@mstr_discrete.cap(chips)!CAP_0805-10UF,16V,10%,X6S,C953A!C9T9!//jf4cfls225.pdx.intel.com/apd_proj/ppg_lib/epg_masterlib/logical/mstr_discrete/cap/chips/chips.prt!CAP!CAP_0805-10UF,16V,10%,X6S,C95333-007!CAP!!!F2452!!VDDQ_GHJ_PWR_VR!!
S!@baseboard_fab2_lib.baseboard_fab2(sch_1):page224_i46@mstr_discrete.cap(chips)!CAP_0805-10UF,16V,10%,X6S,C953A!C9U4!//jf4cfls225.pdx.intel.com/apd_proj/ppg_lib/epg_masterlib/logical/mstr_discrete/cap/chips/chips.prt!CAP!CAP_0805-10UF,16V,10%,X6S,C95333-007!CAP!!!F2450!!VDDQ_GHJ_PWR_VR!!
S!@baseboard_fab2_lib.baseboard_fab2(sch_1):page224_i81@mstr_discrete.cap(chips)!CAP_0805-10UF,16V,10%,X6S,C953A!C9T6!//jf4cfls225.pdx.intel.com/apd_proj/ppg_lib/epg_masterlib/logical/mstr_discrete/cap/chips/chips.prt!CAP!CAP_0805-10UF,16V,10%,X6S,C95333-007!CAP!!!F2453!!VDDQ_GHJ_PWR_VR!!
S!@baseboard_fab2_lib.baseboard_fab2(sch_1):page224_i47@mstr_discrete.cap(chips)!CAP_0805-10UF,16V,10%,X6S,C953A!C9T4!//jf4cfls225.pdx.intel.com/apd_proj/ppg_lib/epg_masterlib/logical/mstr_discrete/cap/chips/chips.prt!CAP!CAP_0805-10UF,16V,10%,X6S,C95333-007!CAP!!!F2454!!VDDQ_GHJ_PWR_VR!!
S!@baseboard_fab2_lib.baseboard_fab2(sch_1):page224_i80@mstr_discrete.cap(chips)!CAP_0805-10UF,16V,10%,X6S,C953A!C9U3!//jf4cfls225.pdx.intel.com/apd_proj/ppg_lib/epg_masterlib/logical/mstr_discrete/cap/chips/chips.prt!CAP!CAP_0805-10UF,16V,10%,X6S,C95333-007!CAP!!!F2451!!VDDQ_GHJ_PWR_VR!!
S!@baseboard_fab2_lib.baseboard_fab2(sch_1):page207_i54@mstr_discrete.cap(chips)!CAP_0805-10UF,16V,10%,X6S,C953A!C9P26!//jf4cfls225.pdx.intel.com/apd_proj/ppg_lib/epg_masterlib/logical/mstr_discrete/cap/chips/chips.prt!CAP!CAP_0805-10UF,16V,10%,X6S,C95333-007!CAP!!!F2459!!PVCCIN_CPU1_PWR_VR!!
S!@baseboard_fab2_lib.baseboard_fab2(sch_1):page207_i48@mstr_discrete.cap(chips)!CAP_0805-10UF,16V,10%,X6S,C953A!C9R11!//jf4cfls225.pdx.intel.com/apd_proj/ppg_lib/epg_masterlib/logical/mstr_discrete/cap/chips/chips.prt!CAP!CAP_0805-10UF,16V,10%,X6S,C95333-007!CAP!!!F2455!!PVCCIN_CPU1_PWR_VR!!
S!@baseboard_fab2_lib.baseboard_fab2(sch_1):page207_i51@mstr_discrete.cap(chips)!CAP_0805-10UF,16V,10%,X6S,C953A!C9P25!//jf4cfls225.pdx.intel.com/apd_proj/ppg_lib/epg_masterlib/logical/mstr_discrete/cap/chips/chips.prt!CAP!CAP_0805-10UF,16V,10%,X6S,C95333-007!CAP!!!F2460!!PVCCIN_CPU1_PWR_VR!!
S!@baseboard_fab2_lib.baseboard_fab2(sch_1):page207_i44@mstr_discrete.cap(chips)!CAP_0805-10UF,16V,10%,X6S,C953A!C9R10!//jf4cfls225.pdx.intel.com/apd_proj/ppg_lib/epg_masterlib/logical/mstr_discrete/cap/chips/chips.prt!CAP!CAP_0805-10UF,16V,10%,X6S,C95333-007!CAP!!!F2456!!PVCCIN_CPU1_PWR_VR!!
S!@baseboard_fab2_lib.baseboard_fab2(sch_1):page207_i50@mstr_discrete.cap(chips)!CAP_0805-10UF,16V,10%,X6S,C953A!C9P22!//jf4cfls225.pdx.intel.com/apd_proj/ppg_lib/epg_masterlib/logical/mstr_discrete/cap/chips/chips.prt!CAP!CAP_0805-10UF,16V,10%,X6S,C95333-007!CAP!!!F2461!!PVCCIN_CPU1_PWR_VR!!
S!@baseboard_fab2_lib.baseboard_fab2(sch_1):page207_i43@mstr_discrete.cap(chips)!CAP_0805-10UF,16V,10%,X6S,C953A!C9R7!//jf4cfls225.pdx.intel.com/apd_proj/ppg_lib/epg_masterlib/logical/mstr_discrete/cap/chips/chips.prt!CAP!CAP_0805-10UF,16V,10%,X6S,C95333-007!CAP!!!F2457!!PVCCIN_CPU1_PWR_VR!!
S!@baseboard_fab2_lib.baseboard_fab2(sch_1):page208_i55@mstr_discrete.cap(chips)!CAP_0805-10UF,16V,10%,X6S,C953A!C9P9!//jf4cfls225.pdx.intel.com/apd_proj/ppg_lib/epg_masterlib/logical/mstr_discrete/cap/chips/chips.prt!CAP!CAP_0805-10UF,16V,10%,X6S,C95333-007!CAP!!!F2465!!PVCCIN_CPU1_PWR_VR!!
S!@baseboard_fab2_lib.baseboard_fab2(sch_1):page208_i60@mstr_discrete.cap(chips)!CAP_0805-10UF,16V,10%,X6S,C953A!C9P2!//jf4cfls225.pdx.intel.com/apd_proj/ppg_lib/epg_masterlib/logical/mstr_discrete/cap/chips/chips.prt!CAP!CAP_0805-10UF,16V,10%,X6S,C95333-007!CAP!!!F2468!!PVCCIN_CPU1_PWR_VR!!
S!@baseboard_fab2_lib.baseboard_fab2(sch_1):page208_i54@mstr_discrete.cap(chips)!CAP_0805-10UF,16V,10%,X6S,C953A!C9P7!//jf4cfls225.pdx.intel.com/apd_proj/ppg_lib/epg_masterlib/logical/mstr_discrete/cap/chips/chips.prt!CAP!CAP_0805-10UF,16V,10%,X6S,C95333-007!CAP!!!F2466!!PVCCIN_CPU1_PWR_VR!!
S!@baseboard_fab2_lib.baseboard_fab2(sch_1):page208_i59@mstr_discrete.cap(chips)!CAP_0805-10UF,16V,10%,X6S,C953A!C9P1!//jf4cfls225.pdx.intel.com/apd_proj/ppg_lib/epg_masterlib/logical/mstr_discrete/cap/chips/chips.prt!CAP!CAP_0805-10UF,16V,10%,X6S,C95333-007!CAP!!!F2469!!PVCCIN_CPU1_PWR_VR!!
S!@baseboard_fab2_lib.baseboard_fab2(sch_1):page208_i53@mstr_discrete.cap(chips)!CAP_0805-10UF,16V,10%,X6S,C953A!C9P4!//jf4cfls225.pdx.intel.com/apd_proj/ppg_lib/epg_masterlib/logical/mstr_discrete/cap/chips/chips.prt!CAP!CAP_0805-10UF,16V,10%,X6S,C95333-007!CAP!!!F2467!!PVCCIN_CPU1_PWR_VR!!
S!@baseboard_fab2_lib.baseboard_fab2(sch_1):page208_i58@mstr_discrete.cap(chips)!CAP_0805-10UF,16V,10%,X6S,C953A!C9P24!//jf4cfls225.pdx.intel.com/apd_proj/ppg_lib/epg_masterlib/logical/mstr_discrete/cap/chips/chips.prt!CAP!CAP_0805-10UF,16V,10%,X6S,C95333-007!CAP!!!F2470!!PVCCIN_CPU1_PWR_VR!!
S!@baseboard_fab2_lib.baseboard_fab2(sch_1):page210_i38@mstr_discrete.cap(chips)!CAP_0805-10UF,16V,10%,X6S,C953A!C9N21!//jf4cfls225.pdx.intel.com/apd_proj/ppg_lib/epg_masterlib/logical/mstr_discrete/cap/chips/chips.prt!CAP!CAP_0805-10UF,16V,10%,X6S,C95333-007!CAP!!!F2471!!PVSA_CPU1_PWR_VR!!
S!@baseboard_fab2_lib.baseboard_fab2(sch_1):page210_i36@mstr_discrete.cap(chips)!CAP_0805-10UF,16V,10%,X6S,C953A!C9N19!//jf4cfls225.pdx.intel.com/apd_proj/ppg_lib/epg_masterlib/logical/mstr_discrete/cap/chips/chips.prt!CAP!CAP_0805-10UF,16V,10%,X6S,C95333-007!CAP!!!F2472!!PVSA_CPU1_PWR_VR!!
S!@baseboard_fab2_lib.baseboard_fab2(sch_1):page210_i35@mstr_discrete.cap(chips)!CAP_0805-10UF,16V,10%,X6S,C953A!C9N13!//jf4cfls225.pdx.intel.com/apd_proj/ppg_lib/epg_masterlib/logical/mstr_discrete/cap/chips/chips.prt!CAP!CAP_0805-10UF,16V,10%,X6S,C95333-007!CAP!!!F2473!!PVSA_CPU1_PWR_VR!!
S!@baseboard_fab2_lib.baseboard_fab2(sch_1):page204_i42@mstr_discrete.cap(chips)!CAP_0805-10UF,16V,10%,X6S,C953A!C6N11!//jf4cfls225.pdx.intel.com/apd_proj/ppg_lib/epg_masterlib/logical/mstr_discrete/cap/chips/chips.prt!CAP!CAP_0805-10UF,16V,10%,X6S,C95333-007!CAP!!!F2508!!PVCCIN_CPU0_PWR_VR!!
S!@baseboard_fab2_lib.baseboard_fab2(sch_1):page204_i37@mstr_discrete.cap(chips)!CAP_0805-10UF,16V,10%,X6S,C953A!C6N10!//jf4cfls225.pdx.intel.com/apd_proj/ppg_lib/epg_masterlib/logical/mstr_discrete/cap/chips/chips.prt!CAP!CAP_0805-10UF,16V,10%,X6S,C95333-007!CAP!!!F2509!!PVCCIN_CPU0_PWR_VR!!
S!@baseboard_fab2_lib.baseboard_fab2(sch_1):page195_i35@mstr_discrete.cap(chips)!CAP_0805-10UF,16V,10%,X6S,C953A!C1E15!//jf4cfls225.pdx.intel.com/apd_proj/ppg_lib/epg_masterlib/logical/mstr_discrete/cap/chips/chips.prt!CAP!CAP_0805-10UF,16V,10%,X6S,C95333-007!CAP!!!F2554!!HOT_SWAP!!
S!@baseboard_fab2_lib.baseboard_fab2(sch_1):page102_i10@mstr_discrete.cap(chips)!CAP_0805-10UF,16V,10%,X7R,G106A!C3D22!//jf4cfls225.pdx.intel.com/apd_proj/ppg_lib/epg_masterlib/logical/mstr_discrete/cap/chips/chips.prt!CAP!CAP_0805-10UF,16V,10%,X7R,G10601-001!CAP!!!F2444!!DB1200ZL!!
S!@baseboard_fab2_lib.baseboard_fab2(sch_1):page165_i67@mstr_discrete.cap(chips)!CAP_0805-10UF,16V,10%,X7R,G106A!C1U20!//jf4cfls225.pdx.intel.com/apd_proj/ppg_lib/epg_masterlib/logical/mstr_discrete/cap/chips/chips.prt!CAP!CAP_0805-10UF,16V,10%,X7R,G10601-001!CAP!!!F2445!!HEC_VOLT_MONITOR!!
S!@baseboard_fab2_lib.baseboard_fab2(sch_1):page197_i65@mstr_discrete.cap(chips)!CAP_0805-10UF,16V,10%,X7R,G106A!C6U10!//jf4cfls225.pdx.intel.com/apd_proj/ppg_lib/epg_masterlib/logical/mstr_discrete/cap/chips/chips.prt!CAP!CAP_0805-10UF,16V,10%,X7R,G10601-001!CAP!!!F2439!!PVDDQ_ABC_PWR_VR!!
S!@baseboard_fab2_lib.baseboard_fab2(sch_1):page197_i54@mstr_discrete.cap(chips)!CAP_0805-10UF,16V,10%,X7R,G106A!C6T2!//jf4cfls225.pdx.intel.com/apd_proj/ppg_lib/epg_masterlib/logical/mstr_discrete/cap/chips/chips.prt!CAP!CAP_0805-10UF,16V,10%,X7R,G10601-001!CAP!!!F2440!!PVDDQ_ABC_PWR_VR!!
S!@baseboard_fab2_lib.baseboard_fab2(sch_1):page197_i52@mstr_discrete.cap(chips)!CAP_0805-10UF,16V,10%,X7R,G106A!C6U18!//jf4cfls225.pdx.intel.com/apd_proj/ppg_lib/epg_masterlib/logical/mstr_discrete/cap/chips/chips.prt!CAP!CAP_0805-10UF,16V,10%,X7R,G10601-001!CAP!!!F2438!!PVDDQ_ABC_PWR_VR!!
S!@baseboard_fab2_lib.baseboard_fab2(sch_1):page197_i67@mstr_discrete.cap(chips)!CAP_0805-10UF,16V,10%,X7R,G106A!C4A17!//jf4cfls225.pdx.intel.com/apd_proj/ppg_lib/epg_masterlib/logical/mstr_discrete/cap/chips/chips.prt!CAP!CAP_0805-10UF,16V,10%,X7R,G10601-001!CAP!!!F2442!!PVDDQ_DEF_PWR_VR!!
S!@baseboard_fab2_lib.baseboard_fab2(sch_1):page197_i62@mstr_discrete.cap(chips)!CAP_0805-10UF,16V,10%,X7R,G106A!C4A4!//jf4cfls225.pdx.intel.com/apd_proj/ppg_lib/epg_masterlib/logical/mstr_discrete/cap/chips/chips.prt!CAP!CAP_0805-10UF,16V,10%,X7R,G10601-001!CAP!!!F2443!!PVDDQ_DEF_PWR_VR!!
S!@baseboard_fab2_lib.baseboard_fab2(sch_1):page197_i59@mstr_discrete.cap(chips)!CAP_0805-10UF,16V,10%,X7R,G106A!C4B11!//jf4cfls225.pdx.intel.com/apd_proj/ppg_lib/epg_masterlib/logical/mstr_discrete/cap/chips/chips.prt!CAP!CAP_0805-10UF,16V,10%,X7R,G10601-001!CAP!!!F2441!!PVDDQ_DEF_PWR_VR!!
S!@baseboard_fab2_lib.baseboard_fab2(sch_1):page197_i76@mstr_discrete.cap(chips)!CAP_0805-10UF,16V,10%,X7R,G106A!C9U8!//jf4cfls225.pdx.intel.com/apd_proj/ppg_lib/epg_masterlib/logical/mstr_discrete/cap/chips/chips.prt!CAP!CAP_0805-10UF,16V,10%,X7R,G10601-001!CAP!!!F2436!!PVDDQ_GHJ_PWR_VR!!
S!@baseboard_fab2_lib.baseboard_fab2(sch_1):page197_i73@mstr_discrete.cap(chips)!CAP_0805-10UF,16V,10%,X7R,G106A!C9U11!//jf4cfls225.pdx.intel.com/apd_proj/ppg_lib/epg_masterlib/logical/mstr_discrete/cap/chips/chips.prt!CAP!CAP_0805-10UF,16V,10%,X7R,G10601-001!CAP!!!F2435!!PVDDQ_GHJ_PWR_VR!!
S!@baseboard_fab2_lib.baseboard_fab2(sch_1):page197_i70@mstr_discrete.cap(chips)!CAP_0805-10UF,16V,10%,X7R,G106A!C9T8!//jf4cfls225.pdx.intel.com/apd_proj/ppg_lib/epg_masterlib/logical/mstr_discrete/cap/chips/chips.prt!CAP!CAP_0805-10UF,16V,10%,X7R,G10601-001!CAP!!!F2437!!PVDDQ_GHJ_PWR_VR!!
S!@baseboard_fab2_lib.baseboard_fab2(sch_1):page197_i85@mstr_discrete.cap(chips)!CAP_0805-10UF,16V,10%,X7R,G106A!C1A16!//jf4cfls225.pdx.intel.com/apd_proj/ppg_lib/epg_masterlib/logical/mstr_discrete/cap/chips/chips.prt!CAP!CAP_0805-10UF,16V,10%,X7R,G10601-001!CAP!!!F2447!!PVDDQ_KLM_PWR_VR!!
S!@baseboard_fab2_lib.baseboard_fab2(sch_1):page197_i82@mstr_discrete.cap(chips)!CAP_0805-10UF,16V,10%,X7R,G106A!C1B7!//jf4cfls225.pdx.intel.com/apd_proj/ppg_lib/epg_masterlib/logical/mstr_discrete/cap/chips/chips.prt!CAP!CAP_0805-10UF,16V,10%,X7R,G10601-001!CAP!!!F2446!!PVDDQ_KLM_PWR_VR!!
S!@baseboard_fab2_lib.baseboard_fab2(sch_1):page197_i79@mstr_discrete.cap(chips)!CAP_0805-10UF,16V,10%,X7R,G106A!C1A4!//jf4cfls225.pdx.intel.com/apd_proj/ppg_lib/epg_masterlib/logical/mstr_discrete/cap/chips/chips.prt!CAP!CAP_0805-10UF,16V,10%,X7R,G10601-001!CAP!!!F2448!!PVDDQ_KLM_PWR_VR!!
S!@baseboard_fab2_lib.baseboard_fab2(sch_1):page240_i158@mstr_discrete.cap(chips)!CAP_0805-22UF,6.3V,20%,X6S,C95A!C2T7!//jf4cfls225.pdx.intel.com/apd_proj/ppg_lib/epg_masterlib/logical/mstr_discrete/cap/chips/chips.prt!CAP!CAP_0805-22UF,6.3V,20%,X6S,C95333-008!CAP!!!F2430!!P3V3_STBY_VR!!
S!@baseboard_fab2_lib.baseboard_fab2(sch_1):page240_i160@mstr_discrete.cap(chips)!CAP_0805-22UF,6.3V,20%,X6S,C95A!C2T6!//jf4cfls225.pdx.intel.com/apd_proj/ppg_lib/epg_masterlib/logical/mstr_discrete/cap/chips/chips.prt!CAP!CAP_0805-22UF,6.3V,20%,X6S,C95333-008!CAP!!!F2431!!P3V3_STBY_VR!!
S!@baseboard_fab2_lib.baseboard_fab2(sch_1):page240_i174@mstr_discrete.cap(chips)!CAP_0805-22UF,6.3V,20%,X6S,C95A!C2T9!//jf4cfls225.pdx.intel.com/apd_proj/ppg_lib/epg_masterlib/logical/mstr_discrete/cap/chips/chips.prt!CAP!CAP_0805-22UF,6.3V,20%,X6S,C95333-008!CAP!!!F2429!!P3V3_STBY_VR!!
S!@baseboard_fab2_lib.baseboard_fab2(sch_1):page241_i3@mstr_discrete.cap(chips)!CAP_0805-22UF,6.3V,20%,X6S,C95A!C8E7!//jf4cfls225.pdx.intel.com/apd_proj/ppg_lib/epg_masterlib/logical/mstr_discrete/cap/chips/chips.prt!CAP!CAP_0805-22UF,6.3V,20%,X6S,C95333-008!CAP!!!F2427!!P5V_STBY_VR!!
S!@baseboard_fab2_lib.baseboard_fab2(sch_1):page241_i2@mstr_discrete.cap(chips)!CAP_0805-22UF,6.3V,20%,X6S,C95A!C8E9!//jf4cfls225.pdx.intel.com/apd_proj/ppg_lib/epg_masterlib/logical/mstr_discrete/cap/chips/chips.prt!CAP!CAP_0805-22UF,6.3V,20%,X6S,C95333-008!CAP!!!F2426!!P5V_STBY_VR!!
S!@baseboard_fab2_lib.baseboard_fab2(sch_1):page237_i13@mstr_discrete.cap(chips)!CAP_0805-22UF,6.3V,20%,X6S,C95A!C8A14!//jf4cfls225.pdx.intel.com/apd_proj/ppg_lib/epg_masterlib/logical/mstr_discrete/cap/chips/chips.prt!CAP!CAP_0805-22UF,6.3V,20%,X6S,C95333-008!CAP!!!F2428!!P1V8_PCH_STBY_VR!!
S!@baseboard_fab2_lib.baseboard_fab2(sch_1):page237_i12@mstr_discrete.cap(chips)!CAP_0805-22UF,6.3V,20%,X6S,C95A!C2L45!//jf4cfls225.pdx.intel.com/apd_proj/ppg_lib/epg_masterlib/logical/mstr_discrete/cap/chips/chips.prt!CAP!CAP_0805-22UF,6.3V,20%,X6S,C95333-008!CAP!!!F2432!!P1V8_PCH_STBY_VR!!
S!@baseboard_fab2_lib.baseboard_fab2(sch_1):page149_i74@mstr_discrete.cap(chips)!CAP_0805-22UF,6.3V,20%,X6S,C95A!C1T13!//jf4cfls225.pdx.intel.com/apd_proj/ppg_lib/epg_masterlib/logical/mstr_discrete/cap/chips/chips.prt!CAP!CAP_0805-22UF,6.3V,20%,X6S,C95333-008!CAP!!!F2433!!BMC!!
S!@baseboard_fab2_lib.baseboard_fab2(sch_1):page149_i75@mstr_discrete.cap(chips)!CAP_0805-22UF,6.3V,20%,X6S,C95A!C1T9!//jf4cfls225.pdx.intel.com/apd_proj/ppg_lib/epg_masterlib/logical/mstr_discrete/cap/chips/chips.prt!CAP!CAP_0805-22UF,6.3V,20%,X6S,C95333-008!CAP!!!F2434!!BMC!!
S!@baseboard_fab2_lib.baseboard_fab2(sch_1):page76_i52@mstr_discrete.cap(chips)!CAP_0805-47UF,4V,20%,X6S,C9533A!C7P3!//jf4cfls225.pdx.intel.com/apd_proj/ppg_lib/epg_masterlib/logical/mstr_discrete/cap/chips/chips.prt!CAP!CAP_0805-47UF,4V,20%,X6S,C95333-006!CAP!!!F2363!!PVCCIN_CPU1_DECAP_VR!!
S!@baseboard_fab2_lib.baseboard_fab2(sch_1):page76_i51@mstr_discrete.cap(chips)!CAP_0805-47UF,4V,20%,X6S,C9533A!C7P18!//jf4cfls225.pdx.intel.com/apd_proj/ppg_lib/epg_masterlib/logical/mstr_discrete/cap/chips/chips.prt!CAP!CAP_0805-47UF,4V,20%,X6S,C95333-006!CAP!!!F2350!!PVCCIN_CPU1_DECAP_VR!!
S!@baseboard_fab2_lib.baseboard_fab2(sch_1):page76_i29@mstr_discrete.cap(chips)!CAP_0805-47UF,4V,20%,X6S,C9533A!C7P17!//jf4cfls225.pdx.intel.com/apd_proj/ppg_lib/epg_masterlib/logical/mstr_discrete/cap/chips/chips.prt!CAP!CAP_0805-47UF,4V,20%,X6S,C95333-006!CAP!!!F2351!!PVCCIN_CPU1_DECAP_VR!!
S!@baseboard_fab2_lib.baseboard_fab2(sch_1):page42_i184@mstr_discrete.cap(chips)!CAP_0805-47UF,4V,20%,X6S,C9533A!C5P21!//jf4cfls225.pdx.intel.com/apd_proj/ppg_lib/epg_masterlib/logical/mstr_discrete/cap/chips/chips.prt!CAP!CAP_0805-47UF,4V,20%,X6S,C95333-006!CAP!!!F2395!!PVCCIN_CPU0_DECAP_VR!!
S!@baseboard_fab2_lib.baseboard_fab2(sch_1):page42_i61@mstr_discrete.cap(chips)!CAP_0805-47UF,4V,20%,X6S,C9533A!C5P44!//jf4cfls225.pdx.intel.com/apd_proj/ppg_lib/epg_masterlib/logical/mstr_discrete/cap/chips/chips.prt!CAP!CAP_0805-47UF,4V,20%,X6S,C95333-006!CAP!!!F2374!!PVCCIN_CPU0_DECAP_VR!!
S!@baseboard_fab2_lib.baseboard_fab2(sch_1):page42_i60@mstr_discrete.cap(chips)!CAP_0805-47UF,4V,20%,X6S,C9533A!C5P43!//jf4cfls225.pdx.intel.com/apd_proj/ppg_lib/epg_masterlib/logical/mstr_discrete/cap/chips/chips.prt!CAP!CAP_0805-47UF,4V,20%,X6S,C95333-006!CAP!!!F2375!!PVCCIN_CPU0_DECAP_VR!!
S!@baseboard_fab2_lib.baseboard_fab2(sch_1):page42_i59@mstr_discrete.cap(chips)!CAP_0805-47UF,4V,20%,X6S,C9533A!C5P42!//jf4cfls225.pdx.intel.com/apd_proj/ppg_lib/epg_masterlib/logical/mstr_discrete/cap/chips/chips.prt!CAP!CAP_0805-47UF,4V,20%,X6S,C95333-006!CAP!!!F2376!!PVCCIN_CPU0_DECAP_VR!!
S!@baseboard_fab2_lib.baseboard_fab2(sch_1):page42_i57@mstr_discrete.cap(chips)!CAP_0805-47UF,4V,20%,X6S,C9533A!C5P40!//jf4cfls225.pdx.intel.com/apd_proj/ppg_lib/epg_masterlib/logical/mstr_discrete/cap/chips/chips.prt!CAP!CAP_0805-47UF,4V,20%,X6S,C95333-006!CAP!!!F2378!!PVCCIN_CPU0_DECAP_VR!!
S!@baseboard_fab2_lib.baseboard_fab2(sch_1):page42_i40@mstr_discrete.cap(chips)!CAP_0805-47UF,4V,20%,X6S,C9533A!C5P41!//jf4cfls225.pdx.intel.com/apd_proj/ppg_lib/epg_masterlib/logical/mstr_discrete/cap/chips/chips.prt!CAP!CAP_0805-47UF,4V,20%,X6S,C95333-006!CAP!!!F2377!!PVCCIN_CPU0_DECAP_VR!!
S!@baseboard_fab2_lib.baseboard_fab2(sch_1):page42_i44@mstr_discrete.cap(chips)!CAP_0805-47UF,4V,20%,X6S,C9533A!C5P27!//jf4cfls225.pdx.intel.com/apd_proj/ppg_lib/epg_masterlib/logical/mstr_discrete/cap/chips/chips.prt!CAP!CAP_0805-47UF,4V,20%,X6S,C95333-006!CAP!!!F2389!!PVCCIN_CPU0_DECAP_VR!!
S!@baseboard_fab2_lib.baseboard_fab2(sch_1):page42_i56@mstr_discrete.cap(chips)!CAP_0805-47UF,4V,20%,X6S,C9533A!C5P26!//jf4cfls225.pdx.intel.com/apd_proj/ppg_lib/epg_masterlib/logical/mstr_discrete/cap/chips/chips.prt!CAP!CAP_0805-47UF,4V,20%,X6S,C95333-006!CAP!!!F2390!!PVCCIN_CPU0_DECAP_VR!!
S!@baseboard_fab2_lib.baseboard_fab2(sch_1):page42_i38@mstr_discrete.cap(chips)!CAP_0805-47UF,4V,20%,X6S,C9533A!C5P6!//jf4cfls225.pdx.intel.com/apd_proj/ppg_lib/epg_masterlib/logical/mstr_discrete/cap/chips/chips.prt!CAP!CAP_0805-47UF,4V,20%,X6S,C95333-006!CAP!!!F2407!!PVCCIN_CPU0_DECAP_VR!!
S!@baseboard_fab2_lib.baseboard_fab2(sch_1):page42_i42@mstr_discrete.cap(chips)!CAP_0805-47UF,4V,20%,X6S,C9533A!C5P5!//jf4cfls225.pdx.intel.com/apd_proj/ppg_lib/epg_masterlib/logical/mstr_discrete/cap/chips/chips.prt!CAP!CAP_0805-47UF,4V,20%,X6S,C95333-006!CAP!!!F2408!!PVCCIN_CPU0_DECAP_VR!!
S!@baseboard_fab2_lib.baseboard_fab2(sch_1):page42_i27@mstr_discrete.cap(chips)!CAP_0805-47UF,4V,20%,X6S,C9533A!C5P4!//jf4cfls225.pdx.intel.com/apd_proj/ppg_lib/epg_masterlib/logical/mstr_discrete/cap/chips/chips.prt!CAP!CAP_0805-47UF,4V,20%,X6S,C95333-006!CAP!!!F2409!!PVCCIN_CPU0_DECAP_VR!!
S!@baseboard_fab2_lib.baseboard_fab2(sch_1):page42_i190@mstr_discrete.cap(chips)!CAP_0805-47UF,4V,20%,X6S,C9533A!C5P17!//jf4cfls225.pdx.intel.com/apd_proj/ppg_lib/epg_masterlib/logical/mstr_discrete/cap/chips/chips.prt!CAP!CAP_0805-47UF,4V,20%,X6S,C95333-006!CAP!!!F2399!!PVCCIN_CPU0_DECAP_VR!!
S!@baseboard_fab2_lib.baseboard_fab2(sch_1):page42_i189@mstr_discrete.cap(chips)!CAP_0805-47UF,4V,20%,X6S,C9533A!C5P3!//jf4cfls225.pdx.intel.com/apd_proj/ppg_lib/epg_masterlib/logical/mstr_discrete/cap/chips/chips.prt!CAP!CAP_0805-47UF,4V,20%,X6S,C95333-006!CAP!!!F2410!!PVCCIN_CPU0_DECAP_VR!!
S!@baseboard_fab2_lib.baseboard_fab2(sch_1):page42_i188@mstr_discrete.cap(chips)!CAP_0805-47UF,4V,20%,X6S,C9533A!C5P16!//jf4cfls225.pdx.intel.com/apd_proj/ppg_lib/epg_masterlib/logical/mstr_discrete/cap/chips/chips.prt!CAP!CAP_0805-47UF,4V,20%,X6S,C95333-006!CAP!!!F2400!!PVCCIN_CPU0_DECAP_VR!!
S!@baseboard_fab2_lib.baseboard_fab2(sch_1):page42_i187@mstr_discrete.cap(chips)!CAP_0805-47UF,4V,20%,X6S,C9533A!C5P15!//jf4cfls225.pdx.intel.com/apd_proj/ppg_lib/epg_masterlib/logical/mstr_discrete/cap/chips/chips.prt!CAP!CAP_0805-47UF,4V,20%,X6S,C95333-006!CAP!!!F2401!!PVCCIN_CPU0_DECAP_VR!!
S!@baseboard_fab2_lib.baseboard_fab2(sch_1):page42_i14@mstr_discrete.cap(chips)!CAP_0805-47UF,4V,20%,X6S,C9533A!C4P4!//jf4cfls225.pdx.intel.com/apd_proj/ppg_lib/epg_masterlib/logical/mstr_discrete/cap/chips/chips.prt!CAP!CAP_0805-47UF,4V,20%,X6S,C95333-006!CAP!!!F2415!!PVCCIN_CPU0_DECAP_VR!!
S!@baseboard_fab2_lib.baseboard_fab2(sch_1):page42_i2@mstr_discrete.cap(chips)!CAP_0805-47UF,4V,20%,X6S,C9533A!C5P18!//jf4cfls225.pdx.intel.com/apd_proj/ppg_lib/epg_masterlib/logical/mstr_discrete/cap/chips/chips.prt!CAP!CAP_0805-47UF,4V,20%,X6S,C95333-006!CAP!!!F2398!!PVCCIN_CPU0_DECAP_VR!!
S!@baseboard_fab2_lib.baseboard_fab2(sch_1):page42_i55@mstr_discrete.cap(chips)!CAP_0805-47UF,4V,20%,X6S,C9533A!C5P22!//jf4cfls225.pdx.intel.com/apd_proj/ppg_lib/epg_masterlib/logical/mstr_discrete/cap/chips/chips.prt!CAP!CAP_0805-47UF,4V,20%,X6S,C95333-006!CAP!!!F2394!!PVCCIN_CPU0_DECAP_VR!!
S!@baseboard_fab2_lib.baseboard_fab2(sch_1):page42_i28@mstr_discrete.cap(chips)!CAP_0805-47UF,4V,20%,X6S,C9533A!C5P23!//jf4cfls225.pdx.intel.com/apd_proj/ppg_lib/epg_masterlib/logical/mstr_discrete/cap/chips/chips.prt!CAP!CAP_0805-47UF,4V,20%,X6S,C95333-006!CAP!!!F2393!!PVCCIN_CPU0_DECAP_VR!!
S!@baseboard_fab2_lib.baseboard_fab2(sch_1):page42_i33@mstr_discrete.cap(chips)!CAP_0805-47UF,4V,20%,X6S,C9533A!C5P24!//jf4cfls225.pdx.intel.com/apd_proj/ppg_lib/epg_masterlib/logical/mstr_discrete/cap/chips/chips.prt!CAP!CAP_0805-47UF,4V,20%,X6S,C95333-006!CAP!!!F2392!!PVCCIN_CPU0_DECAP_VR!!
S!@baseboard_fab2_lib.baseboard_fab2(sch_1):page42_i37@mstr_discrete.cap(chips)!CAP_0805-47UF,4V,20%,X6S,C9533A!C5P25!//jf4cfls225.pdx.intel.com/apd_proj/ppg_lib/epg_masterlib/logical/mstr_discrete/cap/chips/chips.prt!CAP!CAP_0805-47UF,4V,20%,X6S,C95333-006!CAP!!!F2391!!PVCCIN_CPU0_DECAP_VR!!
S!@baseboard_fab2_lib.baseboard_fab2(sch_1):page42_i13@mstr_discrete.cap(chips)!CAP_0805-47UF,4V,20%,X6S,C9533A!C5P19!//jf4cfls225.pdx.intel.com/apd_proj/ppg_lib/epg_masterlib/logical/mstr_discrete/cap/chips/chips.prt!CAP!CAP_0805-47UF,4V,20%,X6S,C95333-006!CAP!!!F2397!!PVCCIN_CPU0_DECAP_VR!!
S!@baseboard_fab2_lib.baseboard_fab2(sch_1):page42_i9@mstr_discrete.cap(chips)!CAP_0805-47UF,4V,20%,X6S,C9533A!C4P7!//jf4cfls225.pdx.intel.com/apd_proj/ppg_lib/epg_masterlib/logical/mstr_discrete/cap/chips/chips.prt!CAP!CAP_0805-47UF,4V,20%,X6S,C95333-006!CAP!!!F2413!!PVCCIN_CPU0_DECAP_VR!!
S!@baseboard_fab2_lib.baseboard_fab2(sch_1):page42_i8@mstr_discrete.cap(chips)!CAP_0805-47UF,4V,20%,X6S,C9533A!C4P3!//jf4cfls225.pdx.intel.com/apd_proj/ppg_lib/epg_masterlib/logical/mstr_discrete/cap/chips/chips.prt!CAP!CAP_0805-47UF,4V,20%,X6S,C95333-006!CAP!!!F2416!!PVCCIN_CPU0_DECAP_VR!!
S!@baseboard_fab2_lib.baseboard_fab2(sch_1):page42_i6@mstr_discrete.cap(chips)!CAP_0805-47UF,4V,20%,X6S,C9533A!C5P10!//jf4cfls225.pdx.intel.com/apd_proj/ppg_lib/epg_masterlib/logical/mstr_discrete/cap/chips/chips.prt!CAP!CAP_0805-47UF,4V,20%,X6S,C95333-006!CAP!!!F2406!!PVCCIN_CPU0_DECAP_VR!!
S!@baseboard_fab2_lib.baseboard_fab2(sch_1):page42_i4@mstr_discrete.cap(chips)!CAP_0805-47UF,4V,20%,X6S,C9533A!C5P11!//jf4cfls225.pdx.intel.com/apd_proj/ppg_lib/epg_masterlib/logical/mstr_discrete/cap/chips/chips.prt!CAP!CAP_0805-47UF,4V,20%,X6S,C95333-006!CAP!!!F2405!!PVCCIN_CPU0_DECAP_VR!!
S!@baseboard_fab2_lib.baseboard_fab2(sch_1):page42_i3@mstr_discrete.cap(chips)!CAP_0805-47UF,4V,20%,X6S,C9533A!C5P28!//jf4cfls225.pdx.intel.com/apd_proj/ppg_lib/epg_masterlib/logical/mstr_discrete/cap/chips/chips.prt!CAP!CAP_0805-47UF,4V,20%,X6S,C95333-006!CAP!!!F2388!!PVCCIN_CPU0_DECAP_VR!!
S!@baseboard_fab2_lib.baseboard_fab2(sch_1):page76_i139@mstr_discrete.cap(chips)!CAP_0805-47UF,4V,20%,X6S,C9533A!C8P11!//jf4cfls225.pdx.intel.com/apd_proj/ppg_lib/epg_masterlib/logical/mstr_discrete/cap/chips/chips.prt!CAP!CAP_0805-47UF,4V,20%,X6S,C95333-006!CAP!!!F2338!!PVCCIN_CPU1_DECAP_VR!!
S!@baseboard_fab2_lib.baseboard_fab2(sch_1):page76_i214@mstr_discrete.cap(chips)!CAP_0805-47UF,4V,20%,X6S,C9533A!C8P9!//jf4cfls225.pdx.intel.com/apd_proj/ppg_lib/epg_masterlib/logical/mstr_discrete/cap/chips/chips.prt!CAP!CAP_0805-47UF,4V,20%,X6S,C95333-006!CAP!!!F2340!!PVCCIN_CPU1_DECAP_VR!!
S!@baseboard_fab2_lib.baseboard_fab2(sch_1):page76_i125@mstr_discrete.cap(chips)!CAP_0805-47UF,4V,20%,X6S,C9533A!C8P29!//jf4cfls225.pdx.intel.com/apd_proj/ppg_lib/epg_masterlib/logical/mstr_discrete/cap/chips/chips.prt!CAP!CAP_0805-47UF,4V,20%,X6S,C95333-006!CAP!!!F2320!!PVCCIN_CPU1_DECAP_VR!!
S!@baseboard_fab2_lib.baseboard_fab2(sch_1):page76_i137@mstr_discrete.cap(chips)!CAP_0805-47UF,4V,20%,X6S,C9533A!C8P28!//jf4cfls225.pdx.intel.com/apd_proj/ppg_lib/epg_masterlib/logical/mstr_discrete/cap/chips/chips.prt!CAP!CAP_0805-47UF,4V,20%,X6S,C95333-006!CAP!!!F2321!!PVCCIN_CPU1_DECAP_VR!!
S!@baseboard_fab2_lib.baseboard_fab2(sch_1):page76_i141@mstr_discrete.cap(chips)!CAP_0805-47UF,4V,20%,X6S,C9533A!C8P27!//jf4cfls225.pdx.intel.com/apd_proj/ppg_lib/epg_masterlib/logical/mstr_discrete/cap/chips/chips.prt!CAP!CAP_0805-47UF,4V,20%,X6S,C95333-006!CAP!!!F2322!!PVCCIN_CPU1_DECAP_VR!!
S!@baseboard_fab2_lib.baseboard_fab2(sch_1):page76_i118@mstr_discrete.cap(chips)!CAP_0805-47UF,4V,20%,X6S,C9533A!C8P26!//jf4cfls225.pdx.intel.com/apd_proj/ppg_lib/epg_masterlib/logical/mstr_discrete/cap/chips/chips.prt!CAP!CAP_0805-47UF,4V,20%,X6S,C95333-006!CAP!!!F2323!!PVCCIN_CPU1_DECAP_VR!!
S!@baseboard_fab2_lib.baseboard_fab2(sch_1):page76_i132@mstr_discrete.cap(chips)!CAP_0805-47UF,4V,20%,X6S,C9533A!C8P13!//jf4cfls225.pdx.intel.com/apd_proj/ppg_lib/epg_masterlib/logical/mstr_discrete/cap/chips/chips.prt!CAP!CAP_0805-47UF,4V,20%,X6S,C95333-006!CAP!!!F2336!!PVCCIN_CPU1_DECAP_VR!!
S!@baseboard_fab2_lib.baseboard_fab2(sch_1):page76_i136@mstr_discrete.cap(chips)!CAP_0805-47UF,4V,20%,X6S,C9533A!C8P25!//jf4cfls225.pdx.intel.com/apd_proj/ppg_lib/epg_masterlib/logical/mstr_discrete/cap/chips/chips.prt!CAP!CAP_0805-47UF,4V,20%,X6S,C95333-006!CAP!!!F2324!!PVCCIN_CPU1_DECAP_VR!!
S!@baseboard_fab2_lib.baseboard_fab2(sch_1):page76_i212@mstr_discrete.cap(chips)!CAP_0805-47UF,4V,20%,X6S,C9533A!C8P15!//jf4cfls225.pdx.intel.com/apd_proj/ppg_lib/epg_masterlib/logical/mstr_discrete/cap/chips/chips.prt!CAP!CAP_0805-47UF,4V,20%,X6S,C95333-006!CAP!!!F2334!!PVCCIN_CPU1_DECAP_VR!!
S!@baseboard_fab2_lib.baseboard_fab2(sch_1):page76_i131@mstr_discrete.cap(chips)!CAP_0805-47UF,4V,20%,X6S,C9533A!C8P33!//jf4cfls225.pdx.intel.com/apd_proj/ppg_lib/epg_masterlib/logical/mstr_discrete/cap/chips/chips.prt!CAP!CAP_0805-47UF,4V,20%,X6S,C95333-006!CAP!!!F2318!!PVCCIN_CPU1_DECAP_VR!!
S!@baseboard_fab2_lib.baseboard_fab2(sch_1):page76_i135@mstr_discrete.cap(chips)!CAP_0805-47UF,4V,20%,X6S,C9533A!C8P21!//jf4cfls225.pdx.intel.com/apd_proj/ppg_lib/epg_masterlib/logical/mstr_discrete/cap/chips/chips.prt!CAP!CAP_0805-47UF,4V,20%,X6S,C95333-006!CAP!!!F2328!!PVCCIN_CPU1_DECAP_VR!!
S!@baseboard_fab2_lib.baseboard_fab2(sch_1):page76_i213@mstr_discrete.cap(chips)!CAP_0805-47UF,4V,20%,X6S,C9533A!C8P8!//jf4cfls225.pdx.intel.com/apd_proj/ppg_lib/epg_masterlib/logical/mstr_discrete/cap/chips/chips.prt!CAP!CAP_0805-47UF,4V,20%,X6S,C95333-006!CAP!!!F2341!!PVCCIN_CPU1_DECAP_VR!!
S!@baseboard_fab2_lib.baseboard_fab2(sch_1):page76_i129@mstr_discrete.cap(chips)!CAP_0805-47UF,4V,20%,X6S,C9533A!C8P16!//jf4cfls225.pdx.intel.com/apd_proj/ppg_lib/epg_masterlib/logical/mstr_discrete/cap/chips/chips.prt!CAP!CAP_0805-47UF,4V,20%,X6S,C95333-006!CAP!!!F2333!!PVCCIN_CPU1_DECAP_VR!!
S!@baseboard_fab2_lib.baseboard_fab2(sch_1):page76_i133@mstr_discrete.cap(chips)!CAP_0805-47UF,4V,20%,X6S,C9533A!C8P17!//jf4cfls225.pdx.intel.com/apd_proj/ppg_lib/epg_masterlib/logical/mstr_discrete/cap/chips/chips.prt!CAP!CAP_0805-47UF,4V,20%,X6S,C95333-006!CAP!!!F2332!!PVCCIN_CPU1_DECAP_VR!!
S!@baseboard_fab2_lib.baseboard_fab2(sch_1):page76_i92@mstr_discrete.cap(chips)!CAP_0805-47UF,4V,20%,X6S,C9533A!C8P18!//jf4cfls225.pdx.intel.com/apd_proj/ppg_lib/epg_masterlib/logical/mstr_discrete/cap/chips/chips.prt!CAP!CAP_0805-47UF,4V,20%,X6S,C95333-006!CAP!!!F2331!!PVCCIN_CPU1_DECAP_VR!!
S!@baseboard_fab2_lib.baseboard_fab2(sch_1):page76_i103@mstr_discrete.cap(chips)!CAP_0805-47UF,4V,20%,X6S,C9533A!C8P19!//jf4cfls225.pdx.intel.com/apd_proj/ppg_lib/epg_masterlib/logical/mstr_discrete/cap/chips/chips.prt!CAP!CAP_0805-47UF,4V,20%,X6S,C95333-006!CAP!!!F2330!!PVCCIN_CPU1_DECAP_VR!!
S!@baseboard_fab2_lib.baseboard_fab2(sch_1):page76_i107@mstr_discrete.cap(chips)!CAP_0805-47UF,4V,20%,X6S,C9533A!C8P12!//jf4cfls225.pdx.intel.com/apd_proj/ppg_lib/epg_masterlib/logical/mstr_discrete/cap/chips/chips.prt!CAP!CAP_0805-47UF,4V,20%,X6S,C95333-006!CAP!!!F2337!!PVCCIN_CPU1_DECAP_VR!!
S!@baseboard_fab2_lib.baseboard_fab2(sch_1):page76_i89@mstr_discrete.cap(chips)!CAP_0805-47UF,4V,20%,X6S,C9533A!C8P20!//jf4cfls225.pdx.intel.com/apd_proj/ppg_lib/epg_masterlib/logical/mstr_discrete/cap/chips/chips.prt!CAP!CAP_0805-47UF,4V,20%,X6S,C95333-006!CAP!!!F2329!!PVCCIN_CPU1_DECAP_VR!!
S!@baseboard_fab2_lib.baseboard_fab2(sch_1):page76_i101@mstr_discrete.cap(chips)!CAP_0805-47UF,4V,20%,X6S,C9533A!C8P3!//jf4cfls225.pdx.intel.com/apd_proj/ppg_lib/epg_masterlib/logical/mstr_discrete/cap/chips/chips.prt!CAP!CAP_0805-47UF,4V,20%,X6S,C95333-006!CAP!!!F2343!!PVCCIN_CPU1_DECAP_VR!!
S!@baseboard_fab2_lib.baseboard_fab2(sch_1):page76_i106@mstr_discrete.cap(chips)!CAP_0805-47UF,4V,20%,X6S,C9533A!C8P34!//jf4cfls225.pdx.intel.com/apd_proj/ppg_lib/epg_masterlib/logical/mstr_discrete/cap/chips/chips.prt!CAP!CAP_0805-47UF,4V,20%,X6S,C95333-006!CAP!!!F2317!!PVCCIN_CPU1_DECAP_VR!!
S!@baseboard_fab2_lib.baseboard_fab2(sch_1):page76_i88@mstr_discrete.cap(chips)!CAP_0805-47UF,4V,20%,X6S,C9533A!C8P4!//jf4cfls225.pdx.intel.com/apd_proj/ppg_lib/epg_masterlib/logical/mstr_discrete/cap/chips/chips.prt!CAP!CAP_0805-47UF,4V,20%,X6S,C95333-006!CAP!!!F2342!!PVCCIN_CPU1_DECAP_VR!!
S!@baseboard_fab2_lib.baseboard_fab2(sch_1):page76_i100@mstr_discrete.cap(chips)!CAP_0805-47UF,4V,20%,X6S,C9533A!C7P2!//jf4cfls225.pdx.intel.com/apd_proj/ppg_lib/epg_masterlib/logical/mstr_discrete/cap/chips/chips.prt!CAP!CAP_0805-47UF,4V,20%,X6S,C95333-006!CAP!!!F2364!!PVCCIN_CPU1_DECAP_VR!!
S!@baseboard_fab2_lib.baseboard_fab2(sch_1):page76_i105@mstr_discrete.cap(chips)!CAP_0805-47UF,4V,20%,X6S,C9533A!C7P1!//jf4cfls225.pdx.intel.com/apd_proj/ppg_lib/epg_masterlib/logical/mstr_discrete/cap/chips/chips.prt!CAP!CAP_0805-47UF,4V,20%,X6S,C95333-006!CAP!!!F2365!!PVCCIN_CPU1_DECAP_VR!!
S!@baseboard_fab2_lib.baseboard_fab2(sch_1):page76_i217@mstr_discrete.cap(chips)!CAP_0805-47UF,4V,20%,X6S,C9533A!C8P24!//jf4cfls225.pdx.intel.com/apd_proj/ppg_lib/epg_masterlib/logical/mstr_discrete/cap/chips/chips.prt!CAP!CAP_0805-47UF,4V,20%,X6S,C95333-006!CAP!!!F2325!!PVCCIN_CPU1_DECAP_VR!!
S!@baseboard_fab2_lib.baseboard_fab2(sch_1):page76_i215@mstr_discrete.cap(chips)!CAP_0805-47UF,4V,20%,X6S,C9533A!C7P19!//jf4cfls225.pdx.intel.com/apd_proj/ppg_lib/epg_masterlib/logical/mstr_discrete/cap/chips/chips.prt!CAP!CAP_0805-47UF,4V,20%,X6S,C95333-006!CAP!!!F2349!!PVCCIN_CPU1_DECAP_VR!!
S!@baseboard_fab2_lib.baseboard_fab2(sch_1):page76_i218@mstr_discrete.cap(chips)!CAP_0805-47UF,4V,20%,X6S,C9533A!C7P20!//jf4cfls225.pdx.intel.com/apd_proj/ppg_lib/epg_masterlib/logical/mstr_discrete/cap/chips/chips.prt!CAP!CAP_0805-47UF,4V,20%,X6S,C95333-006!CAP!!!F2348!!PVCCIN_CPU1_DECAP_VR!!
S!@baseboard_fab2_lib.baseboard_fab2(sch_1):page76_i216@mstr_discrete.cap(chips)!CAP_0805-47UF,4V,20%,X6S,C9533A!C8P32!//jf4cfls225.pdx.intel.com/apd_proj/ppg_lib/epg_masterlib/logical/mstr_discrete/cap/chips/chips.prt!CAP!CAP_0805-47UF,4V,20%,X6S,C95333-006!CAP!!!F2319!!PVCCIN_CPU1_DECAP_VR!!
S!@baseboard_fab2_lib.baseboard_fab2(sch_1):page76_i211@mstr_discrete.cap(chips)!CAP_0805-47UF,4V,20%,X6S,C9533A!C8P14!//jf4cfls225.pdx.intel.com/apd_proj/ppg_lib/epg_masterlib/logical/mstr_discrete/cap/chips/chips.prt!CAP!CAP_0805-47UF,4V,20%,X6S,C95333-006!CAP!!!F2335!!PVCCIN_CPU1_DECAP_VR!!
S!@baseboard_fab2_lib.baseboard_fab2(sch_1):page76_i49@mstr_discrete.cap(chips)!CAP_0805-47UF,4V,20%,X6S,C9533A!C7P14!//jf4cfls225.pdx.intel.com/apd_proj/ppg_lib/epg_masterlib/logical/mstr_discrete/cap/chips/chips.prt!CAP!CAP_0805-47UF,4V,20%,X6S,C95333-006!CAP!!!F2353!!PVCCIN_CPU1_DECAP_VR!!
S!@baseboard_fab2_lib.baseboard_fab2(sch_1):page76_i48@mstr_discrete.cap(chips)!CAP_0805-47UF,4V,20%,X6S,C9533A!C8P23!//jf4cfls225.pdx.intel.com/apd_proj/ppg_lib/epg_masterlib/logical/mstr_discrete/cap/chips/chips.prt!CAP!CAP_0805-47UF,4V,20%,X6S,C95333-006!CAP!!!F2326!!PVCCIN_CPU1_DECAP_VR!!
S!@baseboard_fab2_lib.baseboard_fab2(sch_1):page76_i45@mstr_discrete.cap(chips)!CAP_0805-47UF,4V,20%,X6S,C9533A!C7P15!//jf4cfls225.pdx.intel.com/apd_proj/ppg_lib/epg_masterlib/logical/mstr_discrete/cap/chips/chips.prt!CAP!CAP_0805-47UF,4V,20%,X6S,C95333-006!CAP!!!F2352!!PVCCIN_CPU1_DECAP_VR!!
S!@baseboard_fab2_lib.baseboard_fab2(sch_1):page76_i28@mstr_discrete.cap(chips)!CAP_0805-47UF,4V,20%,X6S,C9533A!C8P22!//jf4cfls225.pdx.intel.com/apd_proj/ppg_lib/epg_masterlib/logical/mstr_discrete/cap/chips/chips.prt!CAP!CAP_0805-47UF,4V,20%,X6S,C95333-006!CAP!!!F2327!!PVCCIN_CPU1_DECAP_VR!!
S!@baseboard_fab2_lib.baseboard_fab2(sch_1):page76_i27@mstr_discrete.cap(chips)!CAP_0805-47UF,4V,20%,X6S,C9533A!C7P7!//jf4cfls225.pdx.intel.com/apd_proj/ppg_lib/epg_masterlib/logical/mstr_discrete/cap/chips/chips.prt!CAP!CAP_0805-47UF,4V,20%,X6S,C95333-006!CAP!!!F2359!!PVCCIN_CPU1_DECAP_VR!!
S!@baseboard_fab2_lib.baseboard_fab2(sch_1):page76_i26@mstr_discrete.cap(chips)!CAP_0805-47UF,4V,20%,X6S,C9533A!C7P10!//jf4cfls225.pdx.intel.com/apd_proj/ppg_lib/epg_masterlib/logical/mstr_discrete/cap/chips/chips.prt!CAP!CAP_0805-47UF,4V,20%,X6S,C95333-006!CAP!!!F2356!!PVCCIN_CPU1_DECAP_VR!!
S!@baseboard_fab2_lib.baseboard_fab2(sch_1):page76_i25@mstr_discrete.cap(chips)!CAP_0805-47UF,4V,20%,X6S,C9533A!C7P13!//jf4cfls225.pdx.intel.com/apd_proj/ppg_lib/epg_masterlib/logical/mstr_discrete/cap/chips/chips.prt!CAP!CAP_0805-47UF,4V,20%,X6S,C95333-006!CAP!!!F2354!!PVCCIN_CPU1_DECAP_VR!!
S!@baseboard_fab2_lib.baseboard_fab2(sch_1):page76_i23@mstr_discrete.cap(chips)!CAP_0805-47UF,4V,20%,X6S,C9533A!C7P6!//jf4cfls225.pdx.intel.com/apd_proj/ppg_lib/epg_masterlib/logical/mstr_discrete/cap/chips/chips.prt!CAP!CAP_0805-47UF,4V,20%,X6S,C95333-006!CAP!!!F2360!!PVCCIN_CPU1_DECAP_VR!!
S!@baseboard_fab2_lib.baseboard_fab2(sch_1):page76_i181@mstr_discrete.cap(chips)!CAP_0805-47UF,4V,20%,X6S,C9533A!C7P9!//jf4cfls225.pdx.intel.com/apd_proj/ppg_lib/epg_masterlib/logical/mstr_discrete/cap/chips/chips.prt!CAP!CAP_0805-47UF,4V,20%,X6S,C95333-006!CAP!!!F2357!!PVCCIN_CPU1_DECAP_VR!!
S!@baseboard_fab2_lib.baseboard_fab2(sch_1):page76_i182@mstr_discrete.cap(chips)!CAP_0805-47UF,4V,20%,X6S,C9533A!C7P5!//jf4cfls225.pdx.intel.com/apd_proj/ppg_lib/epg_masterlib/logical/mstr_discrete/cap/chips/chips.prt!CAP!CAP_0805-47UF,4V,20%,X6S,C95333-006!CAP!!!F2361!!PVCCIN_CPU1_DECAP_VR!!
S!@baseboard_fab2_lib.baseboard_fab2(sch_1):page76_i183@mstr_discrete.cap(chips)!CAP_0805-47UF,4V,20%,X6S,C9533A!C7P11!//jf4cfls225.pdx.intel.com/apd_proj/ppg_lib/epg_masterlib/logical/mstr_discrete/cap/chips/chips.prt!CAP!CAP_0805-47UF,4V,20%,X6S,C95333-006!CAP!!!F2355!!PVCCIN_CPU1_DECAP_VR!!
S!@baseboard_fab2_lib.baseboard_fab2(sch_1):page76_i184@mstr_discrete.cap(chips)!CAP_0805-47UF,4V,20%,X6S,C9533A!C7P8!//jf4cfls225.pdx.intel.com/apd_proj/ppg_lib/epg_masterlib/logical/mstr_discrete/cap/chips/chips.prt!CAP!CAP_0805-47UF,4V,20%,X6S,C95333-006!CAP!!!F2358!!PVCCIN_CPU1_DECAP_VR!!
S!@baseboard_fab2_lib.baseboard_fab2(sch_1):page76_i195@mstr_discrete.cap(chips)!CAP_0805-47UF,4V,20%,X6S,C9533A!C7P4!//jf4cfls225.pdx.intel.com/apd_proj/ppg_lib/epg_masterlib/logical/mstr_discrete/cap/chips/chips.prt!CAP!CAP_0805-47UF,4V,20%,X6S,C95333-006!CAP!!!F2362!!PVCCIN_CPU1_DECAP_VR!!
S!@baseboard_fab2_lib.baseboard_fab2(sch_1):page42_i149@mstr_discrete.cap(chips)!CAP_0805-47UF,4V,20%,X6S,C9533A!C5P29!//jf4cfls225.pdx.intel.com/apd_proj/ppg_lib/epg_masterlib/logical/mstr_discrete/cap/chips/chips.prt!CAP!CAP_0805-47UF,4V,20%,X6S,C95333-006!CAP!!!F2387!!PVCCIN_CPU0_DECAP_VR!!
S!@baseboard_fab2_lib.baseboard_fab2(sch_1):page42_i148@mstr_discrete.cap(chips)!CAP_0805-47UF,4V,20%,X6S,C9533A!C5P30!//jf4cfls225.pdx.intel.com/apd_proj/ppg_lib/epg_masterlib/logical/mstr_discrete/cap/chips/chips.prt!CAP!CAP_0805-47UF,4V,20%,X6S,C95333-006!CAP!!!F2386!!PVCCIN_CPU0_DECAP_VR!!
S!@baseboard_fab2_lib.baseboard_fab2(sch_1):page42_i162@mstr_discrete.cap(chips)!CAP_0805-47UF,4V,20%,X6S,C9533A!C5P31!//jf4cfls225.pdx.intel.com/apd_proj/ppg_lib/epg_masterlib/logical/mstr_discrete/cap/chips/chips.prt!CAP!CAP_0805-47UF,4V,20%,X6S,C95333-006!CAP!!!F2385!!PVCCIN_CPU0_DECAP_VR!!
S!@baseboard_fab2_lib.baseboard_fab2(sch_1):page42_i163@mstr_discrete.cap(chips)!CAP_0805-47UF,4V,20%,X6S,C9533A!C4P2!//jf4cfls225.pdx.intel.com/apd_proj/ppg_lib/epg_masterlib/logical/mstr_discrete/cap/chips/chips.prt!CAP!CAP_0805-47UF,4V,20%,X6S,C95333-006!CAP!!!F2417!!PVCCIN_CPU0_DECAP_VR!!
S!@baseboard_fab2_lib.baseboard_fab2(sch_1):page42_i172@mstr_discrete.cap(chips)!CAP_0805-47UF,4V,20%,X6S,C9533A!C4P5!//jf4cfls225.pdx.intel.com/apd_proj/ppg_lib/epg_masterlib/logical/mstr_discrete/cap/chips/chips.prt!CAP!CAP_0805-47UF,4V,20%,X6S,C95333-006!CAP!!!F2414!!PVCCIN_CPU0_DECAP_VR!!
S!@baseboard_fab2_lib.baseboard_fab2(sch_1):page42_i63@mstr_discrete.cap(chips)!CAP_0805-47UF,4V,20%,X6S,C9533A!C5P37!//jf4cfls225.pdx.intel.com/apd_proj/ppg_lib/epg_masterlib/logical/mstr_discrete/cap/chips/chips.prt!CAP!CAP_0805-47UF,4V,20%,X6S,C95333-006!CAP!!!F2379!!PVCCIN_CPU0_DECAP_VR!!
S!@baseboard_fab2_lib.baseboard_fab2(sch_1):page42_i65@mstr_discrete.cap(chips)!CAP_0805-47UF,4V,20%,X6S,C9533A!C5P36!//jf4cfls225.pdx.intel.com/apd_proj/ppg_lib/epg_masterlib/logical/mstr_discrete/cap/chips/chips.prt!CAP!CAP_0805-47UF,4V,20%,X6S,C95333-006!CAP!!!F2380!!PVCCIN_CPU0_DECAP_VR!!
S!@baseboard_fab2_lib.baseboard_fab2(sch_1):page42_i51@mstr_discrete.cap(chips)!CAP_0805-47UF,4V,20%,X6S,C9533A!C5P35!//jf4cfls225.pdx.intel.com/apd_proj/ppg_lib/epg_masterlib/logical/mstr_discrete/cap/chips/chips.prt!CAP!CAP_0805-47UF,4V,20%,X6S,C95333-006!CAP!!!F2381!!PVCCIN_CPU0_DECAP_VR!!
S!@baseboard_fab2_lib.baseboard_fab2(sch_1):page42_i54@mstr_discrete.cap(chips)!CAP_0805-47UF,4V,20%,X6S,C9533A!C5P34!//jf4cfls225.pdx.intel.com/apd_proj/ppg_lib/epg_masterlib/logical/mstr_discrete/cap/chips/chips.prt!CAP!CAP_0805-47UF,4V,20%,X6S,C95333-006!CAP!!!F2382!!PVCCIN_CPU0_DECAP_VR!!
S!@baseboard_fab2_lib.baseboard_fab2(sch_1):page42_i50@mstr_discrete.cap(chips)!CAP_0805-47UF,4V,20%,X6S,C9533A!C5P33!//jf4cfls225.pdx.intel.com/apd_proj/ppg_lib/epg_masterlib/logical/mstr_discrete/cap/chips/chips.prt!CAP!CAP_0805-47UF,4V,20%,X6S,C95333-006!CAP!!!F2383!!PVCCIN_CPU0_DECAP_VR!!
S!@baseboard_fab2_lib.baseboard_fab2(sch_1):page42_i53@mstr_discrete.cap(chips)!CAP_0805-47UF,4V,20%,X6S,C9533A!C5P32!//jf4cfls225.pdx.intel.com/apd_proj/ppg_lib/epg_masterlib/logical/mstr_discrete/cap/chips/chips.prt!CAP!CAP_0805-47UF,4V,20%,X6S,C95333-006!CAP!!!F2384!!PVCCIN_CPU0_DECAP_VR!!
S!@baseboard_fab2_lib.baseboard_fab2(sch_1):page42_i185@mstr_discrete.cap(chips)!CAP_0805-47UF,4V,20%,X6S,C9533A!C5P20!//jf4cfls225.pdx.intel.com/apd_proj/ppg_lib/epg_masterlib/logical/mstr_discrete/cap/chips/chips.prt!CAP!CAP_0805-47UF,4V,20%,X6S,C95333-006!CAP!!!F2396!!PVCCIN_CPU0_DECAP_VR!!
S!@baseboard_fab2_lib.baseboard_fab2(sch_1):page42_i186@mstr_discrete.cap(chips)!CAP_0805-47UF,4V,20%,X6S,C9533A!C5P13!//jf4cfls225.pdx.intel.com/apd_proj/ppg_lib/epg_masterlib/logical/mstr_discrete/cap/chips/chips.prt!CAP!CAP_0805-47UF,4V,20%,X6S,C95333-006!CAP!!!F2403!!PVCCIN_CPU0_DECAP_VR!!
S!@baseboard_fab2_lib.baseboard_fab2(sch_1):page42_i41@mstr_discrete.cap(chips)!CAP_0805-47UF,4V,20%,X6S,C9533A!C5P14!//jf4cfls225.pdx.intel.com/apd_proj/ppg_lib/epg_masterlib/logical/mstr_discrete/cap/chips/chips.prt!CAP!CAP_0805-47UF,4V,20%,X6S,C95333-006!CAP!!!F2402!!PVCCIN_CPU0_DECAP_VR!!
S!@baseboard_fab2_lib.baseboard_fab2(sch_1):page42_i183@mstr_discrete.cap(chips)!CAP_0805-47UF,4V,20%,X6S,C9533A!C5P12!//jf4cfls225.pdx.intel.com/apd_proj/ppg_lib/epg_masterlib/logical/mstr_discrete/cap/chips/chips.prt!CAP!CAP_0805-47UF,4V,20%,X6S,C95333-006!CAP!!!F2404!!PVCCIN_CPU0_DECAP_VR!!
S!@baseboard_fab2_lib.baseboard_fab2(sch_1):page42_i17@mstr_discrete.cap(chips)!CAP_0805-47UF,4V,20%,X6S,C9533A!C4P10!//jf4cfls225.pdx.intel.com/apd_proj/ppg_lib/epg_masterlib/logical/mstr_discrete/cap/chips/chips.prt!CAP!CAP_0805-47UF,4V,20%,X6S,C95333-006!CAP!!!F2411!!PVCCIN_CPU0_DECAP_VR!!
S!@baseboard_fab2_lib.baseboard_fab2(sch_1):page42_i12@mstr_discrete.cap(chips)!CAP_0805-47UF,4V,20%,X6S,C9533A!C4P9!//jf4cfls225.pdx.intel.com/apd_proj/ppg_lib/epg_masterlib/logical/mstr_discrete/cap/chips/chips.prt!CAP!CAP_0805-47UF,4V,20%,X6S,C95333-006!CAP!!!F2412!!PVCCIN_CPU0_DECAP_VR!!
S!@baseboard_fab2_lib.baseboard_fab2(sch_1):page42_i10@mstr_discrete.cap(chips)!CAP_0805-47UF,4V,20%,X6S,C9533A!C4P1!//jf4cfls225.pdx.intel.com/apd_proj/ppg_lib/epg_masterlib/logical/mstr_discrete/cap/chips/chips.prt!CAP!CAP_0805-47UF,4V,20%,X6S,C95333-006!CAP!!!F2418!!PVCCIN_CPU0_DECAP_VR!!
S!@baseboard_fab2_lib.baseboard_fab2(sch_1):page76_i127@mstr_discrete.cap(chips)!CAP_0805-47UF,4V,20%,X6S,C9533A!C8P10!//jf4cfls225.pdx.intel.com/apd_proj/ppg_lib/epg_masterlib/logical/mstr_discrete/cap/chips/chips.prt!CAP!CAP_0805-47UF,4V,20%,X6S,C95333-006!CAP!!!F2339!!PVCCIN_CPU1_DECAP_VR!!
S!@baseboard_fab2_lib.baseboard_fab2(sch_1):page237_i77@mstr_discrete.cap(chips)!CAP_0805-47UF,4V,20%,X6S,C9533A!C8A12!//jf4cfls225.pdx.intel.com/apd_proj/ppg_lib/epg_masterlib/logical/mstr_discrete/cap/chips/chips.prt!CAP!CAP_0805-47UF,4V,20%,X6S,C95333-006!CAP!!!F2347!!P1V8_PCH_STBY_VR!!
S!@baseboard_fab2_lib.baseboard_fab2(sch_1):page237_i79@mstr_discrete.cap(chips)!CAP_0805-47UF,4V,20%,X6S,C9533A!C2L32!//jf4cfls225.pdx.intel.com/apd_proj/ppg_lib/epg_masterlib/logical/mstr_discrete/cap/chips/chips.prt!CAP!CAP_0805-47UF,4V,20%,X6S,C95333-006!CAP!!!F2425!!P1V8_PCH_STBY_VR!!
S!@baseboard_fab2_lib.baseboard_fab2(sch_1):page232_i236@mstr_discrete.cap(chips)!CAP_0805-47UF,4V,20%,X6S,C9533A!C6B3!//jf4cfls225.pdx.intel.com/apd_proj/ppg_lib/epg_masterlib/logical/mstr_discrete/cap/chips/chips.prt!CAP!CAP_0805-47UF,4V,20%,X6S,C95333-006!CAP!!!F2373!!PVPP_KLM_VR!!
S!@baseboard_fab2_lib.baseboard_fab2(sch_1):page232_i238@mstr_discrete.cap(chips)!CAP_0805-47UF,4V,20%,X6S,C9533A!C7B7!//jf4cfls225.pdx.intel.com/apd_proj/ppg_lib/epg_masterlib/logical/mstr_discrete/cap/chips/chips.prt!CAP!CAP_0805-47UF,4V,20%,X6S,C95333-006!CAP!!!F2366!!PVPP_KLM_VR!!
S!@baseboard_fab2_lib.baseboard_fab2(sch_1):page233_i221@mstr_discrete.cap(chips)!CAP_0805-47UF,4V,20%,X6S,C9533A!C6U3!//jf4cfls225.pdx.intel.com/apd_proj/ppg_lib/epg_masterlib/logical/mstr_discrete/cap/chips/chips.prt!CAP!CAP_0805-47UF,4V,20%,X6S,C95333-006!CAP!!!F2371!!PVPP_KLM_VR!!
S!@baseboard_fab2_lib.baseboard_fab2(sch_1):page233_i223@mstr_discrete.cap(chips)!CAP_0805-47UF,4V,20%,X6S,C9533A!C6U2!//jf4cfls225.pdx.intel.com/apd_proj/ppg_lib/epg_masterlib/logical/mstr_discrete/cap/chips/chips.prt!CAP!CAP_0805-47UF,4V,20%,X6S,C95333-006!CAP!!!F2372!!PVPP_KLM_VR!!
S!@baseboard_fab2_lib.baseboard_fab2(sch_1):page234_i177@mstr_discrete.cap(chips)!CAP_0805-47UF,4V,20%,X6S,C9533A!C4B3!//jf4cfls225.pdx.intel.com/apd_proj/ppg_lib/epg_masterlib/logical/mstr_discrete/cap/chips/chips.prt!CAP!CAP_0805-47UF,4V,20%,X6S,C95333-006!CAP!!!F2419!!PVPP_KLM_VR!!
S!@baseboard_fab2_lib.baseboard_fab2(sch_1):page234_i180@mstr_discrete.cap(chips)!CAP_0805-47UF,4V,20%,X6S,C9533A!C4B2!//jf4cfls225.pdx.intel.com/apd_proj/ppg_lib/epg_masterlib/logical/mstr_discrete/cap/chips/chips.prt!CAP!CAP_0805-47UF,4V,20%,X6S,C95333-006!CAP!!!F2420!!PVPP_KLM_VR!!
S!@baseboard_fab2_lib.baseboard_fab2(sch_1):page231_i184@mstr_discrete.cap(chips)!CAP_0805-47UF,4V,20%,X6S,C9533A!C3T7!//jf4cfls225.pdx.intel.com/apd_proj/ppg_lib/epg_masterlib/logical/mstr_discrete/cap/chips/chips.prt!CAP!CAP_0805-47UF,4V,20%,X6S,C95333-006!CAP!!!F2422!!PVPP_KLM_VR!!
S!@baseboard_fab2_lib.baseboard_fab2(sch_1):page231_i186@mstr_discrete.cap(chips)!CAP_0805-47UF,4V,20%,X6S,C9533A!C3T9!//jf4cfls225.pdx.intel.com/apd_proj/ppg_lib/epg_masterlib/logical/mstr_discrete/cap/chips/chips.prt!CAP!CAP_0805-47UF,4V,20%,X6S,C95333-006!CAP!!!F2421!!PVPP_KLM_VR!!
S!@baseboard_fab2_lib.baseboard_fab2(sch_1):page132_i40@mstr_discrete.cap(chips)!CAP_0805-47UF,4V,20%,X6S,C9533A!C7A31!//jf4cfls225.pdx.intel.com/apd_proj/ppg_lib/epg_masterlib/logical/mstr_discrete/cap/chips/chips.prt!CAP!CAP_0805-47UF,4V,20%,X6S,C95333-006!CAP!!!F2370!!SB_DECOUPLING!!
S!@baseboard_fab2_lib.baseboard_fab2(sch_1):page132_i38@mstr_discrete.cap(chips)!CAP_0805-47UF,4V,20%,X6S,C9533A!C7A32!//jf4cfls225.pdx.intel.com/apd_proj/ppg_lib/epg_masterlib/logical/mstr_discrete/cap/chips/chips.prt!CAP!CAP_0805-47UF,4V,20%,X6S,C95333-006!CAP!!!F2369!!SB_DECOUPLING!!
S!@baseboard_fab2_lib.baseboard_fab2(sch_1):page132_i24@mstr_discrete.cap(chips)!CAP_0805-47UF,4V,20%,X6S,C9533A!C7B4!//jf4cfls225.pdx.intel.com/apd_proj/ppg_lib/epg_masterlib/logical/mstr_discrete/cap/chips/chips.prt!CAP!CAP_0805-47UF,4V,20%,X6S,C95333-006!CAP!!!F2367!!SB_DECOUPLING!!
S!@baseboard_fab2_lib.baseboard_fab2(sch_1):page132_i23@mstr_discrete.cap(chips)!CAP_0805-47UF,4V,20%,X6S,C9533A!C7A33!//jf4cfls225.pdx.intel.com/apd_proj/ppg_lib/epg_masterlib/logical/mstr_discrete/cap/chips/chips.prt!CAP!CAP_0805-47UF,4V,20%,X6S,C95333-006!CAP!!!F2368!!SB_DECOUPLING!!
S!@baseboard_fab2_lib.baseboard_fab2(sch_1):page131_i24@mstr_discrete.cap(chips)!CAP_0805-47UF,4V,20%,X6S,C9533A!C8B15!//jf4cfls225.pdx.intel.com/apd_proj/ppg_lib/epg_masterlib/logical/mstr_discrete/cap/chips/chips.prt!CAP!CAP_0805-47UF,4V,20%,X6S,C95333-006!CAP!!!F2345!!SB_DECOUPLING!!
S!@baseboard_fab2_lib.baseboard_fab2(sch_1):page131_i22@mstr_discrete.cap(chips)!CAP_0805-47UF,4V,20%,X6S,C9533A!C8B16!//jf4cfls225.pdx.intel.com/apd_proj/ppg_lib/epg_masterlib/logical/mstr_discrete/cap/chips/chips.prt!CAP!CAP_0805-47UF,4V,20%,X6S,C95333-006!CAP!!!F2344!!SB_DECOUPLING!!
S!@baseboard_fab2_lib.baseboard_fab2(sch_1):page131_i37@mstr_discrete.cap(chips)!CAP_0805-47UF,4V,20%,X6S,C9533A!C8A13!//jf4cfls225.pdx.intel.com/apd_proj/ppg_lib/epg_masterlib/logical/mstr_discrete/cap/chips/chips.prt!CAP!CAP_0805-47UF,4V,20%,X6S,C95333-006!CAP!!!F2346!!SB_DECOUPLING!!
S!@baseboard_fab2_lib.baseboard_fab2(sch_1):page131_i35@mstr_discrete.cap(chips)!CAP_0805-47UF,4V,20%,X6S,C9533A!C2M11!//jf4cfls225.pdx.intel.com/apd_proj/ppg_lib/epg_masterlib/logical/mstr_discrete/cap/chips/chips.prt!CAP!CAP_0805-47UF,4V,20%,X6S,C95333-006!CAP!!!F2424!!SB_DECOUPLING!!
S!@baseboard_fab2_lib.baseboard_fab2(sch_1):page131_i34@mstr_discrete.cap(chips)!CAP_0805-47UF,4V,20%,X6S,C9533A!C2M17!//jf4cfls225.pdx.intel.com/apd_proj/ppg_lib/epg_masterlib/logical/mstr_discrete/cap/chips/chips.prt!CAP!CAP_0805-47UF,4V,20%,X6S,C95333-006!CAP!!!F2423!!SB_DECOUPLING!!
S!@baseboard_fab2_lib.baseboard_fab2(sch_1):page236_i9@mstr_discrete.cap(chips)!CAP_0805LF-22UF,4V,20%,X6S,C95A!C7A30!//jf4cfls225.pdx.intel.com/apd_proj/ppg_lib/epg_masterlib/logical/mstr_discrete/cap/chips/chips.prt!CAP!CAP_0805LF-22UF,4V,20%,X6S,C95333-002!CAP!!!F2298!!PVNN_PCH_STBY!!
S!@baseboard_fab2_lib.baseboard_fab2(sch_1):page236_i46@mstr_discrete.cap(chips)!CAP_0805LF-22UF,4V,20%,X6S,C95A!C8A16!//jf4cfls225.pdx.intel.com/apd_proj/ppg_lib/epg_masterlib/logical/mstr_discrete/cap/chips/chips.prt!CAP!CAP_0805LF-22UF,4V,20%,X6S,C95333-002!CAP!!!F2296!!P1V05_PCH_STBY_VR!!
S!@baseboard_fab2_lib.baseboard_fab2(sch_1):page217_i184@mstr_discrete.cap(chips)!CAP_0805LF-22UF,4V,20%,X6S,C95A!C5P39!//jf4cfls225.pdx.intel.com/apd_proj/ppg_lib/epg_masterlib/logical/mstr_discrete/cap/chips/chips.prt!CAP!CAP_0805LF-22UF,4V,20%,X6S,C95333-002!CAP!!!F2302!!VDDQ_ABC_CPU0!!
S!@baseboard_fab2_lib.baseboard_fab2(sch_1):page217_i193@mstr_discrete.cap(chips)!CAP_0805LF-22UF,4V,20%,X6S,C95A!C5P38!//jf4cfls225.pdx.intel.com/apd_proj/ppg_lib/epg_masterlib/logical/mstr_discrete/cap/chips/chips.prt!CAP!CAP_0805LF-22UF,4V,20%,X6S,C95333-002!CAP!!!F2303!!VDDQ_ABC_CPU0!!
S!@baseboard_fab2_lib.baseboard_fab2(sch_1):page220_i177@mstr_discrete.cap(chips)!CAP_0805LF-22UF,4V,20%,X6S,C95A!C5P2!//jf4cfls225.pdx.intel.com/apd_proj/ppg_lib/epg_masterlib/logical/mstr_discrete/cap/chips/chips.prt!CAP!CAP_0805LF-22UF,4V,20%,X6S,C95333-002!CAP!!!F2307!!VDDQ_DEF_CPU0!!
S!@baseboard_fab2_lib.baseboard_fab2(sch_1):page220_i179@mstr_discrete.cap(chips)!CAP_0805LF-22UF,4V,20%,X6S,C95A!C5P1!//jf4cfls225.pdx.intel.com/apd_proj/ppg_lib/epg_masterlib/logical/mstr_discrete/cap/chips/chips.prt!CAP!CAP_0805LF-22UF,4V,20%,X6S,C95333-002!CAP!!!F2308!!VDDQ_DEF_CPU0!!
S!@baseboard_fab2_lib.baseboard_fab2(sch_1):page225_i184@mstr_discrete.cap(chips)!CAP_0805LF-22UF,4V,20%,X6S,C95A!C8P30!//jf4cfls225.pdx.intel.com/apd_proj/ppg_lib/epg_masterlib/logical/mstr_discrete/cap/chips/chips.prt!CAP!CAP_0805LF-22UF,4V,20%,X6S,C95333-002!CAP!!!F2290!!VDDQ_GHJ_CPU1!!
S!@baseboard_fab2_lib.baseboard_fab2(sch_1):page225_i178@mstr_discrete.cap(chips)!CAP_0805LF-22UF,4V,20%,X6S,C95A!C8P31!//jf4cfls225.pdx.intel.com/apd_proj/ppg_lib/epg_masterlib/logical/mstr_discrete/cap/chips/chips.prt!CAP!CAP_0805LF-22UF,4V,20%,X6S,C95333-002!CAP!!!F2289!!VDDQ_GHJ_CPU1!!
S!@baseboard_fab2_lib.baseboard_fab2(sch_1):page228_i183@mstr_discrete.cap(chips)!CAP_0805LF-22UF,4V,20%,X6S,C95A!C8P2!//jf4cfls225.pdx.intel.com/apd_proj/ppg_lib/epg_masterlib/logical/mstr_discrete/cap/chips/chips.prt!CAP!CAP_0805LF-22UF,4V,20%,X6S,C95333-002!CAP!!!F2294!!VDDQ_KLM_CPU1!!
S!@baseboard_fab2_lib.baseboard_fab2(sch_1):page228_i185@mstr_discrete.cap(chips)!CAP_0805LF-22UF,4V,20%,X6S,C95A!C8P1!//jf4cfls225.pdx.intel.com/apd_proj/ppg_lib/epg_masterlib/logical/mstr_discrete/cap/chips/chips.prt!CAP!CAP_0805LF-22UF,4V,20%,X6S,C95333-002!CAP!!!F2295!!VDDQ_KLM_CPU1!!
S!@baseboard_fab2_lib.baseboard_fab2(sch_1):page221_i20@mstr_discrete.cap(chips)!CAP_0805LF-22UF,4V,20%,X6S,C95A!C4G24!//jf4cfls225.pdx.intel.com/apd_proj/ppg_lib/epg_masterlib/logical/mstr_discrete/cap/chips/chips.prt!CAP!CAP_0805LF-22UF,4V,20%,X6S,C95333-002!CAP!!!F2309!!VTT_ABC_PWR_VR!!
S!@baseboard_fab2_lib.baseboard_fab2(sch_1):page229_i17@mstr_discrete.cap(chips)!CAP_0805LF-22UF,4V,20%,X6S,C95A!C4G20!//jf4cfls225.pdx.intel.com/apd_proj/ppg_lib/epg_masterlib/logical/mstr_discrete/cap/chips/chips.prt!CAP!CAP_0805LF-22UF,4V,20%,X6S,C95333-002!CAP!!!F2310!!VTT_GHJ_PWR_VR!!
S!@baseboard_fab2_lib.baseboard_fab2(sch_1):page222_i16@mstr_discrete.cap(chips)!CAP_0805LF-22UF,4V,20%,X6S,C95A!C4A1!//jf4cfls225.pdx.intel.com/apd_proj/ppg_lib/epg_masterlib/logical/mstr_discrete/cap/chips/chips.prt!CAP!CAP_0805LF-22UF,4V,20%,X6S,C95333-002!CAP!!!F2312!!VTT_DEF_PWR_VR!!
S!@baseboard_fab2_lib.baseboard_fab2(sch_1):page230_i18@mstr_discrete.cap(chips)!CAP_0805LF-22UF,4V,20%,X6S,C95A!C4A13!//jf4cfls225.pdx.intel.com/apd_proj/ppg_lib/epg_masterlib/logical/mstr_discrete/cap/chips/chips.prt!CAP!CAP_0805LF-22UF,4V,20%,X6S,C95333-002!CAP!!!F2311!!VTT_KLM_PWR_VR!!
S!@baseboard_fab2_lib.baseboard_fab2(sch_1):page238_i30@mstr_discrete.cap(chips)!CAP_0805LF-22UF,4V,20%,X6S,C95A!C9F4!//jf4cfls225.pdx.intel.com/apd_proj/ppg_lib/epg_masterlib/logical/mstr_discrete/cap/chips/chips.prt!CAP!CAP_0805LF-22UF,4V,20%,X6S,C95333-002!CAP!!!F2288!!P1V26_BMC_STBY_VR!!
S!@baseboard_fab2_lib.baseboard_fab2(sch_1):page239_i7@mstr_discrete.cap(chips)!CAP_0805LF-22UF,4V,20%,X6S,C95A!C9F13!//jf4cfls225.pdx.intel.com/apd_proj/ppg_lib/epg_masterlib/logical/mstr_discrete/cap/chips/chips.prt!CAP!CAP_0805LF-22UF,4V,20%,X6S,C95333-002!CAP!!!F2287!!P1V538_BMC_STBY_VR!!
S!@baseboard_fab2_lib.baseboard_fab2(sch_1):page216_i6@mstr_discrete.cap(chips)!CAP_0805LF-22UF,4V,20%,X6S,C95A!C6G3!//jf4cfls225.pdx.intel.com/apd_proj/ppg_lib/epg_masterlib/logical/mstr_discrete/cap/chips/chips.prt!CAP!CAP_0805LF-22UF,4V,20%,X6S,C95333-002!CAP!!!F2299!!VDDQ_ABC_PWR_VR!!
S!@baseboard_fab2_lib.baseboard_fab2(sch_1):page216_i68@mstr_discrete.cap(chips)!CAP_0805LF-22UF,4V,20%,X6S,C95A!C7G27!//jf4cfls225.pdx.intel.com/apd_proj/ppg_lib/epg_masterlib/logical/mstr_discrete/cap/chips/chips.prt!CAP!CAP_0805LF-22UF,4V,20%,X6S,C95333-002!CAP!!!F2297!!VDDQ_ABC_PWR_VR!!
S!@baseboard_fab2_lib.baseboard_fab2(sch_1):page42_i25@mstr_discrete.cap(chips)!CAP_0805LF-22UF,4V,20%,X6S,C95A!C5P7!//jf4cfls225.pdx.intel.com/apd_proj/ppg_lib/epg_masterlib/logical/mstr_discrete/cap/chips/chips.prt!CAP!CAP_0805LF-22UF,4V,20%,X6S,C95333-002!CAP!!!F2306!!PVCCIN_CPU0_DECAP_VR!!
S!@baseboard_fab2_lib.baseboard_fab2(sch_1):page224_i6@mstr_discrete.cap(chips)!CAP_0805LF-22UF,4V,20%,X6S,C95A!C1G17!//jf4cfls225.pdx.intel.com/apd_proj/ppg_lib/epg_masterlib/logical/mstr_discrete/cap/chips/chips.prt!CAP!CAP_0805LF-22UF,4V,20%,X6S,C95333-002!CAP!!!F2314!!VDDQ_GHJ_PWR_VR!!
S!@baseboard_fab2_lib.baseboard_fab2(sch_1):page219_i87@mstr_discrete.cap(chips)!CAP_0805LF-22UF,4V,20%,X6S,C95A!C6A1!//jf4cfls225.pdx.intel.com/apd_proj/ppg_lib/epg_masterlib/logical/mstr_discrete/cap/chips/chips.prt!CAP!CAP_0805LF-22UF,4V,20%,X6S,C95333-002!CAP!!!F2301!!VDDQ_DEF_PWR_VR!!
S!@baseboard_fab2_lib.baseboard_fab2(sch_1):page219_i68@mstr_discrete.cap(chips)!CAP_0805LF-22UF,4V,20%,X6S,C95A!C6A4!//jf4cfls225.pdx.intel.com/apd_proj/ppg_lib/epg_masterlib/logical/mstr_discrete/cap/chips/chips.prt!CAP!CAP_0805LF-22UF,4V,20%,X6S,C95333-002!CAP!!!F2300!!VDDQ_DEF_PWR_VR!!
S!@baseboard_fab2_lib.baseboard_fab2(sch_1):page227_i68@mstr_discrete.cap(chips)!CAP_0805LF-22UF,4V,20%,X6S,C95A!C1A1!//jf4cfls225.pdx.intel.com/apd_proj/ppg_lib/epg_masterlib/logical/mstr_discrete/cap/chips/chips.prt!CAP!CAP_0805LF-22UF,4V,20%,X6S,C95333-002!CAP!!!F2316!!VDDQ_KLM_PWR_VR!!
S!@baseboard_fab2_lib.baseboard_fab2(sch_1):page224_i68@mstr_discrete.cap(chips)!CAP_0805LF-22UF,4V,20%,X6S,C95A!C1G20!//jf4cfls225.pdx.intel.com/apd_proj/ppg_lib/epg_masterlib/logical/mstr_discrete/cap/chips/chips.prt!CAP!CAP_0805LF-22UF,4V,20%,X6S,C95333-002!CAP!!!F2313!!VDDQ_GHJ_PWR_VR!!
S!@baseboard_fab2_lib.baseboard_fab2(sch_1):page227_i6@mstr_discrete.cap(chips)!CAP_0805LF-22UF,4V,20%,X6S,C95A!C1A12!//jf4cfls225.pdx.intel.com/apd_proj/ppg_lib/epg_masterlib/logical/mstr_discrete/cap/chips/chips.prt!CAP!CAP_0805LF-22UF,4V,20%,X6S,C95333-002!CAP!!!F2315!!VDDQ_KLM_PWR_VR!!
S!@baseboard_fab2_lib.baseboard_fab2(sch_1):page42_i19@mstr_discrete.cap(chips)!CAP_0805LF-22UF,4V,20%,X6S,C95A!C5P8!//jf4cfls225.pdx.intel.com/apd_proj/ppg_lib/epg_masterlib/logical/mstr_discrete/cap/chips/chips.prt!CAP!CAP_0805LF-22UF,4V,20%,X6S,C95333-002!CAP!!!F2305!!PVCCIN_CPU0_DECAP_VR!!
S!@baseboard_fab2_lib.baseboard_fab2(sch_1):page42_i18@mstr_discrete.cap(chips)!CAP_0805LF-22UF,4V,20%,X6S,C95A!C5P9!//jf4cfls225.pdx.intel.com/apd_proj/ppg_lib/epg_masterlib/logical/mstr_discrete/cap/chips/chips.prt!CAP!CAP_0805LF-22UF,4V,20%,X6S,C95333-002!CAP!!!F2304!!PVCCIN_CPU0_DECAP_VR!!
S!@baseboard_fab2_lib.baseboard_fab2(sch_1):page76_i58@mstr_discrete.cap(chips)!CAP_0805LF-22UF,4V,20%,X6S,C95A!C8P5!//jf4cfls225.pdx.intel.com/apd_proj/ppg_lib/epg_masterlib/logical/mstr_discrete/cap/chips/chips.prt!CAP!CAP_0805LF-22UF,4V,20%,X6S,C95333-002!CAP!!!F2293!!PVCCIN_CPU1_DECAP_VR!!
S!@baseboard_fab2_lib.baseboard_fab2(sch_1):page76_i55@mstr_discrete.cap(chips)!CAP_0805LF-22UF,4V,20%,X6S,C95A!C8P6!//jf4cfls225.pdx.intel.com/apd_proj/ppg_lib/epg_masterlib/logical/mstr_discrete/cap/chips/chips.prt!CAP!CAP_0805LF-22UF,4V,20%,X6S,C95333-002!CAP!!!F2292!!PVCCIN_CPU1_DECAP_VR!!
S!@baseboard_fab2_lib.baseboard_fab2(sch_1):page76_i50@mstr_discrete.cap(chips)!CAP_0805LF-22UF,4V,20%,X6S,C95A!C8P7!//jf4cfls225.pdx.intel.com/apd_proj/ppg_lib/epg_masterlib/logical/mstr_discrete/cap/chips/chips.prt!CAP!CAP_0805LF-22UF,4V,20%,X6S,C95333-002!CAP!!!F2291!!PVCCIN_CPU1_DECAP_VR!!
S!@baseboard_fab2_lib.baseboard_fab2(sch_1):page232_i202@mstr_discrete.cap(chips)!CAP_1210-47UF,16V,20%,X6S,D384A!C7B8!//jf4cfls225.pdx.intel.com/apd_proj/ppg_lib/epg_masterlib/logical/mstr_discrete/cap/chips/chips.prt!CAP!CAP_1210-47UF,16V,20%,X6S,D38464-007!CAP!!!F2267!!PVPP_KLM_VR!!
S!@baseboard_fab2_lib.baseboard_fab2(sch_1):page233_i189@mstr_discrete.cap(chips)!CAP_1210-47UF,16V,20%,X6S,D384A!C4G5!//jf4cfls225.pdx.intel.com/apd_proj/ppg_lib/epg_masterlib/logical/mstr_discrete/cap/chips/chips.prt!CAP!CAP_1210-47UF,16V,20%,X6S,D38464-007!CAP!!!F2268!!PVPP_KLM_VR!!
S!@baseboard_fab2_lib.baseboard_fab2(sch_1):page234_i130@mstr_discrete.cap(chips)!CAP_1210-47UF,16V,20%,X6S,D384A!C4B1!//jf4cfls225.pdx.intel.com/apd_proj/ppg_lib/epg_masterlib/logical/mstr_discrete/cap/chips/chips.prt!CAP!CAP_1210-47UF,16V,20%,X6S,D38464-007!CAP!!!F2269!!PVPP_KLM_VR!!
S!@baseboard_fab2_lib.baseboard_fab2(sch_1):page231_i151@mstr_discrete.cap(chips)!CAP_1210-47UF,16V,20%,X6S,D384A!C7F7!//jf4cfls225.pdx.intel.com/apd_proj/ppg_lib/epg_masterlib/logical/mstr_discrete/cap/chips/chips.prt!CAP!CAP_1210-47UF,16V,20%,X6S,D38464-007!CAP!!!F2264!!PVPP_KLM_VR!!
S!@baseboard_fab2_lib.baseboard_fab2(sch_1):page240_i134@mstr_discrete.cap(chips)!CAP_1210-47UF,16V,20%,X6S,D384A!C9F1!//jf4cfls225.pdx.intel.com/apd_proj/ppg_lib/epg_masterlib/logical/mstr_discrete/cap/chips/chips.prt!CAP!CAP_1210-47UF,16V,20%,X6S,D38464-007!CAP!!!F2262!!P3V3_STBY_VR!!
S!@baseboard_fab2_lib.baseboard_fab2(sch_1):page240_i135@mstr_discrete.cap(chips)!CAP_1210-47UF,16V,20%,X6S,D384A!C8E11!//jf4cfls225.pdx.intel.com/apd_proj/ppg_lib/epg_masterlib/logical/mstr_discrete/cap/chips/chips.prt!CAP!CAP_1210-47UF,16V,20%,X6S,D38464-007!CAP!!!F2263!!P3V3_STBY_VR!!
S!@baseboard_fab2_lib.baseboard_fab2(sch_1):page225_i192@mstr_discrete.cap(chips)!CAP_1210-47UF,16V,20%,X6S,D384A!C1G15!//jf4cfls225.pdx.intel.com/apd_proj/ppg_lib/epg_masterlib/logical/mstr_discrete/cap/chips/chips.prt!CAP!CAP_1210-47UF,16V,20%,X6S,D38464-007!CAP!!!F2270!!!!
S!@baseboard_fab2_lib.baseboard_fab2(sch_1):page225_i193@mstr_discrete.cap(chips)!CAP_1210-47UF,16V,20%,X6S,D384A!C1G12!//jf4cfls225.pdx.intel.com/apd_proj/ppg_lib/epg_masterlib/logical/mstr_discrete/cap/chips/chips.prt!CAP!CAP_1210-47UF,16V,20%,X6S,D38464-007!CAP!!!F2271!!!!
S!@baseboard_fab2_lib.baseboard_fab2(sch_1):page225_i194@mstr_discrete.cap(chips)!CAP_1210-47UF,16V,20%,X6S,D384A!C1G2!//jf4cfls225.pdx.intel.com/apd_proj/ppg_lib/epg_masterlib/logical/mstr_discrete/cap/chips/chips.prt!CAP!CAP_1210-47UF,16V,20%,X6S,D38464-007!CAP!!!F2273!!!!
S!@baseboard_fab2_lib.baseboard_fab2(sch_1):page225_i195@mstr_discrete.cap(chips)!CAP_1210-47UF,16V,20%,X6S,D384A!C1G7!//jf4cfls225.pdx.intel.com/apd_proj/ppg_lib/epg_masterlib/logical/mstr_discrete/cap/chips/chips.prt!CAP!CAP_1210-47UF,16V,20%,X6S,D38464-007!CAP!!!F2272!!!!
S!@baseboard_fab2_lib.baseboard_fab2(sch_1):page241_i47@mstr_discrete.cap(chips)!CAP_1210-47UF,16V,20%,X6S,D384A!C7E12!//jf4cfls225.pdx.intel.com/apd_proj/ppg_lib/epg_masterlib/logical/mstr_discrete/cap/chips/chips.prt!CAP!CAP_1210-47UF,16V,20%,X6S,D38464-007!CAP!!!F2266!!P5V_STBY_VR!!
S!@baseboard_fab2_lib.baseboard_fab2(sch_1):page241_i45@mstr_discrete.cap(chips)!CAP_1210-47UF,16V,20%,X6S,D384A!C7E13!//jf4cfls225.pdx.intel.com/apd_proj/ppg_lib/epg_masterlib/logical/mstr_discrete/cap/chips/chips.prt!CAP!CAP_1210-47UF,16V,20%,X6S,D38464-007!CAP!!!F2265!!P5V_STBY_VR!!
S!@baseboard_fab2_lib.baseboard_fab2(sch_1):page176_i30@mstr_discrete.choke_4pin(chips)!CHOKE_4PIN_SMLF-90 OHM,EMPTY,7A!L1M2!//jf4cfls225.pdx.intel.com/apd_proj/ppg_lib/epg_masterlib/logical/mstr_discrete/choke_4pin/chips/chips.prt!CHOKE_4PIN!CHOKE_4PIN_SMLF-90 OHM,EMPTY,752402-015!CHOKE_4PIN!!!F2261!!USB_REAR!!
S!@baseboard_fab2_lib.baseboard_fab2(sch_1):page196_i53@mstr_discrete.diode2a_dual(chips)!DIODE2A_DUAL_SMLF-BAS70-05,DIOA!CR2U1!//jf4cfls225.pdx.intel.com/apd_proj/ppg_lib/epg_masterlib/logical/mstr_discrete/diode2a_dual/chips/chips.prt!DIODE2A_DUAL!DIODE2A_DUAL_SMLF-BAS70-05,DIO,C90169-001!DIODE2A_DUAL!!!F2225!!SB_VRD!!
S!@baseboard_fab2_lib.baseboard_fab2(sch_1):page176_i98@mstr_discrete.diodeac_dual_array(chips)!DIODEAC_DUAL_ARRAY_SM9-ESD3V3UA!CR1M2!//jf4cfls225.pdx.intel.com/apd_proj/ppg_lib/epg_masterlib/logical/mstr_discrete/diodeac_dual_array/chips/chips.prt!DIODEAC_DUAL_ARRAY!DIODEAC_DUAL_ARRAY_SM9-ESD3V3U4ULC,IC,G18435-001!DIODEAC_DUAL_ARRAY_SM9!!!F2223!!USB_REAR!!
S!@baseboard_fab2_lib.baseboard_fab2(sch_1):page176_i52@mstr_discrete.diodeac_dual_array(chips)!DIODEAC_DUAL_ARRAY_SM9-ESD3V3UA!CR1M1!//jf4cfls225.pdx.intel.com/apd_proj/ppg_lib/epg_masterlib/logical/mstr_discrete/diodeac_dual_array/chips/chips.prt!DIODEAC_DUAL_ARRAY!DIODEAC_DUAL_ARRAY_SM9-ESD3V3U4ULC,IC,G18435-001!DIODEAC_DUAL_ARRAY_SM9!!!F2224!!USB_REAR!!
S!@baseboard_fab2_lib.baseboard_fab2(sch_1):page232_i200@mstr_discrete.ferrite(chips)!FERRITE_SM-22,FB,656554-051!FB7B1!//jf4cfls225.pdx.intel.com/apd_proj/ppg_lib/epg_masterlib/logical/mstr_discrete/ferrite/chips/chips.prt!FERRITE!FERRITE_SM-22,FB,656554-051!FERRITE_SM!!!F2196!!PVPP_KLM_VR!!
S!@baseboard_fab2_lib.baseboard_fab2(sch_1):page233_i198@mstr_discrete.ferrite(chips)!FERRITE_SM-22,FB,656554-051!FB4G1!//jf4cfls225.pdx.intel.com/apd_proj/ppg_lib/epg_masterlib/logical/mstr_discrete/ferrite/chips/chips.prt!FERRITE!FERRITE_SM-22,FB,656554-051!FERRITE_SM!!!F2197!!PVPP_KLM_VR!!
S!@baseboard_fab2_lib.baseboard_fab2(sch_1):page234_i154@mstr_discrete.ferrite(chips)!FERRITE_SM-22,FB,656554-051!FB4A1!//jf4cfls225.pdx.intel.com/apd_proj/ppg_lib/epg_masterlib/logical/mstr_discrete/ferrite/chips/chips.prt!FERRITE!FERRITE_SM-22,FB,656554-051!FERRITE_SM!!!F2198!!PVPP_KLM_VR!!
S!@baseboard_fab2_lib.baseboard_fab2(sch_1):page231_i162@mstr_discrete.ferrite(chips)!FERRITE_SM-22,FB,656554-051!FB7F1!//jf4cfls225.pdx.intel.com/apd_proj/ppg_lib/epg_masterlib/logical/mstr_discrete/ferrite/chips/chips.prt!FERRITE!FERRITE_SM-22,FB,656554-051!FERRITE_SM!!!F2194!!PVPP_KLM_VR!!
S!@baseboard_fab2_lib.baseboard_fab2(sch_1):page240_i132@mstr_discrete.ferrite(chips)!FERRITE_SM-22,FB,656554-051!FB9E1!//jf4cfls225.pdx.intel.com/apd_proj/ppg_lib/epg_masterlib/logical/mstr_discrete/ferrite/chips/chips.prt!FERRITE!FERRITE_SM-22,FB,656554-051!FERRITE_SM!!!F2193!!P3V3_STBY_VR!!
S!@baseboard_fab2_lib.baseboard_fab2(sch_1):page241_i82@mstr_discrete.ferrite(chips)!FERRITE_SM-22,FB,656554-051!FB7E1!//jf4cfls225.pdx.intel.com/apd_proj/ppg_lib/epg_masterlib/logical/mstr_discrete/ferrite/chips/chips.prt!FERRITE!FERRITE_SM-22,FB,656554-051!FERRITE_SM!!!F2195!!P5V_STBY_VR!!
S!@baseboard_fab2_lib.baseboard_fab2(sch_1):page169_i155@mstr_discrete.ferrite(chips)!FERRITE_SMLF-30,FB,693286-021!FB1U4!//jf4cfls225.pdx.intel.com/apd_proj/ppg_lib/epg_masterlib/logical/mstr_discrete/ferrite/chips/chips.prt!FERRITE!FERRITE_SMLF-30,FB,693286-021!FERRITE!!!F2191!!BMC_VOLT_MONITOR!!
S!@baseboard_fab2_lib.baseboard_fab2(sch_1):page169_i57@mstr_discrete.ferrite(chips)!FERRITE_SMLF-30,FB,693286-021!FB1U3!//jf4cfls225.pdx.intel.com/apd_proj/ppg_lib/epg_masterlib/logical/mstr_discrete/ferrite/chips/chips.prt!FERRITE!FERRITE_SMLF-30,FB,693286-021!FERRITE!!!F2192!!BMC_VOLT_MONITOR!!
S!@baseboard_fab2_lib.baseboard_fab2(sch_1):page156_i291@mstr_discrete.fet_n_dual(chips)!FET_N_DUAL_SMLF-NTJD4001N,FET,A!Q4C1!//jf4cfls225.pdx.intel.com/apd_proj/ppg_lib/epg_masterlib/logical/mstr_discrete/fet_n_dual/chips/chips.prt!FET_N_DUAL!FET_N_DUAL_SMLF-NTJD4001N,FET,E40049-001!FET_N_DUAL_SMLF!1!!F2164!!BMC_MISC!!
S!@baseboard_fab2_lib.baseboard_fab2(sch_1):page156_i290@mstr_discrete.fet_n_dual(chips)!FET_N_DUAL_SMLF-NTJD4001N,FET,A!Q4C1!//jf4cfls225.pdx.intel.com/apd_proj/ppg_lib/epg_masterlib/logical/mstr_discrete/fet_n_dual/chips/chips.prt!FET_N_DUAL!FET_N_DUAL_SMLF-NTJD4001N,FET,E40049-001!FET_N_DUAL_SMLF!1!!F2163!!BMC_MISC!!
S!@baseboard_fab2_lib.baseboard_fab2(sch_1):page169_i162@mstr_discrete.fet_n_dual(chips)!FET_N_DUAL_SMLF-NTJD4001N,FET,A!Q9G1!//jf4cfls225.pdx.intel.com/apd_proj/ppg_lib/epg_masterlib/logical/mstr_discrete/fet_n_dual/chips/chips.prt!FET_N_DUAL!FET_N_DUAL_SMLF-NTJD4001N,FET,E40049-001!FET_N_DUAL_SMLF!1!!F2146!!BMC_VOLT_MONITOR!!
S!@baseboard_fab2_lib.baseboard_fab2(sch_1):page169_i157@mstr_discrete.fet_n_dual(chips)!FET_N_DUAL_SMLF-NTJD4001N,FET,A!Q9G1!//jf4cfls225.pdx.intel.com/apd_proj/ppg_lib/epg_masterlib/logical/mstr_discrete/fet_n_dual/chips/chips.prt!FET_N_DUAL!FET_N_DUAL_SMLF-NTJD4001N,FET,E40049-001!FET_N_DUAL_SMLF!1!!F2145!!BMC_VOLT_MONITOR!!
S!@baseboard_fab2_lib.baseboard_fab2(sch_1):page155_i188@mstr_discrete.fet_n_dual(chips)!FET_N_DUAL_SMLF-NTJD4001N,FET,A!Q1L2!//jf4cfls225.pdx.intel.com/apd_proj/ppg_lib/epg_masterlib/logical/mstr_discrete/fet_n_dual/chips/chips.prt!FET_N_DUAL!FET_N_DUAL_SMLF-NTJD4001N,FET,E40049-001!FET_N_DUAL_SMLF!1!!F2176!!BMC!!
S!@baseboard_fab2_lib.baseboard_fab2(sch_1):page155_i187@mstr_discrete.fet_n_dual(chips)!FET_N_DUAL_SMLF-NTJD4001N,FET,A!Q1L2!//jf4cfls225.pdx.intel.com/apd_proj/ppg_lib/epg_masterlib/logical/mstr_discrete/fet_n_dual/chips/chips.prt!FET_N_DUAL!FET_N_DUAL_SMLF-NTJD4001N,FET,E40049-001!FET_N_DUAL_SMLF!1!!F2175!!BMC!!
S!@baseboard_fab2_lib.baseboard_fab2(sch_1):page177_i80@mstr_discrete.fet_n_dual(chips)!FET_N_DUAL_SMLF-NTJD4001N,FET,A!Q9F1!//jf4cfls225.pdx.intel.com/apd_proj/ppg_lib/epg_masterlib/logical/mstr_discrete/fet_n_dual/chips/chips.prt!FET_N_DUAL!FET_N_DUAL_SMLF-NTJD4001N,FET,E40049-001!FET_N_DUAL_SMLF!1!!F2148!!BMC!!
S!@baseboard_fab2_lib.baseboard_fab2(sch_1):page177_i79@mstr_discrete.fet_n_dual(chips)!FET_N_DUAL_SMLF-NTJD4001N,FET,A!Q9F1!//jf4cfls225.pdx.intel.com/apd_proj/ppg_lib/epg_masterlib/logical/mstr_discrete/fet_n_dual/chips/chips.prt!FET_N_DUAL!FET_N_DUAL_SMLF-NTJD4001N,FET,E40049-001!FET_N_DUAL_SMLF!1!!F2147!!BMC!!
S!@baseboard_fab2_lib.baseboard_fab2(sch_1):page119_i175@mstr_discrete.fet_n_dual(chips)!FET_N_DUAL_SMLF-NTJD4001N,FET,A!Q9A2!//jf4cfls225.pdx.intel.com/apd_proj/ppg_lib/epg_masterlib/logical/mstr_discrete/fet_n_dual/chips/chips.prt!FET_N_DUAL!FET_N_DUAL_SMLF-NTJD4001N,FET,E40049-001!FET_N_DUAL_SMLF!1!!F2152!!SB!!
S!@baseboard_fab2_lib.baseboard_fab2(sch_1):page119_i180@mstr_discrete.fet_n_dual(chips)!FET_N_DUAL_SMLF-NTJD4001N,FET,A!Q9A2!//jf4cfls225.pdx.intel.com/apd_proj/ppg_lib/epg_masterlib/logical/mstr_discrete/fet_n_dual/chips/chips.prt!FET_N_DUAL!FET_N_DUAL_SMLF-NTJD4001N,FET,E40049-001!FET_N_DUAL_SMLF!1!!F2151!!SB!!
S!@baseboard_fab2_lib.baseboard_fab2(sch_1):page147_i135@mstr_discrete.fet_n_dual(chips)!FET_N_DUAL_SMLF-NTJD4001N,FET,A!Q9E1!//jf4cfls225.pdx.intel.com/apd_proj/ppg_lib/epg_masterlib/logical/mstr_discrete/fet_n_dual/chips/chips.prt!FET_N_DUAL!FET_N_DUAL_SMLF-NTJD4001N,FET,E40049-001!FET_N_DUAL_SMLF!1!!F2150!!BMC!!
S!@baseboard_fab2_lib.baseboard_fab2(sch_1):page147_i55@mstr_discrete.fet_n_dual(chips)!FET_N_DUAL_SMLF-NTJD4001N,FET,A!Q9E1!//jf4cfls225.pdx.intel.com/apd_proj/ppg_lib/epg_masterlib/logical/mstr_discrete/fet_n_dual/chips/chips.prt!FET_N_DUAL!FET_N_DUAL_SMLF-NTJD4001N,FET,E40049-001!FET_N_DUAL_SMLF!1!!F2149!!BMC!!
S!@baseboard_fab2_lib.baseboard_fab2(sch_1):page95_i111@mstr_discrete.fet_n_dual(chips)!FET_N_DUAL_SMLF-NTJD4001N,FET,A!Q7E5!//jf4cfls225.pdx.intel.com/apd_proj/ppg_lib/epg_masterlib/logical/mstr_discrete/fet_n_dual/chips/chips.prt!FET_N_DUAL!FET_N_DUAL_SMLF-NTJD4001N,FET,E40049-001!FET_N_DUAL_SMLF!1!!F2156!!HOT_EVENTS!!
S!@baseboard_fab2_lib.baseboard_fab2(sch_1):page95_i59@mstr_discrete.fet_n_dual(chips)!FET_N_DUAL_SMLF-NTJD4001N,FET,A!Q7E5!//jf4cfls225.pdx.intel.com/apd_proj/ppg_lib/epg_masterlib/logical/mstr_discrete/fet_n_dual/chips/chips.prt!FET_N_DUAL!FET_N_DUAL_SMLF-NTJD4001N,FET,E40049-001!FET_N_DUAL_SMLF!1!!F2155!!HOT_EVENTS!!
S!@baseboard_fab2_lib.baseboard_fab2(sch_1):page95_i112@mstr_discrete.fet_n_dual(chips)!FET_N_DUAL_SMLF-NTJD4001N,FET,A!Q7E6!//jf4cfls225.pdx.intel.com/apd_proj/ppg_lib/epg_masterlib/logical/mstr_discrete/fet_n_dual/chips/chips.prt!FET_N_DUAL!FET_N_DUAL_SMLF-NTJD4001N,FET,E40049-001!FET_N_DUAL_SMLF!1!!F2154!!HOT_EVENTS!!
S!@baseboard_fab2_lib.baseboard_fab2(sch_1):page95_i69@mstr_discrete.fet_n_dual(chips)!FET_N_DUAL_SMLF-NTJD4001N,FET,A!Q7E6!//jf4cfls225.pdx.intel.com/apd_proj/ppg_lib/epg_masterlib/logical/mstr_discrete/fet_n_dual/chips/chips.prt!FET_N_DUAL!FET_N_DUAL_SMLF-NTJD4001N,FET,E40049-001!FET_N_DUAL_SMLF!1!!F2153!!HOT_EVENTS!!
S!@baseboard_fab2_lib.baseboard_fab2(sch_1):page95_i32@mstr_discrete.fet_n_dual(chips)!FET_N_DUAL_SMLF-NTJD4001N,FET,A!Q4B2!//jf4cfls225.pdx.intel.com/apd_proj/ppg_lib/epg_masterlib/logical/mstr_discrete/fet_n_dual/chips/chips.prt!FET_N_DUAL!FET_N_DUAL_SMLF-NTJD4001N,FET,E40049-001!FET_N_DUAL_SMLF!1!!F2168!!PROC_SIDEBAND!!
S!@baseboard_fab2_lib.baseboard_fab2(sch_1):page95_i33@mstr_discrete.fet_n_dual(chips)!FET_N_DUAL_SMLF-NTJD4001N,FET,A!Q4B2!//jf4cfls225.pdx.intel.com/apd_proj/ppg_lib/epg_masterlib/logical/mstr_discrete/fet_n_dual/chips/chips.prt!FET_N_DUAL!FET_N_DUAL_SMLF-NTJD4001N,FET,E40049-001!FET_N_DUAL_SMLF!1!!F2167!!PROC_SIDEBAND!!
S!@baseboard_fab2_lib.baseboard_fab2(sch_1):page94_i98@mstr_discrete.fet_n_dual(chips)!FET_N_DUAL_SMLF-NTJD4001N,FET,A!Q4U1!//jf4cfls225.pdx.intel.com/apd_proj/ppg_lib/epg_masterlib/logical/mstr_discrete/fet_n_dual/chips/chips.prt!FET_N_DUAL!FET_N_DUAL_SMLF-NTJD4001N,FET,E40049-001!FET_N_DUAL_SMLF!1!!F2166!!PROC_SIDEBAND!!
S!@baseboard_fab2_lib.baseboard_fab2(sch_1):page94_i102@mstr_discrete.fet_n_dual(chips)!FET_N_DUAL_SMLF-NTJD4001N,FET,A!Q4U1!//jf4cfls225.pdx.intel.com/apd_proj/ppg_lib/epg_masterlib/logical/mstr_discrete/fet_n_dual/chips/chips.prt!FET_N_DUAL!FET_N_DUAL_SMLF-NTJD4001N,FET,E40049-001!FET_N_DUAL_SMLF!1!!F2165!!PROC_SIDEBAND!!
S!@baseboard_fab2_lib.baseboard_fab2(sch_1):page95_i28@mstr_discrete.fet_n_dual(chips)!FET_N_DUAL_SMLF-NTJD4001N,FET,A!Q2U1!//jf4cfls225.pdx.intel.com/apd_proj/ppg_lib/epg_masterlib/logical/mstr_discrete/fet_n_dual/chips/chips.prt!FET_N_DUAL!FET_N_DUAL_SMLF-NTJD4001N,FET,E40049-001!FET_N_DUAL_SMLF!1!!F2174!!PROC_SIDEBAND!!
S!@baseboard_fab2_lib.baseboard_fab2(sch_1):page95_i113@mstr_discrete.fet_n_dual(chips)!FET_N_DUAL_SMLF-NTJD4001N,FET,A!Q2U1!//jf4cfls225.pdx.intel.com/apd_proj/ppg_lib/epg_masterlib/logical/mstr_discrete/fet_n_dual/chips/chips.prt!FET_N_DUAL!FET_N_DUAL_SMLF-NTJD4001N,FET,E40049-001!FET_N_DUAL_SMLF!1!!F2173!!PROC_SIDEBAND!!
S!@baseboard_fab2_lib.baseboard_fab2(sch_1):page94_i49@mstr_discrete.fet_n_dual(chips)!FET_N_DUAL_SMLF-NTJD4001N,FET,A!Q3U1!//jf4cfls225.pdx.intel.com/apd_proj/ppg_lib/epg_masterlib/logical/mstr_discrete/fet_n_dual/chips/chips.prt!FET_N_DUAL!FET_N_DUAL_SMLF-NTJD4001N,FET,E40049-001!FET_N_DUAL_SMLF!1!!F2172!!PROC_SIDEBAND!!
S!@baseboard_fab2_lib.baseboard_fab2(sch_1):page94_i89@mstr_discrete.fet_n_dual(chips)!FET_N_DUAL_SMLF-NTJD4001N,FET,A!Q3U1!//jf4cfls225.pdx.intel.com/apd_proj/ppg_lib/epg_masterlib/logical/mstr_discrete/fet_n_dual/chips/chips.prt!FET_N_DUAL!FET_N_DUAL_SMLF-NTJD4001N,FET,E40049-001!FET_N_DUAL_SMLF!1!!F2171!!PROC_SIDEBAND!!
S!@baseboard_fab2_lib.baseboard_fab2(sch_1):page94_i60@mstr_discrete.fet_n_dual(chips)!FET_N_DUAL_SMLF-NTJD4001N,FET,A!Q7E1!//jf4cfls225.pdx.intel.com/apd_proj/ppg_lib/epg_masterlib/logical/mstr_discrete/fet_n_dual/chips/chips.prt!FET_N_DUAL!FET_N_DUAL_SMLF-NTJD4001N,FET,E40049-001!FET_N_DUAL_SMLF!1!!F2162!!PROC_SIDEBAND!!
S!@baseboard_fab2_lib.baseboard_fab2(sch_1):page94_i64@mstr_discrete.fet_n_dual(chips)!FET_N_DUAL_SMLF-NTJD4001N,FET,A!Q7E1!//jf4cfls225.pdx.intel.com/apd_proj/ppg_lib/epg_masterlib/logical/mstr_discrete/fet_n_dual/chips/chips.prt!FET_N_DUAL!FET_N_DUAL_SMLF-NTJD4001N,FET,E40049-001!FET_N_DUAL_SMLF!1!!F2161!!PROC_SIDEBAND!!
S!@baseboard_fab2_lib.baseboard_fab2(sch_1):page94_i69@mstr_discrete.fet_n_dual(chips)!FET_N_DUAL_SMLF-NTJD4001N,FET,A!Q7E2!//jf4cfls225.pdx.intel.com/apd_proj/ppg_lib/epg_masterlib/logical/mstr_discrete/fet_n_dual/chips/chips.prt!FET_N_DUAL!FET_N_DUAL_SMLF-NTJD4001N,FET,E40049-001!FET_N_DUAL_SMLF!1!!F2160!!PROC_SIDEBAND!!
S!@baseboard_fab2_lib.baseboard_fab2(sch_1):page94_i75@mstr_discrete.fet_n_dual(chips)!FET_N_DUAL_SMLF-NTJD4001N,FET,A!Q7E2!//jf4cfls225.pdx.intel.com/apd_proj/ppg_lib/epg_masterlib/logical/mstr_discrete/fet_n_dual/chips/chips.prt!FET_N_DUAL!FET_N_DUAL_SMLF-NTJD4001N,FET,E40049-001!FET_N_DUAL_SMLF!1!!F2159!!PROC_SIDEBAND!!
S!@baseboard_fab2_lib.baseboard_fab2(sch_1):page94_i84@mstr_discrete.fet_n_dual(chips)!FET_N_DUAL_SMLF-NTJD4001N,FET,A!Q4B1!//jf4cfls225.pdx.intel.com/apd_proj/ppg_lib/epg_masterlib/logical/mstr_discrete/fet_n_dual/chips/chips.prt!FET_N_DUAL!FET_N_DUAL_SMLF-NTJD4001N,FET,E40049-001!FET_N_DUAL_SMLF!1!!F2170!!PROC_SIDEBAND!!
S!@baseboard_fab2_lib.baseboard_fab2(sch_1):page94_i77@mstr_discrete.fet_n_dual(chips)!FET_N_DUAL_SMLF-NTJD4001N,FET,A!Q4B1!//jf4cfls225.pdx.intel.com/apd_proj/ppg_lib/epg_masterlib/logical/mstr_discrete/fet_n_dual/chips/chips.prt!FET_N_DUAL!FET_N_DUAL_SMLF-NTJD4001N,FET,E40049-001!FET_N_DUAL_SMLF!1!!F2169!!PROC_SIDEBAND!!
S!@baseboard_fab2_lib.baseboard_fab2(sch_1):page95_i52@mstr_discrete.fet_n_dual(chips)!FET_N_DUAL_SMLF-NTJD4001N,FET,A!Q7E3!//jf4cfls225.pdx.intel.com/apd_proj/ppg_lib/epg_masterlib/logical/mstr_discrete/fet_n_dual/chips/chips.prt!FET_N_DUAL!FET_N_DUAL_SMLF-NTJD4001N,FET,E40049-001!FET_N_DUAL_SMLF!1!!F2158!!PROC_SIDEBAND!!
S!@baseboard_fab2_lib.baseboard_fab2(sch_1):page95_i51@mstr_discrete.fet_n_dual(chips)!FET_N_DUAL_SMLF-NTJD4001N,FET,A!Q7E3!//jf4cfls225.pdx.intel.com/apd_proj/ppg_lib/epg_masterlib/logical/mstr_discrete/fet_n_dual/chips/chips.prt!FET_N_DUAL!FET_N_DUAL_SMLF-NTJD4001N,FET,E40049-001!FET_N_DUAL_SMLF!1!!F2157!!PROC_SIDEBAND!!
S!@baseboard_fab2_lib.baseboard_fab2(sch_1):page126_i13@mstr_discrete.fet_n(chips)!FET_N_SOT23LF-2N7002,FET,C7925A!Q8E2!//jf4cfls225.pdx.intel.com/apd_proj/ppg_lib/epg_masterlib/logical/mstr_discrete/fet_n/chips/chips.prt!FET_N!FET_N_SOT23LF-2N7002,FET,C79254-001!FET_N!!!F2135!!!!
S!@baseboard_fab2_lib.baseboard_fab2(sch_1):page200_i203@mstr_discrete.fet_n(chips)!FET_N_SOT23LF-2N7002,FET,C7925A!Q1D2!//jf4cfls225.pdx.intel.com/apd_proj/ppg_lib/epg_masterlib/logical/mstr_discrete/fet_n/chips/chips.prt!FET_N!FET_N_SOT23LF-2N7002,FET,C79254-001!FET_N!!!F2138!!HOT_SWAP!!
S!@baseboard_fab2_lib.baseboard_fab2(sch_1):page136_i134@mstr_discrete.fet_n(chips)!FET_N_SOT23LF-2N7002,FET,C7925A!Q8E1!//jf4cfls225.pdx.intel.com/apd_proj/ppg_lib/epg_masterlib/logical/mstr_discrete/fet_n/chips/chips.prt!FET_N!FET_N_SOT23LF-2N7002,FET,C79254-001!FET_N!!!F2134!!SB!!
S!@baseboard_fab2_lib.baseboard_fab2(sch_1):page170_i58@mstr_discrete.fet_n(chips)!FET_N_SOT23LF-2N7002,FET,C7925A!Q2P1!//jf4cfls225.pdx.intel.com/apd_proj/ppg_lib/epg_masterlib/logical/mstr_discrete/fet_n/chips/chips.prt!FET_N!FET_N_SOT23LF-2N7002,FET,C79254-001!FET_N!!!F2137!!PROC_SIDEBAND!!
S!@baseboard_fab2_lib.baseboard_fab2(sch_1):page170_i67@mstr_discrete.fet_n(chips)!FET_N_SOT23LF-2N7002,FET,C7925A!Q8F2!//jf4cfls225.pdx.intel.com/apd_proj/ppg_lib/epg_masterlib/logical/mstr_discrete/fet_n/chips/chips.prt!FET_N!FET_N_SOT23LF-2N7002,FET,C79254-001!FET_N!!!F2132!!PROC_SIDEBAND!!
S!@baseboard_fab2_lib.baseboard_fab2(sch_1):page157_i340@mstr_discrete.fet_n(chips)!FET_N_SOT23LF-2N7002,FET,C7925A!Q2T2!//jf4cfls225.pdx.intel.com/apd_proj/ppg_lib/epg_masterlib/logical/mstr_discrete/fet_n/chips/chips.prt!FET_N!FET_N_SOT23LF-2N7002,FET,C79254-001!FET_N!!!F2136!!PROC_SIDEBAND!!
S!@baseboard_fab2_lib.baseboard_fab2(sch_1):page175_i49@mstr_discrete.fet_n(chips)!FET_N_SOT23LF-2N7002,FET,C7925A!Q9A3!//jf4cfls225.pdx.intel.com/apd_proj/ppg_lib/epg_masterlib/logical/mstr_discrete/fet_n/chips/chips.prt!FET_N!FET_N_SOT23LF-2N7002,FET,C79254-001!FET_N!!!F2131!!MIO_CHASSIS!!
S!@baseboard_fab2_lib.baseboard_fab2(sch_1):page154_i126@mstr_discrete.fet_n(chips)!FET_N_SOT23LF-2N7002,FET,C7925A!Q8F1!//jf4cfls225.pdx.intel.com/apd_proj/ppg_lib/epg_masterlib/logical/mstr_discrete/fet_n/chips/chips.prt!FET_N!FET_N_SOT23LF-2N7002,FET,C79254-001!FET_N!!!F2133!!SB_BMC_SPI_MUX!!
S!@baseboard_fab2_lib.baseboard_fab2(sch_1):page152_i1@mstr_digital.gtl2014(chips)!GTL2014_SM-IC,D66151-001!U9G1!//jf4cfls225.pdx.intel.com/apd_proj/ppg_lib/epg_masterlib/logical/mstr_digital/gtl2014/chips/chips.prt!GTL2014!GTL2014_SM-IC,D66151-001!GTL2014_SM!!!F2120!!PROC_SIDEBAND!!
S!@baseboard_fab2_lib.baseboard_fab2(sch_1):page93_i30@mstr_digital.gtl2014(chips)!GTL2014_SM-IC,D66151-001!U2T4!//jf4cfls225.pdx.intel.com/apd_proj/ppg_lib/epg_masterlib/logical/mstr_digital/gtl2014/chips/chips.prt!GTL2014!GTL2014_SM-IC,D66151-001!GTL2014_SM!!!F2125!!PROC_SIDEBAND!!
S!@baseboard_fab2_lib.baseboard_fab2(sch_1):page96_i42@mstr_digital.gtl2014(chips)!GTL2014_SM-IC,D66151-001!U3P1!//jf4cfls225.pdx.intel.com/apd_proj/ppg_lib/epg_masterlib/logical/mstr_digital/gtl2014/chips/chips.prt!GTL2014!GTL2014_SM-IC,D66151-001!GTL2014_SM!!!F2124!!PROC_RSTS_PGOODS!!
S!@baseboard_fab2_lib.baseboard_fab2(sch_1):page96_i46@mstr_digital.gtl2014(chips)!GTL2014_SM-IC,D66151-001!U4C2!//jf4cfls225.pdx.intel.com/apd_proj/ppg_lib/epg_masterlib/logical/mstr_digital/gtl2014/chips/chips.prt!GTL2014!GTL2014_SM-IC,D66151-001!GTL2014_SM!!!F2122!!PROC_RSTS_PGOODS!!
S!@baseboard_fab2_lib.baseboard_fab2(sch_1):page92_i1@mstr_digital.gtl2014(chips)!GTL2014_SM-IC,D66151-001!U3P2!//jf4cfls225.pdx.intel.com/apd_proj/ppg_lib/epg_masterlib/logical/mstr_digital/gtl2014/chips/chips.prt!GTL2014!GTL2014_SM-IC,D66151-001!GTL2014_SM!!!F2123!!PROC_SIDEBAND!!
S!@baseboard_fab2_lib.baseboard_fab2(sch_1):page92_i32@mstr_digital.gtl2014(chips)!GTL2014_SM-IC,D66151-001!U7D2!//jf4cfls225.pdx.intel.com/apd_proj/ppg_lib/epg_masterlib/logical/mstr_digital/gtl2014/chips/chips.prt!GTL2014!GTL2014_SM-IC,D66151-001!GTL2014_SM!!!F2121!!PROC_SIDEBAND!!
S!@baseboard_fab2_lib.baseboard_fab2(sch_1):page177_i31@mstr_discrete.led(chips)!LED_A1LF-GREEN,IC,C97278-010!DS9A6!//jf4cfls225.pdx.intel.com/apd_proj/ppg_lib/epg_masterlib/logical/mstr_discrete/led/chips/chips.prt!LED!LED_A1LF-GREEN,IC,C97278-010!LED_A1LF!!!F2033!!MIO_CHASSIS!!
S!@baseboard_fab2_lib.baseboard_fab2(sch_1):page119_i179@mstr_discrete.led(chips)!LED_A1LF-GREEN,IC,C97278-010!DS9A5!//jf4cfls225.pdx.intel.com/apd_proj/ppg_lib/epg_masterlib/logical/mstr_discrete/led/chips/chips.prt!LED!LED_A1LF-GREEN,IC,C97278-010!LED_A1LF!!!F2034!!SB!!
S!@baseboard_fab2_lib.baseboard_fab2(sch_1):page147_i56@mstr_discrete.led(chips)!LED_A1LF-GREEN,IC,C97278-010!DS9E1!//jf4cfls225.pdx.intel.com/apd_proj/ppg_lib/epg_masterlib/logical/mstr_discrete/led/chips/chips.prt!LED!LED_A1LF-GREEN,IC,C97278-010!LED_A1LF!!!F2032!!BMC!!
S!@baseboard_fab2_lib.baseboard_fab2(sch_1):page200_i54@mstr_discrete.mosfetn_1d3s(chips)!MOSFETN_1D3S_SOT5-IC,G68777-001!EU1E3!//jf4cfls225.pdx.intel.com/apd_proj/ppg_lib/epg_masterlib/logical/mstr_discrete/mosfetn_1d3s/chips/chips.prt!MOSFETN_1D3S!MOSFETN_1D3S_SOT5-IC,G68777-001!MOSFETN_1D3S_SOT5!!!F2019!!HOT_SWAP!!
S!@baseboard_fab2_lib.baseboard_fab2(sch_1):page200_i57@mstr_discrete.mosfetn_1d3s(chips)!MOSFETN_1D3S_SOT5-IC,G68777-001!EU9R1!//jf4cfls225.pdx.intel.com/apd_proj/ppg_lib/epg_masterlib/logical/mstr_discrete/mosfetn_1d3s/chips/chips.prt!MOSFETN_1D3S!MOSFETN_1D3S_SOT5-IC,G68777-001!MOSFETN_1D3S_SOT5!!!F2018!!HOT_SWAP!!
S!@baseboard_fab2_lib.baseboard_fab2(sch_1):page200_i59@mstr_discrete.mosfetn_1d3s(chips)!MOSFETN_1D3S_SOT5-IC,G68777-001!EU1E1!//jf4cfls225.pdx.intel.com/apd_proj/ppg_lib/epg_masterlib/logical/mstr_discrete/mosfetn_1d3s/chips/chips.prt!MOSFETN_1D3S!MOSFETN_1D3S_SOT5-IC,G68777-001!MOSFETN_1D3S_SOT5!!!F2020!!HOT_SWAP!!
S!@baseboard_fab2_lib.baseboard_fab2(sch_1):page157_i352@mstr_discrete.res(chips)!RES_0402-200.0,1%,1/16W,CHIP,GA!R2R9!//jf4cfls225.pdx.intel.com/apd_proj/ppg_lib/epg_masterlib/logical/mstr_discrete/res/chips/chips.prt!RES!RES_0402-200.0,1%,1/16W,CHIP,G21796-004!RES!!!F897!!MIO_CHASSIS!!
S!@baseboard_fab2_lib.baseboard_fab2(sch_1):page93_i63@mstr_discrete.res(chips)!RES_0402-200.0,1%,1/16W,CHIP,GA!R2T19!//jf4cfls225.pdx.intel.com/apd_proj/ppg_lib/epg_masterlib/logical/mstr_discrete/res/chips/chips.prt!RES!RES_0402-200.0,1%,1/16W,CHIP,G21796-004!RES!!!F895!!PROC_SIDEBAND!!
S!@baseboard_fab2_lib.baseboard_fab2(sch_1):page93_i87@mstr_discrete.res(chips)!RES_0402-200.0,1%,1/16W,CHIP,GA!R2T26!//jf4cfls225.pdx.intel.com/apd_proj/ppg_lib/epg_masterlib/logical/mstr_discrete/res/chips/chips.prt!RES!RES_0402-200.0,1%,1/16W,CHIP,G21796-004!RES!!!F894!!PROC_SIDEBAND!!
S!@baseboard_fab2_lib.baseboard_fab2(sch_1):page175_i4@mstr_discrete.res(chips)!RES_0402-200.0,1%,1/16W,CHIP,GA!R1L31!//jf4cfls225.pdx.intel.com/apd_proj/ppg_lib/epg_masterlib/logical/mstr_discrete/res/chips/chips.prt!RES!RES_0402-200.0,1%,1/16W,CHIP,G21796-004!RES!!!F899!!MIO_CHASSIS!!
S!@baseboard_fab2_lib.baseboard_fab2(sch_1):page175_i22@mstr_discrete.res(chips)!RES_0402-200.0,1%,1/16W,CHIP,GA!R1L22!//jf4cfls225.pdx.intel.com/apd_proj/ppg_lib/epg_masterlib/logical/mstr_discrete/res/chips/chips.prt!RES!RES_0402-200.0,1%,1/16W,CHIP,G21796-004!RES!!!F900!!MIO_CHASSIS!!
S!@baseboard_fab2_lib.baseboard_fab2(sch_1):page154_i101@mstr_discrete.res(chips)!RES_0402-200.0,1%,1/16W,CHIP,GA!R2T13!//jf4cfls225.pdx.intel.com/apd_proj/ppg_lib/epg_masterlib/logical/mstr_discrete/res/chips/chips.prt!RES!RES_0402-200.0,1%,1/16W,CHIP,G21796-004!RES!!!F896!!SB_BMC_SPI_MUX!!
S!@baseboard_fab2_lib.baseboard_fab2(sch_1):page187_i153@mstr_discrete.res(chips)!RES_0402-200.0,1%,1/16W,CHIP,GA!R9E12!//jf4cfls225.pdx.intel.com/apd_proj/ppg_lib/epg_masterlib/logical/mstr_discrete/res/chips/chips.prt!RES!RES_0402-200.0,1%,1/16W,CHIP,G21796-004!RES!!!F890!!IO_SLOT!!
S!@baseboard_fab2_lib.baseboard_fab2(sch_1):page187_i150@mstr_discrete.res(chips)!RES_0402-200.0,1%,1/16W,CHIP,GA!R9E11!//jf4cfls225.pdx.intel.com/apd_proj/ppg_lib/epg_masterlib/logical/mstr_discrete/res/chips/chips.prt!RES!RES_0402-200.0,1%,1/16W,CHIP,G21796-004!RES!!!F891!!IO_SLOT!!
S!@baseboard_fab2_lib.baseboard_fab2(sch_1):page187_i145@mstr_discrete.res(chips)!RES_0402-200.0,1%,1/16W,CHIP,GA!R9E10!//jf4cfls225.pdx.intel.com/apd_proj/ppg_lib/epg_masterlib/logical/mstr_discrete/res/chips/chips.prt!RES!RES_0402-200.0,1%,1/16W,CHIP,G21796-004!RES!!!F892!!IO_SLOT!!
S!@baseboard_fab2_lib.baseboard_fab2(sch_1):page92_i94@mstr_discrete.res(chips)!RES_0402-200.0,1%,1/16W,CHIP,GA!R2T37!//jf4cfls225.pdx.intel.com/apd_proj/ppg_lib/epg_masterlib/logical/mstr_discrete/res/chips/chips.prt!RES!RES_0402-200.0,1%,1/16W,CHIP,G21796-004!RES!!!F893!!PROC_SIDEBAND!!
S!@baseboard_fab2_lib.baseboard_fab2(sch_1):page186_i220@mstr_discrete.res(chips)!RES_0402-200.0,1%,1/16W,CHIP,GA!R1M14!//jf4cfls225.pdx.intel.com/apd_proj/ppg_lib/epg_masterlib/logical/mstr_discrete/res/chips/chips.prt!RES!RES_0402-200.0,1%,1/16W,CHIP,G21796-004!RES!!!F898!!IO_SLOT!!
S!@baseboard_fab2_lib.baseboard_fab2(sch_1):page209_i39@mstr_discrete.res(chips)!RES_2010-0.001,1%,1W,CHIP,E309A!R1B20!//jf4cfls225.pdx.intel.com/apd_proj/ppg_lib/epg_masterlib/logical/mstr_discrete/res/chips/chips.prt!RES!RES_2010-0.001,1%,1W,CHIP,E30969-002!RES!!!F250!!PVCCIN_CPU1_FILTER_VR!!
S!@baseboard_fab2_lib.baseboard_fab2(sch_1):page204_i45@mstr_discrete.res(chips)!RES_2010-0.001,1%,1W,CHIP,E309A!R4C6!//jf4cfls225.pdx.intel.com/apd_proj/ppg_lib/epg_masterlib/logical/mstr_discrete/res/chips/chips.prt!RES!RES_2010-0.001,1%,1W,CHIP,E30969-002!RES!!!F249!!PVCCIN_CPU0_FILTER_VR!!
S!@baseboard_fab2_lib.baseboard_fab2(sch_1):page200_i50@mstr_discrete.res_pwr(chips)!RES_PWR_6PAD-0.001,1%,3W,CHIP,A!R1D49!//jf4cfls225.pdx.intel.com/apd_proj/ppg_lib/epg_masterlib/logical/mstr_discrete/res_pwr/chips/chips.prt!RES_PWR!RES_PWR_6PAD-0.001,1%,3W,CHIP,E74391-005!RES_PWR_6PAD!!!F248!!HOT_SWAP!!
S!@baseboard_fab2_lib.baseboard_fab2(sch_1):page200_i49@mstr_discrete.res_pwr(chips)!RES_PWR_6PAD-0.001,1%,3W,CHIP,A!R9R1!//jf4cfls225.pdx.intel.com/apd_proj/ppg_lib/epg_masterlib/logical/mstr_discrete/res_pwr/chips/chips.prt!RES_PWR!RES_PWR_6PAD-0.001,1%,3W,CHIP,E74391-005!RES_PWR_6PAD!!!F247!!HOT_SWAP!!
